G04 ================== begin FILE IDENTIFICATION RECORD ==================*
G04 Layout Name:  15126-1b.brd*
G04 Film Name:    L4GND*
G04 File Format:  Gerber RS274X*
G04 File Origin:  Cadence Allegro 16.6-2015-S079*
G04 Origin Date:  Fri Feb 10 17:22:16 2017*
G04 *
G04 Layer:  VIA CLASS/L4GND*
G04 Layer:  PIN/L4GND*
G04 Layer:  ETCH/L4GND*
G04 Layer:  DRAWING FORMAT/LAYER_PCB_STORY*
G04 Layer:  DRAWING FORMAT/LAYER_L4GND*
G04 *
G04 Offset:    (0.00 0.00)*
G04 Mirror:    No*
G04 Mode:      Positive*
G04 Rotation:  0*
G04 FullContactRelief:  No*
G04 UndefLineWidth:     6.00*
G04 ================== end FILE IDENTIFICATION RECORD ====================*
%FSLAX35Y35*MOIN*%
%IR0*IPPOS*OFA0.00000B0.00000*MIA0B0*SFA1.00000B1.00000*%
%ADD11C,.02*%
%ADD19C,.04*%
%ADD18C,.031*%
%ADD10C,.022*%
%ADD12C,.034*%
%ADD14C,.044*%
%ADD17C,.018*%
%ADD16C,.028*%
%ADD13C,.046*%
%ADD15C,.057*%
%ADD20O,.032X.036*%
%ADD21O,.099X.048*%
%ADD22C,.01*%
%ADD23C,.006*%
%ADD67R,.05948X.06858*%
%ADD70O,.07202X.12102*%
%ADD46C,.03004*%
%ADD60C,.04004*%
%ADD48C,.03204*%
%ADD69C,.06104*%
%ADD43C,.07004*%
%ADD38C,.05204*%
%ADD62C,.08004*%
%ADD55C,.02604*%
%ADD53C,.06204*%
%ADD40C,.04404*%
%ADD57C,.07204*%
%ADD51C,.02704*%
%ADD66C,.05504*%
%ADD58C,.06404*%
%ADD26C,.02804*%
%ADD65C,.06504*%
%ADD59C,.04704*%
%ADD45C,.07404*%
%ADD25C,.05604*%
%ADD68C,.05506*%
%ADD63C,.05704*%
%ADD61C,.09304*%
%ADD56C,.06604*%
%ADD52C,.07504*%
%ADD42C,.08404*%
%ADD36C,.04804*%
%ADD29C,.0709*%
%ADD44C,.07604*%
%ADD64C,.06804*%
%ADD47C,.05904*%
%ADD39C,.08604*%
%ADD54C,.07804*%
%ADD35C,.07518*%
%ADD32C,.06943*%
%ADD34C,.11211*%
%ADD49C,.12104*%
%ADD37C,.11204*%
%ADD41C,.15004*%
%ADD28O,.15402X.21902*%
%ADD24C,.11404*%
%ADD33C,.11209*%
%ADD27O,.15404X.21904*%
%ADD30C,.15504*%
%ADD31C,.15506*%
%ADD50C,.17804*%
G75*
%LPD*%
G75*
G36*
G01X1973300Y-60000D02*
X-19810D01*
Y-34500D01*
X1973300D01*
Y-60000D01*
G37*
G36*
G01X1683500Y265400D02*
X1870726D01*
G02X1871080Y264815I-1J-400D01*
G03X1873566I1243J-648D01*
G02X1873920Y265400I355J185D01*
G01X1883450D01*
G02X1885858Y262553I-480J-2848D01*
G01Y248342D01*
X1889230Y244970D01*
X1892253D01*
G03X1892345Y244968I187J6484D01*
G01X1912374D01*
G02X1912723Y244374I-1J-400D01*
G03X1915351I1314J-728D01*
G02X1915700Y244968I350J194D01*
G01X1946598D01*
Y236102D01*
X1954390D01*
G03X1959543Y236615I2500J1024D01*
G02X1960225Y236815I393J-76D01*
G03X1959666Y239000I1665J1590D01*
G02X1958972Y238849I-386J104D01*
G03X1957693Y239706I-2081J-1723D01*
G01X1957552Y239750D01*
Y244968D01*
X1965840D01*
Y244646D01*
G03Y240235I1743J-2205D01*
G01Y239440D01*
X1974348D01*
G02X1974544Y238320I-7124J-1824D01*
G01Y210008D01*
X1965840D01*
Y209213D01*
G03Y204801I1743J-2206D01*
G01Y204006D01*
X1974544D01*
Y148909D01*
G02X1973963Y148553I-400J1D01*
G03Y146053I-635J-1250D01*
G02X1974544Y145697I181J-357D01*
G01Y144515D01*
G02X1973891Y144206I-400J1D01*
G03Y142034I-887J-1086D01*
G02X1974544Y141725I253J-310D01*
G01Y66551D01*
X1974536Y66544D01*
Y58986D01*
X1972570Y57020D01*
X1958136D01*
Y61270D01*
X1947376D01*
Y57020D01*
X1901296D01*
X1892646Y48370D01*
Y-4170D01*
X1902116Y-13640D01*
X1947376D01*
Y-17962D01*
X1958136D01*
Y-13640D01*
X1972620D01*
X1974490Y-15510D01*
Y-19790D01*
X1972470Y-21810D01*
X1917110D01*
X1917100Y-21800D01*
X1894755D01*
G02X1894384Y-21252I1J400D01*
G03X1891778I-1303J517D01*
G02X1891407Y-21800I-372J-148D01*
G01X1883100D01*
X1883050Y-21750D01*
X1882472D01*
X1882400Y-21822D01*
X1105041D01*
G02X1105013Y-21821I0J400D01*
G01X1101687D01*
G02X1101659Y-21822I-28J399D01*
G01X1100391D01*
G02X1100363Y-21821I0J400D01*
G01X1097037D01*
G02X1097009Y-21822I-28J399D01*
G01X1096684D01*
X658442Y-21810D01*
G02X658079Y-21242I0J400D01*
G03X655535I-1272J590D01*
G02X655172Y-21810I-363J-168D01*
G01X71249Y-21794D01*
X69245Y-21795D01*
G02X68872Y-21250I0J400D01*
G03X67065Y-19435I-1308J505D01*
G02X66532Y-19149I-143J374D01*
G03X64216Y-18423I-1368J-307D01*
G02X63622Y-18362I-270J295D01*
G03X63434Y-20217I-1136J-822D01*
G02X64028Y-20278I270J-295D01*
G03X65663Y-20766I1136J822D01*
G02X66196Y-21052I143J-374D01*
G03X66257Y-21251I1367J310D01*
G02X65884Y-21796I-373J-145D01*
G01X52241Y-21800D01*
G02X51874Y-21242I0J400D01*
G03X49299Y-21243I-1288J555D01*
G02X48932Y-21801I-367J-158D01*
G01X39777Y-21804D01*
G02X39433Y-21200I0J400D01*
G03X37022Y-21201I-1206J715D01*
G02X36678Y-21805I-344J-204D01*
G01X-14469Y-21822D01*
G02X-21822Y-14469I0J7353D01*
G01Y617225D01*
G02X-16129Y624388I7353J-1D01*
G01X-15873Y624450D01*
X385242D01*
G02X385626Y623937I0J-400D01*
G03X388314I1344J-398D01*
G02X388698Y624450I384J113D01*
G01X451603D01*
G02X451968Y623888I-1J-400D01*
G03X454532I1282J-568D01*
G02X454897Y624450I366J162D01*
G01X455263D01*
G02X455628Y623888I-1J-400D01*
G03X458192I1282J-568D01*
G02X458557Y624450I366J162D01*
G01X726284D01*
G02X726665Y623928I0J-400D01*
G03X729335I1335J-428D01*
G02X729716Y624450I381J122D01*
G01X1044784D01*
G02X1045165Y623928I0J-400D01*
G03X1047835I1335J-428D01*
G02X1048216Y624450I381J122D01*
G01X1545856D01*
X1545859Y624453D01*
X1550490D01*
G02X1550869Y623926I0J-400D01*
G03X1553527I1329J-447D01*
G02X1553906Y624453I379J127D01*
G01X1555843D01*
G02X1556227Y623943I-1J-400D01*
G03X1558813Y622900I1348J-384D01*
G02X1559517Y622904I353J-188D01*
G03X1562068Y624044I1230J672D01*
G02X1562445Y624578I377J134D01*
G01X1564904D01*
G02X1565262Y624001I-1J-400D01*
G03X1567673Y622584I1258J-620D01*
G02X1568333Y622580I329J-228D01*
G03X1570746Y623998I1162J784D01*
G02X1571103Y624578I357J180D01*
G01X1967224D01*
G02X1974413Y618773I0J-7354D01*
G01Y598690D01*
G02X1973788Y598359I-400J0D01*
G03Y596041I-788J-1159D01*
G02X1974413Y595710I225J-331D01*
G01Y577634D01*
G02X1973722Y577360I-400J0D01*
G03Y575440I-1022J-960D01*
G02X1974413Y575166I291J-274D01*
G01Y566532D01*
G02X1973744Y566237I-400J1D01*
G03Y564163I-944J-1037D01*
G02X1974413Y563868I269J-296D01*
G01Y551184D01*
G02X1973722Y550910I-400J0D01*
G03Y548990I-1022J-960D01*
G02X1974413Y548716I291J-274D01*
G01Y538132D01*
G02X1973744Y537837I-400J1D01*
G03Y535763I-944J-1037D01*
G02X1974413Y535468I269J-296D01*
G01Y440197D01*
G02X1968727Y434550I-7187J1550D01*
G01X1922500D01*
Y435297D01*
X1922098Y435699D01*
G03X1919535Y436380I-1398J-99D01*
G03X1919533Y436377I1165J-779D01*
G02X1918867I-333J222D01*
G03X1916533I-1167J-777D01*
G02X1915867I-333J222D01*
G03X1915864Y436382I-1204J-719D01*
G03X1913300Y435673I-1164J-782D01*
G01X1913296Y435596D01*
X1912500Y434800D01*
Y434450D01*
X1683400D01*
X1680000Y431050D01*
Y427850D01*
X1680050Y427800D01*
Y306416D01*
G02X1679528Y306035I-400J0D01*
G03X1678129Y303689I-428J-1335D01*
G02Y303111I-277J-289D01*
G03Y301089I971J-1011D01*
G02Y300511I-277J-289D01*
G03X1678090Y298527I971J-1011D01*
G02Y297973I-288J-277D01*
G03Y296027I1010J-973D01*
G02Y295473I-288J-277D01*
G03Y293527I1010J-973D01*
G02Y292973I-288J-277D01*
G03Y291027I1010J-973D01*
G02Y290473I-288J-277D01*
G03X1678271Y288369I1010J-973D01*
G02Y287724I-236J-323D01*
G03X1678090Y285620I829J-1131D01*
G02Y285066I-288J-277D01*
G03Y283120I1010J-973D01*
G02Y282566I-288J-277D01*
G03X1678158Y280555I1010J-972D01*
G02Y279962I-269J-297D01*
G03X1678099Y277942I942J-1038D01*
G02Y277382I-285J-280D01*
G03X1678090Y275427I1001J-982D01*
G02Y274873I-288J-277D01*
G03X1678129Y272889I1010J-973D01*
G02Y272311I-277J-289D01*
G03X1679528Y269965I971J-1011D01*
G02X1680050Y269584I122J-381D01*
G01Y268850D01*
X1683500Y265400D01*
G37*
G36*
G01X-20621Y661811D02*
G02X-19685Y662747I936J0D01*
G01X1972600D01*
Y637600D01*
X-20412D01*
G02X-20621Y638189I726J589D01*
G01Y661811D01*
G37*
%LPC*%
G75*
G36*
G01X1603820Y433694D02*
G02X1602241Y433668I-770J-1171D01*
G03X1602230Y434329I-231J327D01*
G02X1603809Y434355I770J1171D01*
G03X1603820Y433694I231J-327D01*
G37*
G36*
G01X1685017Y192029D02*
G02X1685249Y190205I1166J-778D01*
G03X1684650Y190129I-266J-298D01*
G02X1684418Y191953I-1166J778D01*
G03X1685017Y192029I266J298D01*
G37*
G36*
G01X1675832Y195852D02*
G03X1675197Y195838I-312J-250D01*
G02X1675158Y197545I-1131J828D01*
G03X1675793Y197559I312J250D01*
G02X1675832Y195852I1131J-828D01*
G37*
G36*
G01X1606022Y557644D02*
Y561645D01*
G02X1607233Y563125I1511J-1D01*
G03X1607452Y563785I-79J393D01*
G02X1616289Y570393I3831J4090D01*
G02X1611415Y562272I-5004J-2520D01*
G02X1609474Y562570I-133J5602D01*
G03X1608983Y562072I-108J-385D01*
G02X1609044Y561654I-1450J-425D01*
G01Y557559D01*
X1609035Y557475D01*
G02X1606022Y557644I-1502J169D01*
G37*
G36*
G01X1514847Y92931D02*
X1514848D01*
Y92928D01*
X1514846D01*
Y92924D01*
X1514847D01*
G02X1514846Y92853I-1512J-14D01*
G01Y92836D01*
X1514844Y92817D01*
G02X1511844Y92664I-1509J102D01*
G01X1511820Y92780D01*
Y92784D01*
X1511819D01*
X1511496Y96414D01*
X1511497D01*
Y96415D01*
X1511501Y96542D01*
G02X1512516Y97974I1512J4D01*
G02X1513224Y98044I499J-1427D01*
G02X1514519Y96682I-211J-1498D01*
G01X1514529Y96683D01*
X1514541Y96554D01*
X1514534D01*
X1514535Y96548D01*
X1514541D01*
X1514852Y93055D01*
X1514849Y93053D01*
X1514848D01*
X1514843Y93048D01*
X1514844Y93026D01*
G02X1514847Y92931I-1509J-95D01*
G37*
G36*
G01X1756912Y37661D02*
Y37615D01*
X1756908Y37577D01*
G02X1754912Y36269I-1507J123D01*
G01X1754909Y36259D01*
X1751506Y37425D01*
Y37430D01*
X1751440Y37460D01*
G02X1751250Y37551I557J1406D01*
G03X1751065Y37198I-78J-184D01*
G02X1751762Y35935I-815J-1273D01*
G01Y35840D01*
X1751752Y35756D01*
G02X1750250Y34414I-1502J170D01*
G01X1746550D01*
G02X1745673Y37156I0J1511D01*
G03X1745687Y37796I-233J325D01*
G02X1747684Y38073I865J1104D01*
G03X1748006Y37436I323J-237D01*
G01X1750251D01*
G02X1750363Y37432I2J-1511D01*
G03X1750741Y38027I29J399D01*
G02X1752488Y40296I1260J837D01*
G01X1752491Y40306D01*
X1755896Y39140D01*
Y39138D01*
X1756013Y39082D01*
G02X1756350Y38877I-611J-1383D01*
G01Y38876D01*
G02X1756360Y38868I-939J-1184D01*
G01X1756362D01*
G02X1756912Y37710I-963J-1167D01*
G01Y37702D01*
G02Y37661I-1512J-20D01*
G37*
G36*
G01X429080Y263579D02*
G03X428790Y263469I-100J-174D01*
G01Y263181D01*
X427298Y261688D01*
X424212D01*
Y258049D01*
X423019Y256856D01*
X422896D01*
G03X422646Y256251I87J-390D01*
G02X420282I-1182J-754D01*
G03X420032Y256856I-337J215D01*
G01X418461D01*
X410712Y249108D01*
Y199446D01*
X415346Y194812D01*
Y132776D01*
X449372Y98751D01*
Y90551D01*
X448579Y90274D01*
X448570Y90271D01*
G03X448562Y89532I122J-371D01*
G01X449372Y89248D01*
Y85925D01*
X448500Y85671D01*
G03Y84921I110J-375D01*
G01X449372Y84667D01*
Y74222D01*
X448513Y73970D01*
X448499Y73966D01*
G03X448208Y73571I99J-378D01*
G03X448345Y73292I390J19D01*
G02X448386Y71183I-917J-1073D01*
G03X448348Y70650I265J-287D01*
G03X448409Y70589I305J244D01*
G02X448396Y68405I-901J-1087D01*
G03X448512Y67717I231J-315D01*
G01X449372Y67457D01*
Y65216D01*
X449300Y65145D01*
Y55514D01*
X448782Y55224D01*
G03Y54542I191J-341D01*
G01X449300Y54252D01*
Y51614D01*
X448394Y51378D01*
G03Y50622I98J-378D01*
G01X449300Y50386D01*
Y47599D01*
X448413Y47352D01*
Y47351D01*
G03Y46599I104J-376D01*
G01Y46598D01*
X449300Y46351D01*
Y36344D01*
X448335Y36144D01*
G03Y35378I79J-383D01*
G01X449300Y35178D01*
Y32421D01*
X448242Y32288D01*
G03X447954Y32095I51J-387D01*
G03X448407Y31527I338J-195D01*
G01X448414Y31529D01*
X449093Y31727D01*
X450212Y30608D01*
Y29808D01*
G02X448351Y28470I-1412J0D01*
G03Y27730I-125J-370D01*
G02X449627Y27535I448J-1338D01*
G03X450171Y27907I144J374D01*
G02X450474Y27028I1402J-8D01*
G03X450118Y26898I-156J-124D01*
G02X450212Y26392I-1318J-507D01*
G01Y25592D01*
X449300Y24681D01*
Y17627D01*
X448724Y17353D01*
G03Y16647I168J-353D01*
G01X449300Y16373D01*
Y14221D01*
X448242Y14088D01*
G03X448014Y13425I50J-388D01*
G02X448422Y12489I-1002J-994D01*
G02X449158Y10053I-196J-1388D01*
G01X449300Y9898D01*
Y-5385D01*
G02X447792Y-6792I-1411J1D01*
G03Y-7568I-48J-388D01*
G02X449300Y-8975I97J-1408D01*
G01Y-11936D01*
X447725Y-13512D01*
X381576D01*
G02X380523Y-11160I0J1412D01*
G03X379948Y-10632I-291J260D01*
G02X377880Y-10616I-1027J969D01*
G03X377418Y-10530I-288J-264D01*
G03X377294Y-10627I174J-350D01*
G02X376126Y-11104I-1061J930D01*
G03X375798Y-11464I71J-394D01*
G02X374822Y-12683I-1397J118D01*
G02X373548Y-13502I-1275J583D01*
G01X372928D01*
G02X372765Y-13512I-168J1402D01*
G01X104131D01*
X100023Y-9404D01*
G03X99491Y-9498I-215J-337D01*
G02X90822Y-10483I-4808J3676D01*
G03X90170Y-10745I-255J-308D01*
G02X88916Y-9191I-1393J159D01*
G03X89311Y-8609I40J398D01*
G02X91007Y-1014I5372J2787D01*
G03X91101Y-482I-243J317D01*
G01X82530Y8090D01*
X82401Y8002D01*
G02X80364Y8516I-791J1157D01*
G03X79806Y8677I-355J-184D01*
G02X78085Y10857I-710J1209D01*
G03X78089Y11406I-289J277D01*
G02X77763Y12728I1027J954D01*
G01X77790Y12829D01*
X65788Y24832D01*
X65666Y24766D01*
G02X63833Y25223I-666J1234D01*
G03X63167I-333J-222D01*
G02X61027Y24990I-1167J777D01*
G03X60473I-277J-288D01*
G02X58490Y26973I-973J1010D01*
G03Y27527I-288J277D01*
G02X60594Y29377I1010J973D01*
G03X60906I156J125D01*
G02X60946Y29424I1087J-885D01*
G03X60974Y29645I-151J131D01*
G01X58468Y32151D01*
Y42198D01*
X58369Y42248D01*
G02Y44752I631J1252D01*
G01X58478Y44807D01*
Y45193D01*
X58369Y45248D01*
G02Y47752I631J1252D01*
G01X58478Y47807D01*
Y48193D01*
X58369Y48248D01*
G02Y50752I631J1252D01*
G01X58468Y50802D01*
Y54698D01*
X58369Y54748D01*
G02X57990Y56973I631J1252D01*
G03Y57527I-288J277D01*
G02Y59473I1010J973D01*
G03Y60027I-288J277D01*
G02X58369Y62252I1010J973D01*
G01X58468Y62302D01*
Y78891D01*
X59295Y79718D01*
G02X59490Y79973I1204J-719D01*
G03Y80527I-288J277D01*
G02X61473Y82510I1010J973D01*
G03X62027I277J288D01*
G02X64337Y81923I973J-1010D01*
G01X64378Y81794D01*
X78098D01*
Y81986D01*
G02X80902I1402J14D01*
G01Y81794D01*
X98719D01*
G03X98967Y82402I-87J390D01*
G02X98747Y83325I1173J767D01*
G03X98122Y83698I-398J44D01*
G02X99631Y85193I-3439J4980D01*
G03X99998Y84565I327J-230D01*
G02X101313Y82402I142J-1395D01*
G03X101561Y81794I335J-218D01*
G01X112132D01*
X121120Y72806D01*
Y69199D01*
X123230Y67089D01*
Y67075D01*
X123249Y67055D01*
X123353Y67075D01*
G02X124941Y65229I267J-1376D01*
G03X125231Y64706I377J-133D01*
G01X128702D01*
G03X128992Y65229I-87J390D01*
G02X131634I1321J470D01*
G03X131924Y64706I377J-133D01*
G01X145434D01*
G03X145724Y65229I-87J390D01*
G02X148366I1321J470D01*
G03X148656Y64706I377J-133D01*
G01X152127D01*
G03X152417Y65229I-87J390D01*
G02X155059I1321J470D01*
G03X155349Y64706I377J-133D01*
G01X158820D01*
G03X159110Y65229I-87J390D01*
G02X161752I1321J470D01*
G03X162042Y64706I377J-133D01*
G01X165513D01*
G03X165803Y65229I-87J390D01*
G02X168445I1321J470D01*
G03X168735Y64706I377J-133D01*
G01X182245D01*
G03X182535Y65229I-87J390D01*
G02X185177I1321J470D01*
G03X185467Y64706I377J-133D01*
G01X188938D01*
G03X189228Y65229I-87J390D01*
G02X191870I1321J470D01*
G03X192160Y64706I377J-133D01*
G01X195631D01*
G03X195921Y65229I-87J390D01*
G02X198563I1321J470D01*
G03X198853Y64706I377J-133D01*
G01X202324D01*
G03X202614Y65229I-87J390D01*
G02X205256I1321J470D01*
G03X205546Y64706I377J-133D01*
G01X219056D01*
G03X219346Y65229I-87J390D01*
G02X221988I1321J470D01*
G03X222278Y64706I377J-133D01*
G01X225749D01*
G03X226039Y65229I-87J390D01*
G02X228681I1321J470D01*
G03X228971Y64706I377J-133D01*
G01X232442D01*
G03X232732Y65229I-87J390D01*
G02X235374I1321J470D01*
G03X235664Y64706I377J-133D01*
G01X239135D01*
G03X239425Y65229I-87J390D01*
G02X242067I1321J470D01*
G03X242357Y64706I377J-133D01*
G01X255867D01*
G03X256157Y65229I-87J390D01*
G02X258799I1321J470D01*
G03X259089Y64706I377J-133D01*
G01X262560D01*
G03X262850Y65229I-87J390D01*
G02X265492I1321J470D01*
G03X265782Y64706I377J-133D01*
G01X269253D01*
G03X269543Y65229I-87J390D01*
G02X272185I1321J470D01*
G03X272475Y64706I377J-133D01*
G01X275946D01*
G03X276236Y65229I-87J390D01*
G02X278878I1321J470D01*
G03X279168Y64706I377J-133D01*
G01X292678D01*
G03X292968Y65229I-87J390D01*
G02X295610I1321J470D01*
G03X295900Y64706I377J-133D01*
G01X299371D01*
G03X299661Y65229I-87J390D01*
G02X302321Y65282I1321J470D01*
G03X302616Y64774I382J-118D01*
G01X303207D01*
X306719Y68285D01*
X306724Y68298D01*
G02X307373Y68980I1204J-496D01*
G01X307378Y68982D01*
X308274Y69878D01*
Y69912D01*
X308322Y70171D01*
X308356Y70259D01*
G03X308357Y70539I-364J141D01*
G01X308274Y70748D01*
Y75782D01*
X307106Y76950D01*
Y85120D01*
X306434Y85792D01*
X307678Y87037D01*
X308138Y87004D01*
G03X308203Y87783I27J390D01*
G02X307106Y89877I135J1405D01*
G01Y91372D01*
X307010Y91423D01*
G02Y93891I665J1234D01*
G01X307106Y93942D01*
Y99170D01*
X312567Y104632D01*
G03X312544Y104847I-179J90D01*
G02X312730Y106795I1093J879D01*
G01Y116269D01*
X331988Y135527D01*
Y155717D01*
G03X331391Y155972I-390J-87D01*
G02X333247Y169691I-4619J7610D01*
G03X333750Y169626I291J274D01*
G01X334080Y169956D01*
Y172757D01*
X334042Y172796D01*
Y198479D01*
X334531Y198774D01*
G03X334673Y198923I-202J335D01*
G01X334743Y199054D01*
X335466Y199776D01*
Y216348D01*
X335742Y216641D01*
G03Y217177I-284J268D01*
G01X335465Y217470D01*
Y219397D01*
X335298Y219416D01*
G02Y222202I160J1393D01*
G01X335466Y222221D01*
Y224148D01*
X335742Y224441D01*
G03X335849Y224709I-284J269D01*
G01X335848Y224710D01*
Y225212D01*
X338074Y227438D01*
Y229384D01*
G02X338486Y231917I764J1176D01*
G01X338626Y231953D01*
Y233839D01*
X339062Y234140D01*
G03X339110Y234179I-222J322D01*
G03X339127Y234723I-272J281D01*
G01X338864Y235012D01*
Y237807D01*
X339127Y238097D01*
G03Y238623I-289J263D01*
G01X338864Y238913D01*
Y240214D01*
X338860Y240217D01*
Y241706D01*
X339126Y241996D01*
G03Y242524I-288J264D01*
G01X338860Y242814D01*
Y245499D01*
X340273Y246912D01*
X340694D01*
G03X340965Y247481I-87J390D01*
G02X343471I1253J628D01*
G03X343742Y246912I358J-179D01*
G01X344414D01*
G02X346782I1184J-752D01*
G01X351173D01*
G02X353541I1184J-752D01*
G01X357933D01*
G02X360301I1184J-752D01*
G01X360973D01*
G03X361244Y247481I-87J390D01*
G02X363750I1253J628D01*
G03X364021Y246912I358J-179D01*
G01X364693D01*
G02X367061I1184J-752D01*
G01X367733D01*
G03X368004Y247481I-87J390D01*
G02X370149Y249191I1253J628D01*
G03X370673Y249204I255J308D01*
G02X372469Y249707I1184J-769D01*
G03X372861Y250380I170J352D01*
G03X372774Y250425I-221J-321D01*
G02X372069Y252351I559J1297D01*
G03X371891Y252773I-391J84D01*
G02X373987Y253582I746J1187D01*
G03X374281Y253084I385J-108D01*
G01X375118D01*
G02X375668Y253367I901J-1074D01*
G02X376076Y254465I1408J102D01*
G01X378075Y256463D01*
G03X377855Y257060I-337J215D01*
G02X379640Y258117I412J1340D01*
G03X379913Y257654I392J-81D01*
G02X380261Y257595I-60J-1410D01*
G03X380452Y257786I-8J199D01*
G02X380805Y259193I1351J409D01*
G01X389056Y267444D01*
X401102D01*
X401118Y267430D01*
X427424D01*
X428790Y266063D01*
Y266049D01*
X428931Y265908D01*
G02X429080Y263579I850J-1115D01*
G37*
G36*
G01X47663Y260589D02*
X58204Y271130D01*
X74637D01*
X79070Y266697D01*
Y222933D01*
X75323Y219186D01*
X51301D01*
X47663Y222824D01*
Y260589D01*
G37*
G36*
G01X1951554Y127860D02*
X1958054D01*
G02Y112456I0J-7702D01*
G01X1951554D01*
G02Y127860I0J7702D01*
G37*
G36*
G01X1833443D02*
X1839943D01*
G02Y112456I0J-7702D01*
G01X1833443D01*
G02Y127860I0J7702D01*
G37*
G36*
G01X1857035Y602728D02*
X1854331D01*
G02Y618532I1J7902D01*
G01X1857044D01*
G03X1860510Y619640I-2J5982D01*
G02X1860511Y601620I7622J-9010D01*
G03X1857035Y602728I-3476J-4898D01*
G37*
G36*
G01Y-15776D02*
X1854331D01*
G02Y28I1J7902D01*
G01X1857044D01*
G03X1860510Y1136I-2J5982D01*
G02X1860511Y-16884I7622J-9010D01*
G03X1857035Y-15776I-3476J-4898D01*
G37*
G36*
G01X1675404Y616622D02*
X1678356Y611110D01*
G02X1674210Y608890I-2073J-1110D01*
G01X1671258Y614402D01*
G02X1675404Y616622I2073J1110D01*
G37*
G36*
G01X1684261Y601662D02*
X1687214Y596150D01*
G02X1683070Y593928I-2072J-1111D01*
G01X1680117Y599440D01*
G02X1684261Y601662I2072J1111D01*
G37*
G36*
G01X1675404Y601661D02*
X1678356Y596149D01*
G02X1674210Y593929I-2073J-1110D01*
G01X1671258Y599441D01*
G02X1675404Y601661I2073J1110D01*
G37*
G36*
G01X1684261Y616623D02*
X1687214Y611111D01*
G02X1683070Y608889I-2072J-1111D01*
G01X1680117Y614401D01*
G02X1684261Y616623I2072J1111D01*
G37*
G36*
G01X1408216Y602728D02*
X1405512D01*
G02Y618532I1J7902D01*
G01X1408225D01*
G03X1411691Y619640I-2J5982D01*
G02X1411692Y601620I7622J-9010D01*
G03X1408216Y602728I-3476J-4898D01*
G37*
G36*
G01Y-15776D02*
X1405512D01*
G02Y28I1J7902D01*
G01X1408225D01*
G03X1411691Y1136I-2J5982D01*
G02X1411692Y-16884I7622J-9010D01*
G03X1408216Y-15776I-3476J-4898D01*
G37*
G36*
G01X679869Y602728D02*
X677165D01*
G02Y618532I1J7902D01*
G01X679878D01*
G03X683344Y619640I-2J5982D01*
G02X683345Y601620I7622J-9010D01*
G03X679869Y602728I-3476J-4898D01*
G37*
G36*
G01Y-15776D02*
X677165D01*
G02Y28I1J7902D01*
G01X679878D01*
G03X683344Y1136I-2J5982D01*
G02X683345Y-16884I7622J-9010D01*
G03X679869Y-15776I-3476J-4898D01*
G37*
G36*
G01X2704Y602728D02*
X0D01*
G02Y618532I1J7902D01*
G01X2713D01*
G03X6179Y619640I-2J5982D01*
G02X6180Y601620I7622J-9010D01*
G03X2704Y602728I-3476J-4898D01*
G37*
G36*
G01X1313465Y618530D02*
G03X1312887I-289J-277D01*
G02Y620472I-1011J971D01*
G03X1313465I289J277D01*
G02Y618530I1011J-971D01*
G37*
G36*
G01X1591926Y619723D02*
G03X1592512Y619711I299J266D01*
G02X1592474Y617801I1007J-975D01*
G03X1591888Y617813I-299J-266D01*
G02X1591926Y619723I-1007J975D01*
G37*
G36*
G01X1602539Y617279D02*
G03X1601961I-289J-277D01*
G02Y619221I-1011J971D01*
G03X1602539I289J277D01*
G02Y617279I1011J-971D01*
G37*
G36*
G01X1962583Y618411D02*
G03Y617789I252J-311D01*
G02X1960817I-883J-1089D01*
G03Y618411I-252J311D01*
G02X1962583I883J1089D01*
G37*
G36*
G01X713345Y616607D02*
G03X712901Y616223I-44J-398D01*
G02X711655Y617667I-1401J51D01*
G03X712099Y618051I44J398D01*
G02X713345Y616607I1401J-51D01*
G37*
G36*
G01X1931383Y617811D02*
G03Y617189I252J-311D01*
G02X1929617I-883J-1089D01*
G03Y617811I-252J311D01*
G02X1931383I883J1089D01*
G37*
G36*
G01X1372904Y615115D02*
G03X1372297Y615025I-266J-298D01*
G02X1372034Y616802I-1197J731D01*
G03X1372641Y616892I266J298D01*
G02X1372904Y615115I1197J-731D01*
G37*
G36*
G01X629517Y611700D02*
G03X629012Y611466I-132J-378D01*
G02X628165Y613297I-1307J507D01*
G03X628670Y613531I132J378D01*
G02X629517Y611700I1307J-507D01*
G37*
G36*
G01X656071Y613089D02*
G03Y612511I277J-289D01*
G02X654129I-971J-1011D01*
G03Y613089I-277J289D01*
G02X656071I971J1011D01*
G37*
G36*
G01X1533154Y612419D02*
G03X1533178Y611832I283J-282D01*
G02X1531276Y611753I-908J-1068D01*
G03X1531252Y612340I-283J282D01*
G02X1531212Y612375I903J1072D01*
G03X1530665Y612370I-271J-294D01*
G02X1528802Y612305I-968J1014D01*
G03X1528215Y612219I-255J-308D01*
G02X1527945Y614079I-1165J781D01*
G03X1528532Y614165I255J308D01*
G02X1528563Y614209I1162J-786D01*
G03X1528485Y614509I-161J118D01*
G02X1530296Y615109I582J1275D01*
G03X1530435Y614576I350J-193D01*
G02X1530645Y614417I-738J-1192D01*
G03X1531192Y614422I271J294D01*
G02X1533154Y612419I969J-1014D01*
G37*
G36*
G01X1383607Y611122D02*
G03X1383603Y610567I286J-280D01*
G02X1381584Y610582I-1017J-965D01*
G03X1381588Y611137I-286J280D01*
G02X1383607Y611122I1017J965D01*
G37*
G36*
G01X1652380Y614210D02*
Y609115D01*
X1652371Y609031D01*
G02X1649358Y609200I-1502J169D01*
G01Y614201D01*
G02X1652380Y614210I1511J-1D01*
G37*
G36*
G01X1637045Y616571D02*
X1637046Y616569D01*
X1639942Y611164D01*
X1639943Y611162D01*
G02X1635798Y608941I-2045J-1162D01*
G01X1635797Y608943D01*
X1632901Y614348D01*
X1632900Y614350D01*
G02X1637045Y616571I2045J1162D01*
G37*
G36*
G01X1628179Y616586D02*
X1628180Y616585D01*
X1631092Y611148D01*
X1631093Y611146D01*
G02X1626947Y608926I-2054J-1146D01*
G01X1626946Y608927D01*
X1624034Y614364D01*
X1624033Y614366D01*
G02X1628179Y616586I2054J1146D01*
G37*
G36*
G01X1505671Y610089D02*
G03Y609511I277J-289D01*
G02X1503729I-971J-1011D01*
G03Y610089I-277J289D01*
G02X1505671I971J1011D01*
G37*
G36*
G01X934593Y608978D02*
G03X934598Y608390I274J-292D01*
G02X932697Y608371I-940J-1040D01*
G03X932692Y608959I-274J292D01*
G02X934593Y608978I940J1040D01*
G37*
G36*
G01X897782D02*
G03X897787Y608390I274J-292D01*
G02X895886Y608371I-940J-1040D01*
G03X895881Y608959I-274J292D01*
G02X897782Y608978I940J1040D01*
G37*
G36*
G01X860971D02*
G03X860976Y608390I274J-292D01*
G02X859075Y608371I-940J-1040D01*
G03X859070Y608959I-274J292D01*
G02X860971Y608978I940J1040D01*
G37*
G36*
G01X824160D02*
G03X824165Y608390I274J-292D01*
G02X822264Y608371I-940J-1040D01*
G03X822259Y608959I-274J292D01*
G02X824160Y608978I940J1040D01*
G37*
G36*
G01X785453Y608371D02*
G03X785448Y608959I-274J292D01*
G02X787349Y608978I940J1040D01*
G03X787354Y608390I274J-292D01*
G02X785453Y608371I-940J-1040D01*
G37*
G36*
G01X576127Y608978D02*
G03X576132Y608390I274J-292D01*
G02X574231Y608371I-940J-1040D01*
G03X574226Y608959I-274J292D01*
G02X576127Y608978I940J1040D01*
G37*
G36*
G01X539316D02*
G03X539321Y608390I274J-292D01*
G02X537420Y608371I-940J-1040D01*
G03X537415Y608959I-274J292D01*
G02X539316Y608978I940J1040D01*
G37*
G36*
G01X502505D02*
G03X502510Y608390I274J-292D01*
G02X500609Y608371I-940J-1040D01*
G03X500604Y608959I-274J292D01*
G02X502505Y608978I940J1040D01*
G37*
G36*
G01X465693D02*
G03X465698Y608390I274J-292D01*
G02X463797Y608371I-940J-1040D01*
G03X463792Y608959I-274J292D01*
G02X465693Y608978I940J1040D01*
G37*
G36*
G01X939699Y608734D02*
G03Y608155I276J-290D01*
G02X937765I-967J-1015D01*
G03Y608734I-276J289D01*
G02X939699I967J1015D01*
G37*
G36*
G01X902888D02*
G03Y608155I276J-290D01*
G02X900954I-967J-1015D01*
G03Y608734I-276J289D01*
G02X902888I967J1015D01*
G37*
G36*
G01X866077D02*
G03Y608155I276J-290D01*
G02X864143I-967J-1015D01*
G03Y608734I-276J289D01*
G02X866077I967J1015D01*
G37*
G36*
G01X829266D02*
G03Y608155I276J-290D01*
G02X827332I-967J-1015D01*
G03Y608734I-276J289D01*
G02X829266I967J1015D01*
G37*
G36*
G01X792455D02*
G03Y608155I276J-290D01*
G02X790521I-967J-1015D01*
G03Y608734I-276J289D01*
G02X792455I967J1015D01*
G37*
G36*
G01X581233D02*
G03Y608155I276J-290D01*
G02X579299I-967J-1015D01*
G03Y608734I-276J289D01*
G02X581233I967J1015D01*
G37*
G36*
G01X544422D02*
G03Y608155I276J-290D01*
G02X542488I-967J-1015D01*
G03Y608734I-276J289D01*
G02X544422I967J1015D01*
G37*
G36*
G01X507611D02*
G03Y608155I276J-290D01*
G02X505677I-967J-1015D01*
G03Y608734I-276J289D01*
G02X507611I967J1015D01*
G37*
G36*
G01X470800D02*
G03Y608155I276J-290D01*
G02X468865I-968J-1015D01*
G03Y608734I-276J289D01*
G02X470800I967J1015D01*
G37*
G36*
G01X1545090Y606559D02*
G03X1545469Y606114I397J-46D01*
G02X1544014Y604873I-62J-1401D01*
G03X1543635Y605318I-397J46D01*
G02X1542337Y606379I62J1401D01*
G03X1541774Y606642I-388J-97D01*
G02X1542522Y608243I-612J1261D01*
G03X1543085Y607980I388J97D01*
G02X1545090Y606559I612J-1261D01*
G37*
G36*
G01X1605380Y608460D02*
Y604365D01*
X1605371Y604281D01*
G02X1602358Y604450I-1502J169D01*
G01Y608451D01*
G02X1605380Y608460I1511J-1D01*
G37*
G36*
G01X1659880Y606260D02*
Y602165D01*
X1659871Y602081D01*
G02X1656858Y602250I-1502J169D01*
G01Y606251D01*
G02X1659880Y606260I1511J-1D01*
G37*
G36*
G01X1572237Y600367D02*
G03X1571718Y600360I-255J-308D01*
G02X1571683Y602796I-1058J1203D01*
G03X1572202Y602803I255J308D01*
G02X1572237Y600367I1058J-1203D01*
G37*
G36*
G01X1804772Y601902D02*
G03X1804178Y601662I-207J-342D01*
G02X1803850Y604145I-3193J841D01*
G03X1804486Y604068I347J199D01*
G02X1804772Y601902I1014J-968D01*
G37*
G36*
G01X1614860Y603260D02*
Y599165D01*
X1614851Y599081D01*
G02X1611838Y599250I-1502J169D01*
G01Y603251D01*
G02X1614860Y603260I1511J-1D01*
G37*
G36*
G01X713010Y598527D02*
G03Y597973I288J-277D01*
G02X710990I-1010J-973D01*
G03Y598527I-288J277D01*
G02X713010I1010J973D01*
G37*
G36*
G01X1589293Y595924D02*
G03X1588711Y595918I-288J-277D01*
G02X1586692Y595871I-1032J949D01*
G03X1586137Y595879I-282J-284D01*
G02X1586166Y597898I-958J1023D01*
G03X1586721Y597890I282J284D01*
G02X1588690Y597839I959J-1023D01*
G03X1589272Y597845I288J277D01*
G02X1589293Y595924I1032J-949D01*
G37*
G36*
G01X709771Y598289D02*
G03Y597711I277J-289D01*
G02X707829I-971J-1011D01*
G03Y598289I-277J289D01*
G02X709771I971J1011D01*
G37*
G36*
G01X1637045Y601610D02*
X1637046Y601608D01*
X1639942Y596203D01*
X1639943Y596201D01*
G02X1635798Y593980I-2045J-1162D01*
G01X1635797Y593982D01*
X1632901Y599387D01*
X1632900Y599389D01*
G02X1637045Y601610I2045J1162D01*
G37*
G36*
G01X1628179Y601625D02*
X1628180Y601624D01*
X1631092Y596187D01*
X1631093Y596185D01*
G02X1626947Y593965I-2054J-1146D01*
G01X1626946Y593966D01*
X1624034Y599403D01*
X1624033Y599405D01*
G02X1628179Y601625I2054J1146D01*
G37*
G36*
G01X1654010Y597960D02*
Y593865D01*
X1654001Y593781D01*
G02X1650988Y593950I-1502J169D01*
G01Y597951D01*
G02X1654010Y597960I1511J-1D01*
G37*
G36*
G01X754907Y592660D02*
G03X754330Y592649I-283J-282D01*
G02X754293Y594590I-1030J951D01*
G03X754870Y594601I283J282D01*
G02X754907Y592660I1030J-951D01*
G37*
G36*
G01X1801343Y595110D02*
G03X1801349Y594538I283J-283D01*
G02X1799387Y594518I-971J-1011D01*
G03X1799381Y595090I-283J283D01*
G02X1801343Y595110I971J1011D01*
G37*
G36*
G01X1710951Y594470D02*
G03X1710940Y593893I271J-294D01*
G02X1708999Y593930I-990J-993D01*
G03X1709010Y594507I-271J294D01*
G02X1710951Y594470I990J993D01*
G37*
G36*
G01X1605430Y596760D02*
Y592665D01*
X1605421Y592581D01*
G02X1602408Y592750I-1502J169D01*
G01Y596751D01*
G02X1605430Y596760I1511J-1D01*
G37*
G36*
G01X1718962Y593631D02*
G03X1718956Y593035I264J-301D01*
G02X1717083Y593055I-948J-1033D01*
G03X1717089Y593651I-264J301D01*
G02X1717027Y595657I948J1033D01*
G03Y596211I-288J277D01*
G02X1719047I1010J973D01*
G03Y595657I288J-277D01*
G02X1718962Y593631I-1010J-972D01*
G37*
G36*
G01X1554589Y590129D02*
G03X1554011I-289J-277D01*
G02Y592071I-1011J971D01*
G03X1554589I289J277D01*
G02Y590129I1011J-971D01*
G37*
G36*
G01X648104Y592592D02*
G03X648419Y592084I383J-114D01*
G02X646836Y591102I-239J-1382D01*
G03X646521Y591610I-383J114D01*
G02X645381Y592738I239J1382D01*
G03X644880Y593050I-393J-73D01*
G02X645879Y594654I-380J1350D01*
G03X646380Y594342I393J73D01*
G02X648104Y592592I380J-1350D01*
G37*
G36*
G01X2455Y591389D02*
G03X2419Y590786I244J-317D01*
G02X584Y590894I-980J-1003D01*
G03X620Y591497I-244J317D01*
G02X506Y591623I981J1002D01*
G03X194I-156J-125D01*
G02X73Y593510I-1094J877D01*
G03X627I277J288D01*
G02X2455Y591389I972J-1010D01*
G37*
G36*
G01X1763216Y590944D02*
G03Y590666I144J-139D01*
G02X1760908I-1154J-1111D01*
G03Y590944I-144J139D01*
G02X1763216I1154J1111D01*
G37*
G36*
G01X939703Y590103D02*
G03Y589525I277J-289D01*
G02X937761I-971J-1011D01*
G03Y590103I-277J289D01*
G02X939703I971J1011D01*
G37*
G36*
G01X902892D02*
G03Y589525I277J-289D01*
G02X900950I-971J-1011D01*
G03Y590103I-277J289D01*
G02X902892I971J1011D01*
G37*
G36*
G01X866081D02*
G03Y589525I277J-289D01*
G02X864139I-971J-1011D01*
G03Y590103I-277J289D01*
G02X866081I971J1011D01*
G37*
G36*
G01X829270D02*
G03Y589525I277J-289D01*
G02X827328I-971J-1011D01*
G03Y590103I-277J289D01*
G02X829270I971J1011D01*
G37*
G36*
G01X792459D02*
G03Y589525I277J-289D01*
G02X790517I-971J-1011D01*
G03Y590103I-277J289D01*
G02X792459I971J1011D01*
G37*
G36*
G01X581237D02*
G03Y589525I277J-289D01*
G02X579295I-971J-1011D01*
G03Y590103I-277J289D01*
G02X581237I971J1011D01*
G37*
G36*
G01X544426D02*
G03Y589525I277J-289D01*
G02X542484I-971J-1011D01*
G03Y590103I-277J289D01*
G02X544426I971J1011D01*
G37*
G36*
G01X507615D02*
G03Y589525I277J-289D01*
G02X505673I-971J-1011D01*
G03Y590103I-277J289D01*
G02X507615I971J1011D01*
G37*
G36*
G01X470803D02*
G03Y589525I277J-289D01*
G02X468861I-971J-1011D01*
G03Y590103I-277J289D01*
G02X470803I971J1011D01*
G37*
G36*
G01X934603Y589889D02*
G03Y589311I277J-289D01*
G02X932661I-971J-1011D01*
G03Y589889I-277J289D01*
G02X934603I971J1011D01*
G37*
G36*
G01X897792D02*
G03Y589311I277J-289D01*
G02X895850I-971J-1011D01*
G03Y589889I-277J289D01*
G02X897792I971J1011D01*
G37*
G36*
G01X860981D02*
G03Y589311I277J-289D01*
G02X859039I-971J-1011D01*
G03Y589889I-277J289D01*
G02X860981I971J1011D01*
G37*
G36*
G01X824170D02*
G03Y589311I277J-289D01*
G02X822228I-971J-1011D01*
G03Y589889I-277J289D01*
G02X824170I971J1011D01*
G37*
G36*
G01X787359D02*
G03Y589311I277J-289D01*
G02X785417I-971J-1011D01*
G03Y589889I-277J289D01*
G02X787359I971J1011D01*
G37*
G36*
G01X576137D02*
G03Y589311I277J-289D01*
G02X574195I-971J-1011D01*
G03Y589889I-277J289D01*
G02X576137I971J1011D01*
G37*
G36*
G01X539326D02*
G03Y589311I277J-289D01*
G02X537384I-971J-1011D01*
G03Y589889I-277J289D01*
G02X539326I971J1011D01*
G37*
G36*
G01X502515D02*
G03Y589311I277J-289D01*
G02X500573I-971J-1011D01*
G03Y589889I-277J289D01*
G02X502515I971J1011D01*
G37*
G36*
G01X465703D02*
G03Y589311I277J-289D01*
G02X463761I-971J-1011D01*
G03Y589889I-277J289D01*
G02X465703I971J1011D01*
G37*
G36*
G01X1662192Y590760D02*
Y586665D01*
X1662182Y586581D01*
G02X1659168Y586750I-1502J169D01*
G01Y590751D01*
G02X1662192Y590760I1512J-1D01*
G37*
G36*
G01X1419447Y585240D02*
G03X1418893I-277J-288D01*
G02X1416824Y585375I-973J1010D01*
G03X1416215Y585394I-313J-249D01*
G02X1414200Y585322I-1042J938D01*
G03X1413646I-277J-288D01*
G02Y587342I-973J1010D01*
G03X1414200I277J288D01*
G02X1416269Y587207I973J-1010D01*
G03X1416878Y587188I313J249D01*
G02X1418893Y587260I1042J-938D01*
G03X1419447I277J288D01*
G02X1421393I973J-1010D01*
G03X1421947I277J288D01*
G02Y585240I973J-1010D01*
G03X1421393I-277J-288D01*
G02X1419447I-973J1010D01*
G37*
G36*
G01X1611008Y590005D02*
G02X1614030Y590014I1511J-1D01*
G01Y586004D01*
X1614031D01*
Y585919D01*
X1614021Y585835D01*
G02X1611008Y586004I-1502J169D01*
G01Y590005D01*
G37*
G36*
G01X1544189Y584753D02*
G03X1543611I-289J-277D01*
G02Y586695I-1011J971D01*
G03X1544189I289J277D01*
G02Y584753I1011J-971D01*
G37*
G36*
G01X1372689Y583685D02*
G03X1372111I-289J-277D01*
G02Y585627I-1011J971D01*
G03X1372689I289J277D01*
G02Y583685I1011J-971D01*
G37*
G36*
G01X1815255Y582948D02*
G03X1814679Y582814I-227J-329D01*
G02X1814253Y584653I-1223J686D01*
G03X1814829Y584787I227J329D01*
G02X1815255Y582948I1223J-686D01*
G37*
G36*
G01X1731818Y580896D02*
G03X1732393Y580876I297J267D01*
G02X1732324Y578932I975J-1008D01*
G03X1731749Y578952I-297J-267D01*
G02X1731818Y580896I-975J1008D01*
G37*
G36*
G01X1684289Y586650D02*
X1684290Y586648D01*
X1687186Y581243D01*
X1687187Y581241D01*
G02X1683042Y579020I-2045J-1162D01*
G01X1683041Y579022D01*
X1680145Y584427D01*
X1680144Y584429D01*
G02X1684289Y586650I2045J1162D01*
G37*
G36*
G01X1675423Y586665D02*
X1675424Y586664D01*
X1678336Y581227D01*
X1678337Y581225D01*
G02X1674191Y579005I-2054J-1146D01*
G01X1674190Y579006D01*
X1671278Y584443D01*
X1671277Y584445D01*
G02X1675423Y586665I2054J1146D01*
G37*
G36*
G01X1637045Y586650D02*
X1637046Y586648D01*
X1639942Y581243D01*
X1639943Y581241D01*
G02X1635798Y579020I-2045J-1162D01*
G01X1635797Y579022D01*
X1632901Y584427D01*
X1632900Y584429D01*
G02X1637045Y586650I2045J1162D01*
G37*
G36*
G01X1628179Y586665D02*
X1628180Y586664D01*
X1631092Y581227D01*
X1631093Y581225D01*
G02X1626947Y579005I-2054J-1146D01*
G01X1626946Y579006D01*
X1624034Y584443D01*
X1624033Y584445D01*
G02X1628179Y586665I2054J1146D01*
G37*
G36*
G01X1607506Y582510D02*
Y578415D01*
X1607496Y578331D01*
G02X1604482Y578500I-1502J169D01*
G01Y582501D01*
G02X1607506Y582510I1512J-1D01*
G37*
G36*
G01X1654180Y582360D02*
Y578265D01*
X1654171Y578181D01*
G02X1651158Y578350I-1502J169D01*
G01Y582351D01*
G02X1654180Y582360I1511J-1D01*
G37*
G36*
G01X651238Y573438D02*
G03X650696Y573413I-257J-306D01*
G02X648729Y575411I-996J987D01*
G03Y575989I-277J289D01*
G02X650645Y578036I971J1011D01*
G03X651186Y578039I269J296D01*
G02X653150Y576038I954J-1028D01*
G03Y575484I288J-277D01*
G02X651238Y573438I-1009J-973D01*
G37*
G36*
G01X664689Y573229D02*
G03X664111I-289J-277D01*
G02Y575171I-1011J971D01*
G03X664689I289J277D01*
G02Y573229I1011J-971D01*
G37*
G36*
G01X1772522Y574592D02*
G03X1772110Y574142I-15J-400D01*
G02X1770775Y575365I-1391J-178D01*
G03X1771187Y575815I15J400D01*
G02X1772522Y574592I1391J178D01*
G37*
G36*
G01X660489Y568829D02*
G03X659911I-289J-277D01*
G02Y570771I-1011J971D01*
G03X660489I289J277D01*
G02Y568829I1011J-971D01*
G37*
G36*
G01X934593Y571178D02*
G03X934598Y570590I274J-292D01*
G02X932697Y570571I-940J-1040D01*
G03X932692Y571159I-274J292D01*
G02X934593Y571178I940J1040D01*
G37*
G36*
G01X897782D02*
G03X897787Y570590I274J-292D01*
G02X895886Y570571I-940J-1040D01*
G03X895881Y571159I-274J292D01*
G02X897782Y571178I940J1040D01*
G37*
G36*
G01X860971D02*
G03X860976Y570590I274J-292D01*
G02X859075Y570571I-940J-1040D01*
G03X859070Y571159I-274J292D01*
G02X860971Y571178I940J1040D01*
G37*
G36*
G01X824160D02*
G03X824165Y570590I274J-292D01*
G02X822264Y570571I-940J-1040D01*
G03X822259Y571159I-274J292D01*
G02X824160Y571178I940J1040D01*
G37*
G36*
G01X787349D02*
G03X787354Y570590I274J-292D01*
G02X785453Y570571I-940J-1040D01*
G03X785448Y571159I-274J292D01*
G02X787349Y571178I940J1040D01*
G37*
G36*
G01X576127D02*
G03X576132Y570590I274J-292D01*
G02X574231Y570571I-940J-1040D01*
G03X574226Y571159I-274J292D01*
G02X576127Y571178I940J1040D01*
G37*
G36*
G01X539316D02*
G03X539321Y570590I274J-292D01*
G02X537420Y570571I-940J-1040D01*
G03X537415Y571159I-274J292D01*
G02X539316Y571178I940J1040D01*
G37*
G36*
G01X502505D02*
G03X502510Y570590I274J-292D01*
G02X500609Y570571I-940J-1040D01*
G03X500604Y571159I-274J292D01*
G02X502505Y571178I940J1040D01*
G37*
G36*
G01X463797Y570571D02*
G03X463792Y571159I-274J292D01*
G02X465693Y571178I940J1040D01*
G03X465698Y570590I274J-292D01*
G02X463797Y570571I-940J-1040D01*
G37*
G36*
G01X939699Y570934D02*
G03Y570355I276J-290D01*
G02X937765I-967J-1015D01*
G03Y570934I-276J289D01*
G02X939699I967J1015D01*
G37*
G36*
G01X902888D02*
G03Y570355I276J-290D01*
G02X900954I-967J-1015D01*
G03Y570934I-276J289D01*
G02X902888I967J1015D01*
G37*
G36*
G01X866077D02*
G03Y570355I276J-290D01*
G02X864143I-967J-1015D01*
G03Y570934I-276J289D01*
G02X866077I967J1015D01*
G37*
G36*
G01X829266D02*
G03Y570355I276J-290D01*
G02X827332I-967J-1015D01*
G03Y570934I-276J289D01*
G02X829266I967J1015D01*
G37*
G36*
G01X792455D02*
G03Y570355I276J-290D01*
G02X790521I-967J-1015D01*
G03Y570934I-276J289D01*
G02X792455I967J1015D01*
G37*
G36*
G01X581233D02*
G03Y570355I276J-290D01*
G02X579299I-967J-1015D01*
G03Y570934I-276J289D01*
G02X581233I967J1015D01*
G37*
G36*
G01X544422D02*
G03Y570355I276J-290D01*
G02X542488I-967J-1015D01*
G03Y570934I-276J289D01*
G02X544422I967J1015D01*
G37*
G36*
G01X507611D02*
G03Y570355I276J-290D01*
G02X505677I-967J-1015D01*
G03Y570934I-276J289D01*
G02X507611I967J1015D01*
G37*
G36*
G01X470799D02*
G03Y570355I276J-290D01*
G02X468865I-967J-1015D01*
G03Y570934I-276J289D01*
G02X470799I967J1015D01*
G37*
G36*
G01X703008Y570426D02*
G03X703030Y569849I288J-278D01*
G02X701092Y569774I-930J-1049D01*
G03X701070Y570351I-288J278D01*
G02X703008Y570426I930J1049D01*
G37*
G36*
G01X649000Y567694D02*
G03X648400I-300J-265D01*
G02Y569552I-1050J929D01*
G03X649000I300J265D01*
G02Y567694I1050J-929D01*
G37*
G36*
G01X1603336Y572335D02*
Y568240D01*
X1603327Y568156D01*
G02X1600314Y568325I-1502J169D01*
G01Y572326D01*
G02X1603336Y572335I1511J-1D01*
G37*
G36*
G01X4611Y568271D02*
G03X5189I289J277D01*
G02Y566329I1011J-971D01*
G03X4611I-289J-277D01*
G02Y568271I-1011J971D01*
G37*
G36*
G01X1684289Y571689D02*
X1684290Y571687D01*
X1687186Y566282D01*
X1687187Y566280D01*
G02X1683042Y564059I-2045J-1162D01*
G01X1683041Y564061D01*
X1680145Y569466D01*
X1680144Y569468D01*
G02X1684289Y571689I2045J1162D01*
G37*
G36*
G01X1675423Y571704D02*
X1675424Y571703D01*
X1678336Y566266D01*
X1678337Y566264D01*
G02X1674191Y564044I-2054J-1146D01*
G01X1674190Y564045D01*
X1671278Y569482D01*
X1671277Y569484D01*
G02X1675423Y571704I2054J1146D01*
G37*
G36*
G01X1637045Y571689D02*
X1637046Y571687D01*
X1639942Y566282D01*
X1639943Y566280D01*
G02X1635798Y564059I-2045J-1162D01*
G01X1635797Y564061D01*
X1632901Y569466D01*
X1632900Y569468D01*
G02X1637045Y571689I2045J1162D01*
G37*
G36*
G01X1628179Y571704D02*
X1628180Y571703D01*
X1631092Y566266D01*
X1631093Y566264D01*
G02X1626947Y564044I-2054J-1146D01*
G01X1626946Y564045D01*
X1624034Y569482D01*
X1624033Y569484D01*
G02X1628179Y571704I2054J1146D01*
G37*
G36*
G01X1448234Y562842D02*
G03X1447666I-284J-282D01*
G02Y564958I-1066J1058D01*
G03X1448234I284J282D01*
G02X1450327Y564996I1066J-1058D01*
G03X1450873I273J292D01*
G02X1452966Y564958I1027J-1096D01*
G03X1453534I284J282D01*
G02X1455666I1066J-1058D01*
G03X1456234I284J282D01*
G02Y562842I1066J-1058D01*
G03X1455666I-284J-282D01*
G02X1453534I-1066J1058D01*
G03X1452966I-284J-282D01*
G02X1450873Y562804I-1066J1058D01*
G03X1450327I-273J-292D01*
G02X1448234Y562842I-1027J1096D01*
G37*
G36*
G01X1655911Y562918D02*
G03X1655333Y562646I-187J-354D01*
G02X1653568Y564276I-1373J284D01*
G03X1653794Y564874I-112J384D01*
G02X1655911Y562918I4734J3000D01*
G37*
G36*
G01X1598097Y561256D02*
G03X1597543I-277J-288D01*
G02X1595579Y563258I-973J1010D01*
G03X1595590Y563812I-283J283D01*
G02X1595597Y565723I1030J952D01*
G03X1595593Y566275I-292J274D01*
G02X1597623Y566291I1007J975D01*
G03X1597627Y565739I292J-274D01*
G02X1597714Y565641I-1004J-979D01*
G03X1598026I156J125D01*
G02X1600111Y563772I1093J-878D01*
G03X1600100Y563218I283J-283D01*
G02X1598097Y561256I-1030J-952D01*
G37*
G36*
G01X1469299Y560816D02*
G03X1468752Y560810I-270J-295D01*
G02X1468729Y563003I-1038J1086D01*
G03X1469276Y563009I270J295D01*
G02X1471350Y563010I1038J-1086D01*
G03X1471919Y563027I276J289D01*
G02X1471982Y560916I1099J-1024D01*
G03X1471413Y560899I-276J-289D01*
G02X1469299Y560816I-1099J1024D01*
G37*
G36*
G01X1491088Y560819D02*
G03X1490484Y560798I-293J-273D01*
G02X1490415Y562765I-1168J944D01*
G03X1491019Y562786I293J273D01*
G02X1493372Y562765I1168J-944D01*
G03X1494002I315J246D01*
G02X1496254Y562899I1185J-923D01*
G03X1496828Y562906I284J282D01*
G02X1498949Y562964I1090J-1034D01*
G03X1499499I275J291D01*
G02Y560780I1031J-1092D01*
G03X1498949I-275J-291D01*
G02X1496851Y560815I-1031J1092D01*
G03X1496277Y560808I-284J-282D01*
G02X1494002Y560919I-1090J1034D01*
G03X1493372I-315J-246D01*
G02X1491088Y560819I-1185J923D01*
G37*
G36*
G01X1383118Y561641D02*
G03X1383081Y561073I262J-302D01*
G02X1381114Y561202I-1049J-930D01*
G03X1381151Y561770I-262J302D01*
G02X1383118Y561641I1049J930D01*
G37*
G36*
G01X1850561Y558233D02*
X1850537Y558238D01*
X1848488D01*
Y560287D01*
X1848483Y560311D01*
G02Y561689I2767J689D01*
G01X1848488Y561713D01*
Y563762D01*
X1850537D01*
X1850561Y563767D01*
G02X1851939I689J-2767D01*
G01X1851963Y563762D01*
X1854012D01*
Y561713D01*
X1854017Y561689D01*
G02Y560311I-2767J-689D01*
G01X1854012Y560287D01*
Y558238D01*
X1851963D01*
X1851939Y558233D01*
G02X1850561I-689J2767D01*
G37*
G36*
G01X1739133Y559735D02*
G03X1739297Y559155I335J-218D01*
G02X1737522Y558653I-600J-1267D01*
G03X1737358Y559233I-335J218D01*
G02X1739133Y559735I600J1267D01*
G37*
G36*
G01X1626606Y559210D02*
Y555115D01*
X1626596Y555031D01*
G02X1623582Y555200I-1502J169D01*
G01Y559200D01*
G02X1626606Y559210I1512J0D01*
G37*
G36*
G01X2336Y555456D02*
G03X2345Y554853I267J-298D01*
G02X503Y554827I-906J-1070D01*
G03X494Y555430I-267J298D01*
G02X389Y555529I908J1068D01*
G03X-189I-289J-277D01*
G02Y557471I-1011J971D01*
G03X389I289J277D01*
G02X2336Y555456I1011J-971D01*
G37*
G36*
G01X652611Y551617D02*
G03X651989I-311J-252D01*
G02Y553383I-1089J883D01*
G03X652611I311J252D01*
G02Y551617I1089J-883D01*
G37*
G36*
G01X1663754Y549588D02*
X1658753D01*
G02X1658754Y552412I1J1412D01*
G01X1663754D01*
G02X1665166Y551010I0J-1412D01*
G01Y550916D01*
X1665155Y550832D01*
G02X1663754Y549588I-1401J167D01*
G37*
G36*
G01X939703Y552303D02*
G03Y551725I277J-289D01*
G02X937761I-971J-1011D01*
G03Y552303I-277J289D01*
G02X939703I971J1011D01*
G37*
G36*
G01X902892D02*
G03Y551725I277J-289D01*
G02X900950I-971J-1011D01*
G03Y552303I-277J289D01*
G02X902892I971J1011D01*
G37*
G36*
G01X866081D02*
G03Y551725I277J-289D01*
G02X864139I-971J-1011D01*
G03Y552303I-277J289D01*
G02X866081I971J1011D01*
G37*
G36*
G01X829270D02*
G03Y551725I277J-289D01*
G02X827328I-971J-1011D01*
G03Y552303I-277J289D01*
G02X829270I971J1011D01*
G37*
G36*
G01X792459D02*
G03Y551725I277J-289D01*
G02X790517I-971J-1011D01*
G03Y552303I-277J289D01*
G02X792459I971J1011D01*
G37*
G36*
G01X581237D02*
G03Y551725I277J-289D01*
G02X579295I-971J-1011D01*
G03Y552303I-277J289D01*
G02X581237I971J1011D01*
G37*
G36*
G01X544426D02*
G03Y551725I277J-289D01*
G02X542484I-971J-1011D01*
G03Y552303I-277J289D01*
G02X544426I971J1011D01*
G37*
G36*
G01X507615D02*
G03Y551725I277J-289D01*
G02X505673I-971J-1011D01*
G03Y552303I-277J289D01*
G02X507615I971J1011D01*
G37*
G36*
G01X470803D02*
G03Y551725I277J-289D01*
G02X468861I-971J-1011D01*
G03Y552303I-277J289D01*
G02X470803I971J1011D01*
G37*
G36*
G01X934603Y552089D02*
G03Y551511I277J-289D01*
G02X932661I-971J-1011D01*
G03Y552089I-277J289D01*
G02X934603I971J1011D01*
G37*
G36*
G01X897792D02*
G03Y551511I277J-289D01*
G02X895850I-971J-1011D01*
G03Y552089I-277J289D01*
G02X897792I971J1011D01*
G37*
G36*
G01X860981D02*
G03Y551511I277J-289D01*
G02X859039I-971J-1011D01*
G03Y552089I-277J289D01*
G02X860981I971J1011D01*
G37*
G36*
G01X824170D02*
G03Y551511I277J-289D01*
G02X822228I-971J-1011D01*
G03Y552089I-277J289D01*
G02X824170I971J1011D01*
G37*
G36*
G01X787359D02*
G03Y551511I277J-289D01*
G02X785417I-971J-1011D01*
G03Y552089I-277J289D01*
G02X787359I971J1011D01*
G37*
G36*
G01X576137D02*
G03Y551511I277J-289D01*
G02X574195I-971J-1011D01*
G03Y552089I-277J289D01*
G02X576137I971J1011D01*
G37*
G36*
G01X539326D02*
G03Y551511I277J-289D01*
G02X537384I-971J-1011D01*
G03Y552089I-277J289D01*
G02X539326I971J1011D01*
G37*
G36*
G01X502515D02*
G03Y551511I277J-289D01*
G02X500573I-971J-1011D01*
G03Y552089I-277J289D01*
G02X502515I971J1011D01*
G37*
G36*
G01X465703D02*
G03Y551511I277J-289D01*
G02X463761I-971J-1011D01*
G03Y552089I-277J289D01*
G02X465703I971J1011D01*
G37*
G36*
G01X1685000Y549032D02*
X1679999D01*
G02X1680000Y552056I1J1512D01*
G01X1685000D01*
G02X1686512Y550554I0J-1512D01*
G01Y550459D01*
X1686502Y550375D01*
G02X1685000Y549032I-1502J168D01*
G37*
G36*
G01X1794888Y551715D02*
G03X1794866Y551116I254J-309D01*
G02X1793012Y551185I-966J-1016D01*
G03X1793034Y551784I-254J309D01*
G02X1794888Y551715I966J1016D01*
G37*
G36*
G01X1936731Y551240D02*
G03X1937264Y550995I380J125D01*
G02X1936469Y549260I536J-1295D01*
G03X1935936Y549505I-380J-125D01*
G02X1936731Y551240I-536J1295D01*
G37*
G36*
G01X1739037Y549968D02*
G03X1739065Y549355I270J-295D01*
G02X1737267Y549271I-849J-1116D01*
G03X1737239Y549884I-270J295D01*
G02X1739037Y549968I849J1116D01*
G37*
G36*
G01X1364055Y546944D02*
G03X1363501I-277J-288D01*
G02Y548964I-973J1010D01*
G03X1364055I277J288D01*
G02Y546944I973J-1010D01*
G37*
G36*
G01X1705348Y545122D02*
X1700348D01*
G02Y548144I0J1511D01*
G01X1705348D01*
G02X1706860Y546643I0J-1512D01*
G01Y546548D01*
X1706850Y546464D01*
G02X1705348Y545122I-1502J169D01*
G37*
G36*
G01X1496253Y546907D02*
G03X1496829Y546883I300J265D01*
G02X1496743Y544800I1037J-1086D01*
G03X1496167Y544824I-300J-265D01*
G02X1493945Y544987I-1037J1086D01*
G03X1493315I-315J-246D01*
G02X1490948Y544983I-1185J923D01*
G03X1490356Y545023I-314J-247D01*
G02X1490440Y546948I-976J1007D01*
G03X1491034Y546937I302J262D01*
G02X1493315Y546833I1096J-1027D01*
G03X1493945I315J246D01*
G02X1496253Y546907I1185J-923D01*
G37*
G36*
G01X1439987Y544190D02*
G03X1439915Y543633I247J-315D01*
G02X1437935Y543889I-1116J-848D01*
G03X1438007Y544446I-247J315D01*
G02X1439987Y544190I1116J848D01*
G37*
G36*
G01X1676020Y550027D02*
G03X1676280Y549508I376J-136D01*
G02X1671633Y548350I-1359J-4449D01*
G03X1671350Y549032I-283J282D01*
G01X1669599D01*
G02X1669600Y552056I1J1512D01*
G01X1674600D01*
G02X1676112Y550554I0J-1512D01*
G01Y550459D01*
X1676102Y550375D01*
G02X1676020Y550027I-1502J170D01*
G37*
G36*
G01X1391359Y540723D02*
G03X1391368Y540101I256J-307D01*
G02X1389603Y540077I-868J-1101D01*
G03X1389594Y540699I-256J307D01*
G02X1391359Y540723I868J1101D01*
G37*
G36*
G01X1743894Y534951D02*
G03X1743351I-271J-294D01*
G02Y538631I-1697J1840D01*
G03X1743894I272J294D01*
G02X1747288I1697J-1840D01*
G03X1747831I272J294D01*
G02X1751225I1697J-1840D01*
G03X1751768I271J294D01*
G02X1755162I1697J-1840D01*
G03X1755705I271J294D01*
G02X1759099I1697J-1840D01*
G03X1759642I272J294D01*
G02Y534951I1697J-1840D01*
G03X1759099I-271J-294D01*
G02X1755705I-1697J1840D01*
G03X1755162I-272J-294D01*
G02X1751768I-1697J1840D01*
G03X1751225I-272J-294D01*
G02X1747831I-1697J1840D01*
G03X1747288I-271J-294D01*
G02X1743894I-1697J1840D01*
G37*
G36*
G01X735027Y534190D02*
G03X734473I-277J-288D01*
G02X732490Y536173I-973J1010D01*
G03Y536727I-288J277D01*
G02X734473Y538710I1010J973D01*
G03X735027I277J288D01*
G02X737010Y536727I973J-1010D01*
G03Y536173I288J-277D01*
G02X735027Y534190I-1010J-973D01*
G37*
G36*
G01X1712206Y533780D02*
X1707204D01*
G02X1704820Y534952I0J3011D01*
G03X1704207Y534977I-317J-244D01*
G02X1700203Y534976I-2002J1814D01*
G03X1699590Y534952I-296J-268D01*
G02X1697206Y533780I-2384J1839D01*
G01X1692204D01*
G02X1689820Y534952I0J3011D01*
G03X1689207Y534977I-317J-244D01*
G02Y538605I-2002J1814D01*
G03X1689820Y538630I296J269D01*
G02X1692204Y539802I2384J-1839D01*
G01X1697206D01*
G02X1699590Y538630I0J-3011D01*
G03X1700203Y538606I317J244D01*
G02X1704207Y538605I2002J-1815D01*
G03X1704820Y538630I296J269D01*
G02X1707204Y539802I2384J-1839D01*
G01X1712206D01*
G02X1714590Y538630I0J-3011D01*
G03X1715203Y538606I317J244D01*
G02Y534976I2002J-1815D01*
G03X1714590Y534952I-296J-268D01*
G02X1712206Y533780I-2384J1839D01*
G37*
G36*
G01X1225735Y533378D02*
G03X1225740Y532790I274J-292D01*
G02X1223839Y532771I-940J-1040D01*
G03X1223834Y533359I-274J292D01*
G02X1225735Y533378I940J1040D01*
G37*
G36*
G01X1188924D02*
G03X1188929Y532790I274J-292D01*
G02X1187028Y532771I-940J-1040D01*
G03X1187023Y533359I-274J292D01*
G02X1188924Y533378I940J1040D01*
G37*
G36*
G01X1152113D02*
G03X1152118Y532790I274J-292D01*
G02X1150217Y532771I-940J-1040D01*
G03X1150212Y533359I-274J292D01*
G02X1152113Y533378I940J1040D01*
G37*
G36*
G01X1115301D02*
G03X1115306Y532790I274J-292D01*
G02X1113405Y532771I-940J-1040D01*
G03X1113400Y533359I-274J292D01*
G02X1115301Y533378I940J1040D01*
G37*
G36*
G01X934593D02*
G03X934598Y532790I274J-292D01*
G02X932697Y532771I-940J-1040D01*
G03X932692Y533359I-274J292D01*
G02X934593Y533378I940J1040D01*
G37*
G36*
G01X897782D02*
G03X897787Y532790I274J-292D01*
G02X895886Y532771I-940J-1040D01*
G03X895881Y533359I-274J292D01*
G02X897782Y533378I940J1040D01*
G37*
G36*
G01X860971D02*
G03X860976Y532790I274J-292D01*
G02X859075Y532771I-940J-1040D01*
G03X859070Y533359I-274J292D01*
G02X860971Y533378I940J1040D01*
G37*
G36*
G01X824160D02*
G03X824165Y532790I274J-292D01*
G02X822264Y532771I-940J-1040D01*
G03X822259Y533359I-274J292D01*
G02X824160Y533378I940J1040D01*
G37*
G36*
G01X785453Y532771D02*
G03X785448Y533359I-274J292D01*
G02X787349Y533378I940J1040D01*
G03X787354Y532790I274J-292D01*
G02X785453Y532771I-940J-1040D01*
G37*
G36*
G01X576127Y533378D02*
G03X576132Y532790I274J-292D01*
G02X574231Y532771I-940J-1040D01*
G03X574226Y533359I-274J292D01*
G02X576127Y533378I940J1040D01*
G37*
G36*
G01X539316D02*
G03X539321Y532790I274J-292D01*
G02X537420Y532771I-940J-1040D01*
G03X537415Y533359I-274J292D01*
G02X539316Y533378I940J1040D01*
G37*
G36*
G01X502505D02*
G03X502510Y532790I274J-292D01*
G02X500609Y532771I-940J-1040D01*
G03X500604Y533359I-274J292D01*
G02X502505Y533378I940J1040D01*
G37*
G36*
G01X463797Y532771D02*
G03X463792Y533359I-274J292D01*
G02X465693Y533378I940J1040D01*
G03X465698Y532790I274J-292D01*
G02X463797Y532771I-940J-1040D01*
G37*
G36*
G01X284985Y533378D02*
G03X284990Y532790I274J-292D01*
G02X283089Y532771I-940J-1040D01*
G03X283084Y533359I-274J292D01*
G02X284985Y533378I940J1040D01*
G37*
G36*
G01X248174D02*
G03X248179Y532790I274J-292D01*
G02X246278Y532771I-940J-1040D01*
G03X246273Y533359I-274J292D01*
G02X248174Y533378I940J1040D01*
G37*
G36*
G01X211363D02*
G03X211368Y532790I274J-292D01*
G02X209467Y532771I-940J-1040D01*
G03X209462Y533359I-274J292D01*
G02X211363Y533378I940J1040D01*
G37*
G36*
G01X174552D02*
G03X174557Y532790I274J-292D01*
G02X172656Y532771I-940J-1040D01*
G03X172651Y533359I-274J292D01*
G02X174552Y533378I940J1040D01*
G37*
G36*
G01X135845Y532771D02*
G03X135840Y533359I-274J292D01*
G02X137741Y533378I940J1040D01*
G03X137746Y532790I274J-292D01*
G02X135845Y532771I-940J-1040D01*
G37*
G36*
G01X1230841Y533134D02*
G03Y532555I276J-290D01*
G02X1228907I-967J-1015D01*
G03Y533134I-276J289D01*
G02X1230841I967J1015D01*
G37*
G36*
G01X1194030D02*
G03Y532555I276J-290D01*
G02X1192096I-967J-1015D01*
G03Y533134I-276J289D01*
G02X1194030I967J1015D01*
G37*
G36*
G01X1157219D02*
G03Y532555I276J-290D01*
G02X1155285I-967J-1015D01*
G03Y533134I-276J289D01*
G02X1157219I967J1015D01*
G37*
G36*
G01X1120407D02*
G03Y532555I276J-290D01*
G02X1118473I-967J-1015D01*
G03Y533134I-276J289D01*
G02X1120407I967J1015D01*
G37*
G36*
G01X939699D02*
G03Y532555I276J-290D01*
G02X937765I-967J-1015D01*
G03Y533134I-276J289D01*
G02X939699I967J1015D01*
G37*
G36*
G01X902888D02*
G03Y532555I276J-290D01*
G02X900954I-967J-1015D01*
G03Y533134I-276J289D01*
G02X902888I967J1015D01*
G37*
G36*
G01X866077D02*
G03Y532555I276J-290D01*
G02X864143I-967J-1015D01*
G03Y533134I-276J289D01*
G02X866077I967J1015D01*
G37*
G36*
G01X829266D02*
G03Y532555I276J-290D01*
G02X827332I-967J-1015D01*
G03Y533134I-276J289D01*
G02X829266I967J1015D01*
G37*
G36*
G01X792455D02*
G03Y532555I276J-290D01*
G02X790521I-967J-1015D01*
G03Y533134I-276J289D01*
G02X792455I967J1015D01*
G37*
G36*
G01X581233D02*
G03Y532555I276J-290D01*
G02X579299I-967J-1015D01*
G03Y533134I-276J289D01*
G02X581233I967J1015D01*
G37*
G36*
G01X544422D02*
G03Y532555I276J-290D01*
G02X542488I-967J-1015D01*
G03Y533134I-276J289D01*
G02X544422I967J1015D01*
G37*
G36*
G01X507611D02*
G03Y532555I276J-290D01*
G02X505677I-967J-1015D01*
G03Y533134I-276J289D01*
G02X507611I967J1015D01*
G37*
G36*
G01X470799D02*
G03Y532555I276J-290D01*
G02X468865I-967J-1015D01*
G03Y533134I-276J289D01*
G02X470799I967J1015D01*
G37*
G36*
G01X290091D02*
G03Y532555I276J-290D01*
G02X288157I-967J-1015D01*
G03Y533134I-276J289D01*
G02X290091I967J1015D01*
G37*
G36*
G01X253280D02*
G03Y532555I276J-290D01*
G02X251346I-967J-1015D01*
G03Y533134I-276J289D01*
G02X253280I967J1015D01*
G37*
G36*
G01X216469D02*
G03Y532555I276J-290D01*
G02X214535I-967J-1015D01*
G03Y533134I-276J289D01*
G02X216469I967J1015D01*
G37*
G36*
G01X179658D02*
G03Y532555I276J-290D01*
G02X177724I-967J-1015D01*
G03Y533134I-276J289D01*
G02X179658I967J1015D01*
G37*
G36*
G01X142847D02*
G03Y532555I276J-290D01*
G02X140913I-967J-1015D01*
G03Y533134I-276J289D01*
G02X142847I967J1015D01*
G37*
G36*
G01X4611Y532271D02*
G03X5189I289J277D01*
G02Y530329I1011J-971D01*
G03X4611I-289J-277D01*
G02Y532271I-1011J971D01*
G37*
G36*
G01X1930653Y529830D02*
X1928253D01*
G02Y535252I0J2711D01*
G01X1930653D01*
G02X1933364Y532551I0J-2711D01*
G01Y532452D01*
X1933359Y532363D01*
G02X1930653Y529830I-2706J179D01*
G37*
G36*
G01X1889927D02*
X1884727D01*
G02Y535252I0J2711D01*
G01X1889927D01*
G02X1892638Y532551I0J-2711D01*
G01Y532452D01*
X1892633Y532363D01*
G02X1889927Y529830I-2706J179D01*
G37*
G36*
G01X1482727Y530190D02*
G03X1482173I-277J-288D01*
G02Y532210I-973J1010D01*
G03X1482727I277J288D01*
G02Y530190I973J-1010D01*
G37*
G36*
G01X113575Y527166D02*
G03X113679Y527748I-214J338D01*
G02X115539Y527414I1113J852D01*
G03X115435Y526832I214J-338D01*
G02X113575Y527166I-1113J-852D01*
G37*
G36*
G01X1818548Y526492D02*
G03X1818168Y526005I11J-400D01*
G02X1816761Y527101I-1368J-305D01*
G03X1817141Y527588I-11J400D01*
G02X1818548Y526492I1368J305D01*
G37*
G36*
G01X1638728Y528723D02*
G03X1638940Y528154I350J-194D01*
G02X1636593Y527726I-810J-2208D01*
G03X1636591Y528333I-261J303D01*
G02X1638728Y528723I909J1067D01*
G37*
G36*
G01X1785026Y521592D02*
G03X1784449Y521570I-278J-288D01*
G02X1782379Y521539I-1049J930D01*
G03X1781811Y521552I-290J-275D01*
G02X1781859Y523523I-973J1010D01*
G03X1782427Y523510I290J275D01*
G02X1784374Y523508I972J-1010D01*
G03X1784951Y523530I278J288D01*
G02X1785026Y521592I1049J-930D01*
G37*
G36*
G01X702144Y523214D02*
G03X702156Y522612I270J-296D01*
G02X700311Y522574I-901J-1074D01*
G03X700299Y523176I-270J296D01*
G02X702144Y523214I901J1074D01*
G37*
G36*
G01X1629183Y519602D02*
G03X1628572Y519538I-279J-287D01*
G02X1628383Y521324I-1165J780D01*
G03X1628994Y521388I279J287D01*
G02X1629183Y519602I1165J-780D01*
G37*
G36*
G01X1698850Y519221D02*
G03X1698272I-289J-277D01*
G02Y521163I-1011J971D01*
G03X1698850I289J277D01*
G02Y519221I1011J-971D01*
G37*
G36*
G01X1790804Y521062D02*
G03X1790594Y520541I159J-367D01*
G02X1788746Y521288I-1294J-541D01*
G03X1788956Y521809I-159J367D01*
G02X1790804Y521062I1294J541D01*
G37*
G36*
G01X1377636Y518921D02*
G03X1377082I-277J-288D01*
G02X1375031Y519035I-973J1010D01*
G03X1374417Y519037I-308J-256D01*
G02X1374423Y520836I-1072J903D01*
G03X1375037Y520834I308J256D01*
G02X1377082Y520941I1073J-903D01*
G03X1377636I277J288D01*
G02X1379572Y520950I973J-1010D01*
G03X1380124Y520952I275J290D01*
G02X1382173Y520836I970J-1012D01*
G03X1382787Y520834I308J256D01*
G02X1384832Y520941I1073J-903D01*
G03X1385386I277J288D01*
G02Y518921I973J-1010D01*
G03X1384832I-277J-288D01*
G02X1382781Y519035I-973J1010D01*
G03X1382167Y519037I-308J-256D01*
G02X1380132Y518921I-1072J903D01*
G03X1379580Y518919I-275J-290D01*
G02X1377636Y518921I-971J1012D01*
G37*
G36*
G01X1492700Y518498D02*
X1490099D01*
G02X1490100Y521502I1J1502D01*
G01X1492700D01*
G02X1494202Y520010I0J-1502D01*
G01Y519915D01*
X1494192Y519831D01*
G02X1492700Y518498I-1492J168D01*
G37*
G36*
G01X753910Y520148D02*
G03Y519594I288J-277D01*
G02X751890I-1010J-973D01*
G03Y520148I-288J277D01*
G02X753910I1010J973D01*
G37*
G36*
G01X1510005Y516654D02*
X1507404D01*
G02X1507405Y519656I1J1501D01*
G01X1510005D01*
G02X1511506Y518165I0J-1501D01*
G01Y518070D01*
X1511497Y517986D01*
G02X1510005Y516654I-1492J169D01*
G37*
G36*
G01X53987Y525432D02*
G03X54513I263J302D01*
G02X56487I987J-1132D01*
G03X57013I263J302D01*
G02X59132Y523313I987J-1132D01*
G03Y522787I302J-263D01*
G02X59075Y520751I-1132J-987D01*
G03X59061Y520207I286J-280D01*
G02X56933Y518094I-1125J-995D01*
G03X56420Y518113I-268J-297D01*
G02X54397Y518281I-920J1187D01*
G03X54103I-147J-136D01*
G02X54037Y518214I-1102J1020D01*
G03X54036Y517925I138J-145D01*
G02X51848Y517819I-1044J-1079D01*
G03X51849Y518335I-305J259D01*
G02X51868Y520287I1151J965D01*
G03Y520813I-302J263D01*
G02Y522787I1132J987D01*
G03Y523313I-302J263D01*
G02X53987Y525432I1132J987D01*
G37*
G36*
G01X1498054Y517624D02*
X1500655D01*
G02X1502156Y516132I-1J-1502D01*
G01Y516037D01*
X1502147Y515953D01*
G02X1500655Y514620I-1492J169D01*
G01X1498054D01*
G02Y517624I0J1502D01*
G37*
G36*
G01X1483227Y514690D02*
G03X1482673I-277J-288D01*
G02Y516710I-973J1010D01*
G03X1483227I277J288D01*
G02Y514690I973J-1010D01*
G37*
G36*
G01X63468Y516587D02*
G03Y517113I-302J263D01*
G02X63617Y519235I1132J987D01*
G03X63596Y519857I-262J303D01*
G02X63343Y522008I907J1197D01*
G03X63317Y522545I-309J254D01*
G02X63282Y524631I1063J1061D01*
G03Y525177I-292J273D01*
G02X65087Y527527I1098J1025D01*
G03X65604Y527653I188J353D01*
G02X67972Y525813I1237J-852D01*
G03Y525287I302J-263D01*
G02X67864Y523201I-1132J-987D01*
G03X67853Y522919I136J-147D01*
G02X67882Y520913I-1103J-1019D01*
G03Y520387I302J-263D01*
G02Y518413I-1132J-987D01*
G03Y517887I302J-263D01*
G02X66485Y515422I-1132J-987D01*
G03X66032Y515148I-71J-394D01*
G02X63468Y516587I-1432J452D01*
G37*
G36*
G01X1314671Y516789D02*
G03Y516211I277J-289D01*
G02X1312729I-971J-1011D01*
G03Y516789I-277J289D01*
G02X1314671I971J1011D01*
G37*
G36*
G01X1230845Y514503D02*
G03Y513925I277J-289D01*
G02X1228903I-971J-1011D01*
G03Y514503I-277J289D01*
G02X1230845I971J1011D01*
G37*
G36*
G01X1194034D02*
G03Y513925I277J-289D01*
G02X1192092I-971J-1011D01*
G03Y514503I-277J289D01*
G02X1194034I971J1011D01*
G37*
G36*
G01X1157223D02*
G03Y513925I277J-289D01*
G02X1155281I-971J-1011D01*
G03Y514503I-277J289D01*
G02X1157223I971J1011D01*
G37*
G36*
G01X1120411D02*
G03Y513925I277J-289D01*
G02X1118469I-971J-1011D01*
G03Y514503I-277J289D01*
G02X1120411I971J1011D01*
G37*
G36*
G01X939703D02*
G03Y513925I277J-289D01*
G02X937761I-971J-1011D01*
G03Y514503I-277J289D01*
G02X939703I971J1011D01*
G37*
G36*
G01X902892D02*
G03Y513925I277J-289D01*
G02X900950I-971J-1011D01*
G03Y514503I-277J289D01*
G02X902892I971J1011D01*
G37*
G36*
G01X866081D02*
G03Y513925I277J-289D01*
G02X864139I-971J-1011D01*
G03Y514503I-277J289D01*
G02X866081I971J1011D01*
G37*
G36*
G01X829270D02*
G03Y513925I277J-289D01*
G02X827328I-971J-1011D01*
G03Y514503I-277J289D01*
G02X829270I971J1011D01*
G37*
G36*
G01X792459D02*
G03Y513925I277J-289D01*
G02X790517I-971J-1011D01*
G03Y514503I-277J289D01*
G02X792459I971J1011D01*
G37*
G36*
G01X581237D02*
G03Y513925I277J-289D01*
G02X579295I-971J-1011D01*
G03Y514503I-277J289D01*
G02X581237I971J1011D01*
G37*
G36*
G01X544426D02*
G03Y513925I277J-289D01*
G02X542484I-971J-1011D01*
G03Y514503I-277J289D01*
G02X544426I971J1011D01*
G37*
G36*
G01X507615D02*
G03Y513925I277J-289D01*
G02X505673I-971J-1011D01*
G03Y514503I-277J289D01*
G02X507615I971J1011D01*
G37*
G36*
G01X470803D02*
G03Y513925I277J-289D01*
G02X468861I-971J-1011D01*
G03Y514503I-277J289D01*
G02X470803I971J1011D01*
G37*
G36*
G01X290095D02*
G03Y513925I277J-289D01*
G02X288153I-971J-1011D01*
G03Y514503I-277J289D01*
G02X290095I971J1011D01*
G37*
G36*
G01X253284D02*
G03Y513925I277J-289D01*
G02X251342I-971J-1011D01*
G03Y514503I-277J289D01*
G02X253284I971J1011D01*
G37*
G36*
G01X216473D02*
G03Y513925I277J-289D01*
G02X214531I-971J-1011D01*
G03Y514503I-277J289D01*
G02X216473I971J1011D01*
G37*
G36*
G01X179662D02*
G03Y513925I277J-289D01*
G02X177720I-971J-1011D01*
G03Y514503I-277J289D01*
G02X179662I971J1011D01*
G37*
G36*
G01X142851D02*
G03Y513925I277J-289D01*
G02X140909I-971J-1011D01*
G03Y514503I-277J289D01*
G02X142851I971J1011D01*
G37*
G36*
G01X1225745Y514289D02*
G03Y513711I277J-289D01*
G02X1223803I-971J-1011D01*
G03Y514289I-277J289D01*
G02X1225745I971J1011D01*
G37*
G36*
G01X1188934D02*
G03Y513711I277J-289D01*
G02X1186992I-971J-1011D01*
G03Y514289I-277J289D01*
G02X1188934I971J1011D01*
G37*
G36*
G01X1152123D02*
G03Y513711I277J-289D01*
G02X1150181I-971J-1011D01*
G03Y514289I-277J289D01*
G02X1152123I971J1011D01*
G37*
G36*
G01X1115311D02*
G03Y513711I277J-289D01*
G02X1113369I-971J-1011D01*
G03Y514289I-277J289D01*
G02X1115311I971J1011D01*
G37*
G36*
G01X934603D02*
G03Y513711I277J-289D01*
G02X932661I-971J-1011D01*
G03Y514289I-277J289D01*
G02X934603I971J1011D01*
G37*
G36*
G01X897792D02*
G03Y513711I277J-289D01*
G02X895850I-971J-1011D01*
G03Y514289I-277J289D01*
G02X897792I971J1011D01*
G37*
G36*
G01X860981D02*
G03Y513711I277J-289D01*
G02X859039I-971J-1011D01*
G03Y514289I-277J289D01*
G02X860981I971J1011D01*
G37*
G36*
G01X824170D02*
G03Y513711I277J-289D01*
G02X822228I-971J-1011D01*
G03Y514289I-277J289D01*
G02X824170I971J1011D01*
G37*
G36*
G01X787359D02*
G03Y513711I277J-289D01*
G02X785417I-971J-1011D01*
G03Y514289I-277J289D01*
G02X787359I971J1011D01*
G37*
G36*
G01X576137D02*
G03Y513711I277J-289D01*
G02X574195I-971J-1011D01*
G03Y514289I-277J289D01*
G02X576137I971J1011D01*
G37*
G36*
G01X539326D02*
G03Y513711I277J-289D01*
G02X537384I-971J-1011D01*
G03Y514289I-277J289D01*
G02X539326I971J1011D01*
G37*
G36*
G01X502515D02*
G03Y513711I277J-289D01*
G02X500573I-971J-1011D01*
G03Y514289I-277J289D01*
G02X502515I971J1011D01*
G37*
G36*
G01X465703D02*
G03Y513711I277J-289D01*
G02X463761I-971J-1011D01*
G03Y514289I-277J289D01*
G02X465703I971J1011D01*
G37*
G36*
G01X284995D02*
G03Y513711I277J-289D01*
G02X283053I-971J-1011D01*
G03Y514289I-277J289D01*
G02X284995I971J1011D01*
G37*
G36*
G01X248184D02*
G03Y513711I277J-289D01*
G02X246242I-971J-1011D01*
G03Y514289I-277J289D01*
G02X248184I971J1011D01*
G37*
G36*
G01X211373D02*
G03Y513711I277J-289D01*
G02X209431I-971J-1011D01*
G03Y514289I-277J289D01*
G02X211373I971J1011D01*
G37*
G36*
G01X174562D02*
G03Y513711I277J-289D01*
G02X172620I-971J-1011D01*
G03Y514289I-277J289D01*
G02X174562I971J1011D01*
G37*
G36*
G01X137751D02*
G03Y513711I277J-289D01*
G02X135809I-971J-1011D01*
G03Y514289I-277J289D01*
G02X137751I971J1011D01*
G37*
G36*
G01X1775235Y513745D02*
G03X1775789Y513710I295J270D01*
G02X1775660Y511695I906J-1070D01*
G03X1775106Y511730I-295J-270D01*
G02X1775235Y513745I-906J1070D01*
G37*
G36*
G01X1460011Y514043D02*
G03X1459949Y513438I227J-329D01*
G02X1458137Y513623I-1014J-968D01*
G03X1458199Y514228I-227J329D01*
G02X1460186Y516206I1014J968D01*
G03X1460740I277J288D01*
G02Y514186I973J-1010D01*
G03X1460186I-277J-288D01*
G02X1460011Y514043I-972J1011D01*
G37*
G36*
G01X730626Y510592D02*
G03X730049Y510570I-278J-288D01*
G02X729974Y512508I-1049J930D01*
G03X730551Y512530I278J288D01*
G02X730626Y510592I1049J-930D01*
G37*
G36*
G01X1509586Y509144D02*
X1506984D01*
G02X1506985Y512146I1J1501D01*
G01X1509586D01*
G02X1510889Y511390I0J-1501D01*
G02X1511086Y510655I-1304J-744D01*
G01Y510653D01*
X1511087Y510652D01*
G02X1509586Y509144I-1501J-7D01*
G37*
G36*
G01X1614027Y509290D02*
G03X1613473I-277J-288D01*
G02Y511310I-973J1010D01*
G03X1614027I277J288D01*
G02Y509290I973J-1010D01*
G37*
G36*
G01X1932053Y508490D02*
X1926853D01*
G02Y513914I0J2712D01*
G01X1932053D01*
G02X1934764Y511212I0J-2711D01*
G01Y511113D01*
X1934759Y511024D01*
G02X1932053Y508490I-2706J178D01*
G37*
G36*
G01X1888527D02*
X1886127D01*
G02Y513914I0J2712D01*
G01X1888527D01*
G02X1891238Y511212I0J-2711D01*
G01Y511113D01*
X1891233Y511024D01*
G02X1888527Y508490I-2706J178D01*
G37*
G36*
G01X1549271Y510789D02*
G03Y510211I277J-289D01*
G02X1547329I-971J-1011D01*
G03Y510789I-277J289D01*
G02X1549271I971J1011D01*
G37*
G36*
G01X721845Y510766D02*
G03X722033Y510244I365J-163D01*
G02X720134Y509558I-619J-1258D01*
G03X719946Y510080I-365J163D01*
G02X721845Y510766I619J1258D01*
G37*
G36*
G01X1500877Y506738D02*
X1498276D01*
G02X1498277Y509740I1J1501D01*
G01X1500877D01*
G02X1502378Y508249I0J-1501D01*
G01Y508154D01*
X1502369Y508070D01*
G02X1500877Y506738I-1492J169D01*
G37*
G36*
G01X1485692Y509502D02*
X1488293D01*
G02X1489794Y508010I0J-1501D01*
G01Y507915D01*
X1489785Y507831D01*
G02X1488293Y506498I-1492J168D01*
G01X1485692D01*
G02Y509502I0J1502D01*
G37*
G36*
G01X1481975Y506474D02*
X1479374D01*
G02X1479375Y509476I1J1501D01*
G01X1481975D01*
G02X1483476Y507985I0J-1501D01*
G01Y507890D01*
X1483467Y507806D01*
G02X1481975Y506474I-1492J169D01*
G37*
G36*
G01X115452Y509327D02*
G03Y508773I288J-277D01*
G02X113432I-1010J-973D01*
G03Y509327I-288J277D01*
G02X115452I1010J973D01*
G37*
G36*
G01X1844304Y507840D02*
G03X1843851Y507461I-54J-396D01*
G02X1842636Y508910I-1401J59D01*
G03X1843089Y509289I54J396D01*
G02X1844304Y507840I1401J-59D01*
G37*
G36*
G01X34223Y509289D02*
G03X34058Y509518I-197J32D01*
G02X33490Y509735I241J1482D01*
G03X32964Y509651I-216J-337D01*
G02X32610Y511865I-1164J949D01*
G03X33136Y511949I216J337D01*
G02X35288Y512131I1164J-949D01*
G03X35856Y512173I263J301D01*
G02X38495Y511340I1144J-973D01*
G03X38958Y510982I399J37D01*
G02X39428Y508015I241J-1483D01*
G03X39092Y507574I61J-395D01*
G02X36111Y507205I-1492J-174D01*
G03X35713Y507553I-397J-52D01*
G02X34223Y509289I-6J1502D01*
G37*
G36*
G01X1556448Y508744D02*
G03Y508190I288J-277D01*
G02X1554428I-1010J-973D01*
G03Y508744I-288J277D01*
G02X1556448I1010J973D01*
G37*
G36*
G01X1543446Y508589D02*
G03Y508011I277J-289D01*
G02X1541504I-971J-1011D01*
G03Y508589I-277J289D01*
G02X1543446I971J1011D01*
G37*
G36*
G01X764960Y507567D02*
G03Y507013I288J-277D01*
G02X762940I-1010J-973D01*
G03Y507567I-288J277D01*
G02Y509513I1010J973D01*
G03Y510067I-288J277D01*
G02X764960I1010J973D01*
G03Y509513I288J-277D01*
G02Y507567I-1010J-973D01*
G37*
G36*
G01X703409Y505754D02*
G03X702898Y505399I-112J-384D01*
G02X701891Y506846I-1398J101D01*
G03X702402Y507201I112J384D01*
G02X703409Y505754I1398J-101D01*
G37*
G36*
G01X712207Y504510D02*
G03X711639I-284J-282D01*
G02X709492Y504695I-997J986D01*
G03X708872Y504741I-329J-228D01*
G02X709001Y506501I-1022J960D01*
G03X709621Y506455I329J228D01*
G02X711636Y506486I1022J-959D01*
G03X712204I284J282D01*
G02X714199Y506484I997J-986D01*
G03X714798Y506517I285J280D01*
G02X714901Y504666I1102J-867D01*
G03X714302Y504633I-285J-280D01*
G02X712207Y504510I-1102J867D01*
G37*
G36*
G01X1650037Y503846D02*
G03X1649482Y503744I-226J-330D01*
G02X1648998Y505777I-1152J800D01*
G03X1649539Y505936I191J351D01*
G02X1650037Y503846I1405J-770D01*
G37*
G36*
G01X1568662Y504677D02*
G03X1569135Y505096I74J393D01*
G02X1570261Y502751I3463J220D01*
G03X1569638Y502643I-270J-296D01*
G02X1568662Y504677I-1238J657D01*
G37*
G36*
G01X1508625Y504540D02*
X1511126D01*
G02X1512628Y503048I0J-1502D01*
G01Y503038D01*
G02X1511126Y501536I-1502J0D01*
G01X1508625D01*
G02Y504540I0J1502D01*
G37*
G36*
G01X1549310Y503027D02*
G03Y502473I288J-277D01*
G02X1547290I-1010J-973D01*
G03Y503027I-288J277D01*
G02X1549310I1010J973D01*
G37*
G36*
G01X1528002Y503810D02*
Y501300D01*
G02X1524998I-1502J0D01*
G01Y503801D01*
G02X1528002Y503810I1502J-1D01*
G37*
G36*
G01X675626Y500292D02*
G03X675049Y500270I-278J-288D01*
G02X672987Y500231I-1049J930D01*
G03X672432Y500253I-289J-277D01*
G02X672513Y502269I-932J1047D01*
G03X673068Y502247I289J277D01*
G02X674974Y502208I932J-1047D01*
G03X675551Y502230I278J288D01*
G02X675626Y500292I1049J-930D01*
G37*
G36*
G01X1738703Y502186D02*
G03X1738508Y501612I149J-371D01*
G02X1736777Y502201I-1208J-712D01*
G03X1736972Y502775I-149J371D01*
G02X1738703Y502186I1208J712D01*
G37*
G36*
G01X1874950Y501383D02*
G03X1875469Y501146I376J136D01*
G02X1874655Y499359I504J-1308D01*
G03X1874136Y499596I-376J-136D01*
G02X1874950Y501383I-504J1308D01*
G37*
G36*
G01X648006Y500173D02*
G03X647601Y499757I-5J-400D01*
G02X646219Y501102I-1401J-57D01*
G03X646624Y501518I5J400D01*
G02X648006Y500173I1401J57D01*
G37*
G36*
G01X1269329Y500380D02*
G03X1268968Y499918I34J-398D01*
G02X1267464Y501091I-1384J-224D01*
G03X1267825Y501553I-34J398D01*
G02X1269329Y500380I1384J224D01*
G37*
G36*
G01X745051Y498664D02*
G03X744497I-277J-288D01*
G02X742514Y500647I-973J1010D01*
G03Y501201I-288J277D01*
G02X744497Y503184I1010J973D01*
G03X745051I277J288D01*
G02X746997I973J-1010D01*
G03X747551I277J288D01*
G02X749401Y501080I973J-1010D01*
G03Y500768I125J-156D01*
G02X749485Y500695I-877J-1094D01*
G03X749786Y500725I138J145D01*
G02X750099Y498788I1145J-809D01*
G03X749564Y498734I-238J-322D01*
G02X747551Y498664I-1040J940D01*
G03X746997I-277J-288D01*
G02X745051I-973J1010D01*
G37*
G36*
G01X1532695Y501067D02*
G03Y500513I288J-277D01*
G02X1530675I-1010J-973D01*
G03Y501067I-288J277D01*
G02X1532695I1010J973D01*
G37*
G36*
G01X1556520Y501002D02*
G03Y500448I288J-277D01*
G02X1554500I-1010J-973D01*
G03Y501002I-288J277D01*
G02X1556520I1010J973D01*
G37*
G36*
G01X1543485Y500927D02*
G03Y500373I288J-277D01*
G02X1541465I-1010J-973D01*
G03Y500927I-288J277D01*
G02X1543485I1010J973D01*
G37*
G36*
G01X710341Y498494D02*
G03X709755Y498476I-285J-281D01*
G02X709698Y500384I-1055J923D01*
G03X710284Y500402I285J281D01*
G02X710341Y498494I1055J-923D01*
G37*
G36*
G01X1336011Y498417D02*
G03X1335389I-311J-252D01*
G02Y500183I-1089J883D01*
G03X1336011I311J252D01*
G02Y498417I1089J-883D01*
G37*
G36*
G01X1705601Y500560D02*
G03X1705612Y499982I282J-284D01*
G02X1703453Y497902I-1015J-1107D01*
G03X1702908Y497962I-304J-259D01*
G02X1700871Y500148I-904J1200D01*
G03X1700844Y500702I-301J263D01*
G02X1702995Y502794I1030J1093D01*
G03X1703557Y502759I299J266D01*
G02X1705601Y500560I986J-1133D01*
G37*
G36*
G01X-17651Y498430D02*
G03X-17666Y499031I-271J294D01*
G02X-15815Y499076I900J1075D01*
G03X-15800Y498475I271J-294D01*
G02X-17651Y498430I-900J-1075D01*
G37*
G36*
G01X1673481Y498725D02*
G03X1673416Y498165I250J-313D01*
G02X1671438Y498395I-1103J-865D01*
G03X1671503Y498955I-250J313D01*
G02X1673481Y498725I1103J865D01*
G37*
G36*
G01X113060Y499007D02*
G03X113164Y498418I314J-248D01*
G02X111328Y498095I-737J-1193D01*
G03X111224Y498684I-314J248D01*
G02X113060Y499007I737J1193D01*
G37*
G36*
G01X1758575Y494894D02*
X1753575D01*
G02Y497918I0J1512D01*
G01X1758575D01*
G02X1760086Y496416I-1J-1512D01*
G01Y496321D01*
X1760077Y496237D01*
G02X1758575Y494894I-1502J169D01*
G37*
G36*
G01X1748125Y494888D02*
X1743124D01*
G02X1743125Y497912I1J1512D01*
G01X1748125D01*
G02X1749636Y496410I-1J-1512D01*
G01Y496315D01*
X1749627Y496231D01*
G02X1748125Y494888I-1502J168D01*
G37*
G36*
G01X1157223Y495156D02*
G03Y494578I277J-289D01*
G02X1155281I-971J-1011D01*
G03Y495156I-277J289D01*
G02X1157223I971J1011D01*
G37*
G36*
G01X507615D02*
G03Y494578I277J-289D01*
G02X505673I-971J-1011D01*
G03Y495156I-277J289D01*
G02X507615I971J1011D01*
G37*
G36*
G01X1193992Y495159D02*
G03Y494559I265J-300D01*
G02X1192134I-929J-1050D01*
G03Y495159I-265J300D01*
G02X1193992I929J1050D01*
G37*
G36*
G01X544384D02*
G03Y494559I265J-300D01*
G02X542526I-929J-1050D01*
G03Y495159I-265J300D01*
G02X544384I929J1050D01*
G37*
G36*
G01X1152097Y495117D02*
G03Y494517I265J-300D01*
G02X1150239I-929J-1050D01*
G03Y495117I-265J300D01*
G02X1152097I929J1050D01*
G37*
G36*
G01X502489D02*
G03Y494517I265J-300D01*
G02X500631I-929J-1050D01*
G03Y495117I-265J300D01*
G02X502489I929J1050D01*
G37*
G36*
G01X939703Y494933D02*
G03Y494355I277J-289D01*
G02X937761I-971J-1011D01*
G03Y494933I-277J289D01*
G02X939703I971J1011D01*
G37*
G36*
G01X934618D02*
G03Y494355I277J-289D01*
G02X932676I-971J-1011D01*
G03Y494933I-277J289D01*
G02X934618I971J1011D01*
G37*
G36*
G01X290095D02*
G03Y494355I277J-289D01*
G02X288153I-971J-1011D01*
G03Y494933I-277J289D01*
G02X290095I971J1011D01*
G37*
G36*
G01X285010D02*
G03Y494355I277J-289D01*
G02X283068I-971J-1011D01*
G03Y494933I-277J289D01*
G02X285010I971J1011D01*
G37*
G36*
G01X902892Y494803D02*
G03Y494225I277J-289D01*
G02X900950I-971J-1011D01*
G03Y494803I-277J289D01*
G02X902892I971J1011D01*
G37*
G36*
G01X253284D02*
G03Y494225I277J-289D01*
G02X251342I-971J-1011D01*
G03Y494803I-277J289D01*
G02X253284I971J1011D01*
G37*
G36*
G01X1188907Y494859D02*
G03Y494259I265J-300D01*
G02X1187049I-929J-1050D01*
G03Y494859I-265J300D01*
G02X1188907I929J1050D01*
G37*
G36*
G01X897765D02*
G03Y494259I265J-300D01*
G02X895907I-929J-1050D01*
G03Y494859I-265J300D01*
G02X897765I929J1050D01*
G37*
G36*
G01X539299D02*
G03Y494259I265J-300D01*
G02X537441I-929J-1050D01*
G03Y494859I-265J300D01*
G02X539299I929J1050D01*
G37*
G36*
G01X248157D02*
G03Y494259I265J-300D01*
G02X246299I-929J-1050D01*
G03Y494859I-265J300D01*
G02X248157I929J1050D01*
G37*
G36*
G01X1296341Y494226D02*
G03X1296927Y494180I314J248D01*
G02X1296777Y492283I951J-1030D01*
G03X1296191Y492329I-314J-248D01*
G02X1296341Y494226I-951J1030D01*
G37*
G36*
G01X694614Y493330D02*
G03Y492776I288J-277D01*
G02X692594I-1010J-973D01*
G03Y493330I-288J277D01*
G02X694614I1010J973D01*
G37*
G36*
G01X690835Y493282D02*
G03Y492728I288J-277D01*
G02X688815I-1010J-973D01*
G03Y493282I-288J277D01*
G02X690835I1010J973D01*
G37*
G36*
G01X88867Y500506D02*
G03X89413I273J292D01*
G02X91467I1027J-1096D01*
G03X92013I273J292D01*
G02X94067I1027J-1096D01*
G03X94613I273J292D01*
G02X96667I1027J-1096D01*
G03X97213I273J292D01*
G02X99336Y498383I1027J-1096D01*
G03Y497837I292J-273D01*
G02X97093Y495841I-1096J-1027D01*
G03X96787I-153J-130D01*
G02X96668Y495715I-1150J966D01*
G03X96684Y495410I137J-146D01*
G02X94678Y493190I-907J-1197D01*
G03X94092Y493189I-293J-273D01*
G02X91963Y493114I-1102J1021D01*
G03X91417I-273J-292D01*
G02X91359Y493063I-1020J1102D01*
G03Y492757I130J-153D01*
G02X89363Y490514I-969J-1147D01*
G03X88817I-273J-292D01*
G02X86694Y492637I-1027J1096D01*
G03Y493183I-292J273D01*
G02X86714Y495258I1096J1027D01*
G03X86724Y495804I-287J278D01*
G02X86744Y497837I1116J1006D01*
G03Y498383I-292J273D01*
G02X88867Y500506I1096J1027D01*
G37*
G36*
G01X1842089Y490529D02*
G03X1841511I-289J-277D01*
G02X1839529Y492511I-1011J971D01*
G03Y493089I-277J289D01*
G02X1841511Y495071I971J1011D01*
G03X1842089I289J277D01*
G02X1844071Y493089I1011J-971D01*
G03Y492511I277J-289D01*
G02X1842089Y490529I-971J-1011D01*
G37*
G36*
G01X1249880Y490086D02*
G03X1249721Y489554I196J-348D01*
G02X1247787Y490135I-1247J-641D01*
G03X1247946Y490667I-196J348D01*
G02X1249880Y490086I1247J641D01*
G37*
G36*
G01X1819124Y490442D02*
X1824125D01*
G02X1825636Y488940I-1J-1512D01*
G01Y488845D01*
X1825627Y488761D01*
G02X1824125Y487418I-1502J169D01*
G01X1819124D01*
G02Y490442I0J1512D01*
G37*
G36*
G01X1796124D02*
X1801125D01*
G02X1802636Y488940I-1J-1512D01*
G01Y488845D01*
X1802627Y488761D01*
G02X1801125Y487418I-1502J169D01*
G01X1796124D01*
G02Y490442I0J1512D01*
G37*
G36*
G01X1784524D02*
X1789525D01*
G02X1791036Y488940I-1J-1512D01*
G01Y488845D01*
X1791027Y488761D01*
G02X1789525Y487418I-1502J169D01*
G01X1784524D01*
G02Y490442I0J1512D01*
G37*
G36*
G01X1811975Y487218D02*
X1806975D01*
G02Y490242I0J1512D01*
G01X1811975D01*
G02X1813486Y488740I-1J-1512D01*
G01Y488645D01*
X1813477Y488561D01*
G02X1811975Y487218I-1502J169D01*
G37*
G36*
G01X1754300Y486344D02*
X1749299D01*
G02X1749300Y489366I1J1511D01*
G01X1754300D01*
G02X1755812Y487865I0J-1512D01*
G01Y487770D01*
X1755802Y487686D01*
G02X1754300Y486344I-1502J170D01*
G37*
G36*
G01X1741900Y486244D02*
X1736899D01*
G02X1736900Y489266I1J1511D01*
G01X1741900D01*
G02X1743412Y487765I0J-1512D01*
G01Y487670D01*
X1743402Y487586D01*
G02X1741900Y486244I-1502J170D01*
G37*
G36*
G01X1770325Y485844D02*
X1765324D01*
G02X1765325Y488866I1J1511D01*
G01X1770325D01*
G02X1771836Y487365I0J-1511D01*
G01Y487270D01*
X1771827Y487186D01*
G02X1770325Y485844I-1502J169D01*
G37*
G36*
G01X1450607Y488218D02*
G03X1451188Y488206I296J268D01*
G02X1451149Y486281I1000J-983D01*
G03X1450568Y486293I-296J-268D01*
G02X1450607Y488218I-1000J983D01*
G37*
G36*
G01X721807Y486893D02*
G03X721585Y486360I145J-373D01*
G02X719794Y487107I-1285J-560D01*
G03X720016Y487640I-145J373D01*
G02X721934Y489451I1285J560D01*
G03X722487Y489661I181J357D01*
G02X723159Y487897I1305J-513D01*
G03X722606Y487687I-181J-357D01*
G02X721807Y486893I-1304J514D01*
G37*
G36*
G01X676752Y484669D02*
G03X676148Y484662I-299J-266D01*
G02X676128Y486501I-1068J908D01*
G03X676732Y486508I299J266D01*
G02X678732Y486647I1068J-908D01*
G03X679287Y486669I266J299D01*
G02X679368Y484653I1013J-969D01*
G03X678813Y484631I-266J-299D01*
G02X676752Y484669I-1013J969D01*
G37*
G36*
G01X1841471Y486239D02*
G03Y485661I277J-289D01*
G02X1839529I-971J-1011D01*
G03Y486239I-277J289D01*
G02X1841471I971J1011D01*
G37*
G36*
G01X610478Y485035D02*
G03X611039Y485021I288J278D01*
G02X610992Y483025I961J-1021D01*
G03X610431Y483039I-288J-278D01*
G02X610478Y485035I-961J1021D01*
G37*
G36*
G01X709168Y482570D02*
G03X708585Y482538I-277J-289D01*
G02X708480Y484452I-1074J901D01*
G03X709063Y484484I277J289D01*
G02X709168Y482570I1074J-901D01*
G37*
G36*
G01X1652882Y483774D02*
G03X1652896Y483210I290J-275D01*
G02X1650911Y483164I-970J-1013D01*
G03X1650897Y483728I-290J275D01*
G02X1652882Y483774I970J1013D01*
G37*
G36*
G01X1616627Y480390D02*
G03X1616073I-277J-288D01*
G02Y482410I-973J1010D01*
G03X1616627I277J288D01*
G02Y480390I973J-1010D01*
G37*
G36*
G01X1672021Y482589D02*
G03Y482011I277J-289D01*
G02X1670079I-971J-1011D01*
G03Y482589I-277J289D01*
G02X1672021I971J1011D01*
G37*
G36*
G01X606268Y482376D02*
G03X606278Y481843I303J-261D01*
G02X604187Y481806I-1029J-952D01*
G03X604177Y482339I-303J261D01*
G02X606268Y482376I1029J952D01*
G37*
G36*
G01X1291510Y481727D02*
G03Y481173I288J-277D01*
G02X1289490I-1010J-973D01*
G03Y481727I-288J277D01*
G02X1291510I1010J973D01*
G37*
G36*
G01X1794975Y477788D02*
X1789974D01*
G02X1789975Y480812I1J1512D01*
G01X1794975D01*
G02X1796486Y479310I-1J-1512D01*
G01Y479215D01*
X1796477Y479131D01*
G02X1794975Y477788I-1502J168D01*
G37*
G36*
G01X658794Y478143D02*
G03X658229Y478136I-279J-287D01*
G02X658203Y480122I-1002J980D01*
G03X658768Y480129I279J287D01*
G02X660708Y480191I1002J-980D01*
G03X661243I267J297D01*
G02Y478107I938J-1042D01*
G03X660708I-268J-297D01*
G02X658794Y478143I-938J1042D01*
G37*
G36*
G01X1817375Y476808D02*
X1812375D01*
G02Y479832I0J1512D01*
G01X1817375D01*
G02X1818886Y478330I-1J-1512D01*
G01Y478235D01*
X1818877Y478151D01*
G02X1817375Y476808I-1502J169D01*
G37*
G36*
G01X1829967Y475416D02*
X1825297D01*
G02Y478438I0J1511D01*
G01X1829967D01*
G02X1831478Y476937I0J-1511D01*
G01Y476842D01*
X1831469Y476758D01*
G02X1829967Y475416I-1502J169D01*
G37*
G36*
G01X1766700Y474144D02*
X1761699D01*
G02X1761700Y477166I1J1511D01*
G01X1766700D01*
G02X1768212Y475665I0J-1512D01*
G01Y475570D01*
X1768202Y475486D01*
G02X1766700Y474144I-1502J170D01*
G37*
G36*
G01X15473Y476510D02*
G03X16027I277J288D01*
G02Y474490I973J-1010D01*
G03X15473I-277J-288D01*
G02X13549Y474470I-973J1010D01*
G03X12988Y474451I-271J-294D01*
G02X12923Y476447I-1016J966D01*
G03X13484Y476466I271J294D01*
G02X15473Y476510I1016J-966D01*
G37*
G36*
G01X1779300Y473544D02*
X1774299D01*
G02X1774300Y476566I1J1511D01*
G01X1779300D01*
G02X1780812Y475065I0J-1512D01*
G01Y474970D01*
X1780802Y474886D01*
G02X1779300Y473544I-1502J170D01*
G37*
G36*
G01X1806525Y472444D02*
X1801524D01*
G02X1801525Y475466I1J1511D01*
G01X1806525D01*
G02X1808036Y473965I0J-1511D01*
G01Y473870D01*
X1808027Y473786D01*
G02X1806525Y472444I-1502J169D01*
G37*
G36*
G01X-13140Y474769D02*
G03X-12540I300J265D01*
G02Y472911I1050J-929D01*
G03X-13140I-300J-265D01*
G02Y474769I-1050J929D01*
G37*
G36*
G01X1679576Y472270D02*
G03X1679022Y472244I-263J-301D01*
G02X1678925Y474260I-1021J961D01*
G03X1679479Y474286I263J301D01*
G02X1679576Y472270I1021J-961D01*
G37*
G36*
G01X1895789Y469229D02*
G03X1895211I-289J-277D01*
G02X1893117Y471090I-1011J971D01*
G03X1893095Y471623I-309J254D01*
G02X1895111Y473571I1005J977D01*
G03X1895689I289J277D01*
G02X1897634Y473646I1011J-971D01*
G03X1898166I266J298D01*
G02X1900111Y473571I934J-1046D01*
G03X1900689I289J277D01*
G02X1902632Y473647I1011J-971D01*
G03X1903187Y473669I266J299D01*
G02X1905283Y471810I1013J-969D01*
G03X1905305Y471277I309J-254D01*
G02X1903368Y469253I-1005J-977D01*
G03X1902813Y469231I-266J-299D01*
G02X1900789Y469229I-1013J969D01*
G03X1900211I-289J-277D01*
G02X1898266Y469154I-1011J971D01*
G03X1897734I-266J-298D01*
G02X1895789Y469229I-934J1046D01*
G37*
G36*
G01X1634422Y471660D02*
G03X1634365Y471124I265J-299D01*
G02X1632012Y471373I-1290J-950D01*
G03X1632069Y471909I-265J299D01*
G02X1634422Y471660I1290J950D01*
G37*
G36*
G01X1463389Y464529D02*
G03X1462811I-289J-277D01*
G02Y466471I-1011J971D01*
G03X1463389I289J277D01*
G02Y464529I1011J-971D01*
G37*
G36*
G01X1455589D02*
G03X1455011I-289J-277D01*
G02Y466471I-1011J971D01*
G03X1455589I289J277D01*
G02Y464529I1011J-971D01*
G37*
G36*
G01X1667496Y465448D02*
G03X1667236Y465939I-384J111D01*
G02X1666657Y466306I438J1332D01*
G03X1666074Y466303I-290J-276D01*
G02X1666064Y468222I-1027J954D01*
G03X1666647Y468225I290J276D01*
G02X1669021Y466883I1027J-954D01*
G03X1669281Y466392I384J-111D01*
G02X1667496Y465448I-438J-1332D01*
G37*
G36*
G01X1322493Y464943D02*
G03X1323080Y464737I377J134D01*
G02X1322494Y463074I735J-1194D01*
G03X1321907Y463280I-377J-134D01*
G02X1322493Y464943I-735J1194D01*
G37*
G36*
G01X1343133Y462606D02*
G03X1342564Y462583I-273J-292D01*
G02X1342485Y464552I-1036J945D01*
G03X1343054Y464575I273J292D01*
G02X1345126I1036J-945D01*
G03X1345714Y464571I296J269D01*
G02X1345703Y462670I1025J-956D01*
G03X1345115Y462674I-296J-269D01*
G02X1343133Y462606I-1025J956D01*
G37*
G36*
G01X1624247Y462902D02*
G03X1624014Y462389I142J-374D01*
G02X1622202Y463211I-1314J-489D01*
G03X1622435Y463724I-142J374D01*
G02X1624247Y462902I1314J489D01*
G37*
G36*
G01X1586502Y459200D02*
G03X1585948I-277J-288D01*
G02X1583863Y459356I-973J1010D01*
G03X1583247Y459378I-317J-244D01*
G02X1580798Y460293I-1047J932D01*
G03X1580392Y460688I-400J-5D01*
G02X1581772Y462107I-22J1402D01*
G03X1582178Y461712I400J5D01*
G02X1582413Y461696I23J-1402D01*
G03X1582857Y462206I61J395D01*
G02X1585455Y461984I1343J404D01*
G03X1585627Y461451I358J-179D01*
G02X1585948Y461220I-650J-1242D01*
G03X1586502I277J288D01*
G02Y459200I973J-1010D01*
G37*
G36*
G01X1463389Y458829D02*
G03X1462811I-289J-277D01*
G02Y460771I-1011J971D01*
G03X1463389I289J277D01*
G02Y458829I1011J-971D01*
G37*
G36*
G01X1455589D02*
G03X1455011I-289J-277D01*
G02Y460771I-1011J971D01*
G03X1455589I289J277D01*
G02Y458829I1011J-971D01*
G37*
G36*
G01X1640942Y458579D02*
G03X1640920Y457958I241J-319D01*
G02X1639158Y458021I-920J-1058D01*
G03X1639180Y458642I-241J319D01*
G02X1640942Y458579I920J1058D01*
G37*
G36*
G01X1685410Y458414D02*
G03Y457839I279J-288D01*
G02X1683460I-975J-1007D01*
G03Y458414I-279J287D01*
G02X1685410I975J1007D01*
G37*
G36*
G01X1676848Y457738D02*
G03X1676782Y457142I230J-327D01*
G02X1674937Y457346I-1038J-942D01*
G03X1675003Y457942I-230J327D01*
G02X1676848Y457738I1038J942D01*
G37*
G36*
G01X1529333Y455957D02*
G03X1529260Y455398I245J-316D01*
G02X1527289Y455655I-1113J-852D01*
G03X1527362Y456214I-245J316D01*
G02X1529333Y455957I1113J852D01*
G37*
G36*
G01X1463389Y453129D02*
G03X1462811I-289J-277D01*
G02Y455071I-1011J971D01*
G03X1463389I289J277D01*
G02Y453129I1011J-971D01*
G37*
G36*
G01X1455589D02*
G03X1455011I-289J-277D01*
G02Y455071I-1011J971D01*
G03X1455589I289J277D01*
G02Y453129I1011J-971D01*
G37*
G36*
G01X1411986Y457571D02*
Y453476D01*
X1411977Y453392D01*
G02X1408964Y453561I-1502J169D01*
G01Y457561D01*
G02X1411986Y457571I1511J0D01*
G37*
G36*
G01X1404286D02*
Y453476D01*
X1404277Y453392D01*
G02X1401264Y453561I-1502J169D01*
G01Y457561D01*
G02X1404286Y457571I1511J0D01*
G37*
G36*
G01X1396886D02*
Y453476D01*
X1396877Y453392D01*
G02X1393864Y453561I-1502J169D01*
G01Y457562D01*
G02X1396886Y457571I1511J-1D01*
G37*
G36*
G01X1589693Y453068D02*
G03X1590295Y453064I303J261D01*
G02X1590283Y451217I1049J-930D01*
G03X1589681Y451221I-303J-261D01*
G02X1587504Y451319I-1049J930D01*
G03X1586902Y451367I-322J-238D01*
G02X1584927Y451378I-982J1001D01*
G03X1584325Y451338I-284J-282D01*
G02X1584201Y453175I-1117J847D01*
G03X1584803Y453215I284J282D01*
G02X1587048Y453200I1117J-847D01*
G03X1587650Y453152I322J238D01*
G02X1589693Y453068I982J-1001D01*
G37*
G36*
G01X1620175Y453672D02*
G03X1620664Y453361I393J77D01*
G02X1619625Y451728I336J-1361D01*
G03X1619136Y452039I-393J-77D01*
G02X1620175Y453672I-336J1361D01*
G37*
G36*
G01X1662542Y452789D02*
G03X1662548Y452234I291J-274D01*
G02X1660529Y452213I-999J-983D01*
G03X1660523Y452768I-291J274D01*
G02X1660492Y454703I999J984D01*
G03X1660481Y455257I-294J271D01*
G02X1662500Y455299I989J994D01*
G03X1662511Y454745I294J-271D01*
G02X1662542Y452789I-989J-994D01*
G37*
G36*
G01X1867886Y451591D02*
G03X1867450Y451172I-36J-398D01*
G02X1866179Y452496I-1400J-72D01*
G03X1866615Y452915I36J398D01*
G02X1869093Y453883I1400J72D01*
G03X1869715Y453891I308J256D01*
G02X1869737Y452126I1100J-869D01*
G03X1869115Y452118I-308J-256D01*
G02X1867886Y451591I-1100J869D01*
G37*
G36*
G01X1836495Y449088D02*
X1831494D01*
G02X1831495Y452112I1J1512D01*
G01X1836495D01*
G02X1838006Y450610I-1J-1512D01*
G01Y450515D01*
X1837997Y450431D01*
G02X1836495Y449088I-1502J168D01*
G37*
G36*
G01X1818760Y451920D02*
X1823760D01*
G02X1825272Y450418I0J-1512D01*
G01Y450323D01*
X1825262Y450239D01*
G02X1823760Y448896I-1502J169D01*
G01X1818760D01*
G02Y451920I0J1512D01*
G37*
G36*
G01X1811161Y448896D02*
X1806161D01*
G02Y451920I0J1512D01*
G01X1811161D01*
G02X1812672Y450418I-1J-1512D01*
G01Y450323D01*
X1812663Y450239D01*
G02X1811161Y448896I-1502J169D01*
G37*
G36*
G01X1793562Y451920D02*
X1798563D01*
G02X1800074Y450418I-1J-1512D01*
G01Y450323D01*
X1800065Y450239D01*
G02X1798563Y448896I-1502J169D01*
G01X1793562D01*
G02Y451920I1J1512D01*
G37*
G36*
G01X1780963D02*
X1785964D01*
G02X1787476Y450418I0J-1512D01*
G01Y450323D01*
X1787466Y450239D01*
G02X1785964Y448896I-1502J168D01*
G01X1780963D01*
G02Y451920I0J1512D01*
G37*
G36*
G01X1768366D02*
X1773366D01*
G02X1774878Y450418I0J-1512D01*
G01Y450323D01*
X1774868Y450239D01*
G02X1773366Y448896I-1502J169D01*
G01X1768366D01*
G02Y451920I0J1512D01*
G37*
G36*
G01X1760767Y448896D02*
X1755767D01*
G02Y451920I0J1512D01*
G01X1760767D01*
G02X1762278Y450418I-1J-1512D01*
G01Y450323D01*
X1762269Y450239D01*
G02X1760767Y448896I-1502J169D01*
G37*
G36*
G01X1748169D02*
X1743169D01*
G02Y451920I0J1512D01*
G01X1748169D01*
G02X1749680Y450418I-1J-1512D01*
G01Y450323D01*
X1749671Y450239D01*
G02X1748169Y448896I-1502J169D01*
G37*
G36*
G01X1470989Y449026D02*
G03X1470411I-289J-277D01*
G02Y450968I-1011J971D01*
G03X1470989I289J277D01*
G02Y449026I1011J-971D01*
G37*
G36*
G01X1463189D02*
G03X1462611I-289J-277D01*
G02Y450968I-1011J971D01*
G03X1463189I289J277D01*
G02Y449026I1011J-971D01*
G37*
G36*
G01X1631268Y451086D02*
G03X1631263Y450513I277J-289D01*
G02X1629308Y450531I-987J-996D01*
G03X1629313Y451104I-277J289D01*
G02X1629282Y453064I987J996D01*
G03X1629260Y453635I-291J275D01*
G02X1629190Y455648I940J1040D01*
G03Y456202I-288J277D01*
G02X1631210I1010J973D01*
G03Y455648I288J-277D01*
G02X1631218Y453711I-1010J-973D01*
G03X1631240Y453140I291J-275D01*
G02X1631268Y451086I-940J-1040D01*
G37*
G36*
G01X1682201Y450789D02*
G03X1682187Y450234I281J-285D01*
G02X1680168Y450283I-1033J-948D01*
G03X1680182Y450838I-281J285D01*
G02X1682201Y450789I1033J948D01*
G37*
G36*
G01X1873831Y449539D02*
G03Y448961I277J-289D01*
G02X1871889I-971J-1011D01*
G03Y449539I-277J289D01*
G02X1873831I971J1011D01*
G37*
G36*
G01X1647500Y449140D02*
G03X1647513Y448585I294J-271D01*
G02X1645494Y448540I-988J-995D01*
G03X1645481Y449095I-294J271D01*
G02X1645452Y451055I988J995D01*
G03X1645448Y451610I-290J275D01*
G02X1647468Y451625I1003J980D01*
G03X1647472Y451070I290J-275D01*
G02X1647500Y449140I-1003J-980D01*
G37*
G36*
G01X1677288Y448795D02*
G03X1677284Y448229I281J-285D01*
G02X1675303Y448243I-998J-985D01*
G03X1675307Y448809I-281J285D01*
G02X1677288Y448795I998J985D01*
G37*
G36*
G01X1674076Y447548D02*
G03X1674075Y446993I288J-278D01*
G02X1672056Y446996I-1011J-971D01*
G03X1672057Y447551I-288J278D01*
G02X1674076Y447548I1011J971D01*
G37*
G36*
G01X-616Y454932D02*
G03X-328Y455438I-94J389D01*
G02X2535Y455410I1436J441D01*
G03X2794Y454904I380J-125D01*
G02X3435Y452446I-455J-1431D01*
G03Y451900I292J-273D01*
G02Y449846I-1096J-1027D01*
G03Y449300I292J-273D01*
G02Y447246I-1096J-1027D01*
G03Y446700I292J-273D01*
G02X1312Y444577I-1096J-1027D01*
G03X766I-273J-292D01*
G02X-1357Y446700I-1027J1096D01*
G03Y447246I-292J273D01*
G02Y449300I1096J1027D01*
G03Y449846I-292J273D01*
G02Y451900I1096J1027D01*
G03Y452446I-292J273D01*
G02X-616Y454932I1096J1027D01*
G37*
G36*
G01X6770Y447971D02*
G03X7316I273J292D01*
G02X9705Y447508I1027J-1096D01*
G03X10297Y447349I363J169D01*
G02X9857Y445552I803J-1149D01*
G03X9258Y445684I-355J-185D01*
G02X7316Y445779I-915J1191D01*
G03X6770I-273J-292D01*
G02X6712Y445728I-1020J1102D01*
G03Y445422I130J-153D01*
G02X4647Y445302I-969J-1147D01*
G03Y445848I-292J273D01*
G02X6770Y447971I1096J1027D01*
G37*
G36*
G01X1670826Y445480D02*
G03Y444926I288J-277D01*
G02X1668806I-1010J-973D01*
G03Y445480I-288J277D01*
G02Y447426I1010J973D01*
G03Y447980I-288J277D01*
G02X1670826I1010J973D01*
G03Y447426I288J-277D01*
G02Y445480I-1010J-973D01*
G37*
G36*
G01X1718140Y442709D02*
G03X1717978Y443287I-335J218D01*
G02X1717595Y443559I609J1263D01*
G03X1717029I-283J-282D01*
G02Y445541I-992J991D01*
G03X1717595I283J282D01*
G02X1719764Y443788I992J-991D01*
G03X1719926Y443210I335J-218D01*
G02X1718140Y442709I-609J-1263D01*
G37*
G36*
G01X10786Y443296D02*
X15787D01*
G02X17298Y441795I0J-1512D01*
G01Y441700D01*
X17288Y441616D01*
G02X15786Y440274I-1502J170D01*
G01X10786D01*
G02Y443296I0J1511D01*
G37*
G36*
G01X1413300Y442491D02*
G03X1413324Y441870I264J-301D01*
G02X1411559Y441802I-841J-1122D01*
G03X1411535Y442423I-264J301D01*
G02X1413300Y442491I841J1122D01*
G37*
G36*
G01X1589900Y441497D02*
G03X1590472Y441480I294J271D01*
G02X1590416Y439521I974J-1008D01*
G03X1589844Y439538I-294J-271D01*
G02X1589900Y441497I-974J1008D01*
G37*
G36*
G01X1613207Y441666D02*
G03X1613223Y441103I292J-273D01*
G02X1611232Y441045I-967J-1015D01*
G03X1611216Y441608I-292J273D01*
G02X1613207Y441666I967J1015D01*
G37*
G36*
G01X22936Y444354D02*
G02X25958Y444364I1511J0D01*
G01Y439354D01*
X25959D01*
X25958Y439269D01*
X25949Y439185D01*
G02X22936Y439354I-1502J169D01*
G01Y444354D01*
G37*
G36*
G01X750525Y439327D02*
G03X749900Y438975I-226J-330D01*
G02X747401Y439770I-1400J-75D01*
G03X747278Y440369I-314J248D01*
G02X748440Y442914I672J1231D01*
G03X748971Y443205I140J375D01*
G02X750525Y439327I3670J-780D01*
G37*
G36*
G01X1409123Y439924D02*
G03Y439309I257J-307D01*
G02X1407327I-898J-1076D01*
G03Y439924I-257J307D01*
G02X1409123I898J1076D01*
G37*
G36*
G01X1506427Y436187D02*
G03X1506443Y435632I296J-269D01*
G02X1504427Y435576I-981J-1002D01*
G03X1504411Y436131I-296J269D01*
G02X1506427Y436187I981J1002D01*
G37*
G36*
G01X1640510Y434727D02*
G03Y434173I288J-277D01*
G02X1638490I-1010J-973D01*
G03Y434727I-288J277D01*
G02X1640510I1010J973D01*
G37*
G36*
G01X1461099Y431902D02*
G03X1460510I-294J-271D01*
G02Y433800I-1032J949D01*
G03X1461099I295J271D01*
G02Y431902I1032J-949D01*
G37*
G36*
G01X1468386Y433869D02*
G03X1468958Y433852I294J271D01*
G02X1468900Y431892I973J-1010D01*
G03X1468328Y431909I-294J-271D01*
G02X1468386Y433869I-973J1010D01*
G37*
G36*
G01X1588351Y433445D02*
G03X1588973Y433428I318J243D01*
G02X1588924Y431663I1064J-913D01*
G03X1588302Y431680I-318J-243D01*
G02X1588351Y433445I-1064J913D01*
G37*
G36*
G01X1410812Y434785D02*
Y429690D01*
X1410802Y429606D01*
G02X1407788Y429775I-1502J169D01*
G01Y434776D01*
G02X1410812Y434785I1512J-1D01*
G37*
G36*
G01X1402910D02*
Y429690D01*
X1402900Y429606D01*
G02X1399886Y429775I-1502J169D01*
G01Y434776D01*
G02X1402910Y434785I1512J-1D01*
G37*
G36*
G01X1468885Y427046D02*
G03X1468305I-290J-276D01*
G02Y428980I-1015J967D01*
G03X1468885I290J276D01*
G02Y427046I1015J-967D01*
G37*
G36*
G01X1548776Y429391D02*
G03Y428844I292J-274D01*
G02X1546732I-1022J-960D01*
G03Y429391I-292J274D01*
G02X1548097Y431710I1022J960D01*
G03X1548579Y431986I98J388D01*
G02X1549582Y430235I1346J-392D01*
G03X1549100Y429959I-98J-388D01*
G02X1548776Y429391I-1346J392D01*
G37*
G36*
G01X1583820Y426607D02*
G03X1583311Y426307I-118J-382D01*
G02X1582352Y427934I-1372J287D01*
G03X1582861Y428234I118J382D01*
G02X1583820Y426607I1372J-287D01*
G37*
G36*
G01X17025Y423338D02*
X12024D01*
G02X12025Y426362I1J1512D01*
G01X17025D01*
G02X18536Y424860I-1J-1512D01*
G01Y424765D01*
X18527Y424681D01*
G02X17025Y423338I-1502J168D01*
G37*
G36*
G01X7025D02*
X2024D01*
G02X2025Y426362I1J1512D01*
G01X7025D01*
G02X8536Y424860I-1J-1512D01*
G01Y424765D01*
X8527Y424681D01*
G02X7025Y423338I-1502J168D01*
G37*
G36*
G01X62516Y424220D02*
X62507Y424136D01*
G02X59494Y424305I-1502J169D01*
G01Y429306D01*
G02X62516Y429315I1511J-1D01*
G01Y424220D01*
G37*
G36*
G01X1589368Y424272D02*
G03X1588961Y423864I-7J-400D01*
G02X1587587Y425237I-1402J-29D01*
G03X1587994Y425645I7J400D01*
G02X1589368Y424272I1402J29D01*
G37*
G36*
G01X1559675Y420042D02*
X1555775D01*
G02Y422866I0J1412D01*
G01X1559676D01*
G02X1561086Y421464I-1J-1412D01*
G01Y421370D01*
X1561076Y421286D01*
G02X1559675Y420042I-1401J167D01*
G37*
G36*
G01X1548790Y422624D02*
G03Y422084I295J-270D01*
G02X1546720I-1035J-946D01*
G03Y422624I-295J270D01*
G02X1548139Y424918I1035J946D01*
G03X1548629Y425181I109J385D01*
G02X1549580Y423405I1335J-428D01*
G03X1549090Y423142I-109J-385D01*
G02X1548790Y422624I-1335J427D01*
G37*
G36*
G01X1504996Y419784D02*
G03X1504478Y419514I-133J-377D01*
G02X1501738Y419711I-1350J378D01*
G03X1501304Y420058I-397J-51D01*
G02X1502565Y421635I-129J1396D01*
G03X1502999Y421288I397J51D01*
G02X1503591Y421215I128J-1396D01*
G03X1504109Y421485I133J377D01*
G02X1504508Y422137I1350J-378D01*
G03X1504541Y422692I-271J295D01*
G02X1506556Y422574I1064J912D01*
G03X1506523Y422019I271J-295D01*
G02X1504996Y419784I-1065J-912D01*
G37*
G36*
G01X50776Y424005D02*
Y418910D01*
X50767Y418826D01*
G02X47754Y418995I-1502J169D01*
G01Y423996D01*
G02X50776Y424005I1511J-1D01*
G37*
G36*
G01X1557725Y416662D02*
X1553824D01*
G02X1553825Y419486I1J1412D01*
G01X1554448D01*
G02X1554998Y418963I0J-551D01*
G03X1555016Y418813I777J17D01*
G02X1555159Y418507I-1189J-742D01*
G03X1556391I616J472D01*
G02X1556534Y418813I1332J-436D01*
G03X1556550Y419022I-759J163D01*
G02X1557050Y419486I500J-37D01*
G01X1557725D01*
G02X1559136Y418084I0J-1411D01*
G01Y417990D01*
X1559126Y417906D01*
G02X1557725Y416662I-1401J167D01*
G37*
G36*
G01X1413476Y416907D02*
X1413461Y417081D01*
X1413626Y421997D01*
X1413634Y422005D01*
X1413640Y422078D01*
G02X1416647Y422124I1506J-131D01*
G01X1416668Y421948D01*
X1416504Y417042D01*
X1416505D01*
X1416502Y416988D01*
X1416477Y416817D01*
G02X1413476Y416907I-1495J222D01*
G37*
G36*
G01X1405646Y421576D02*
G02X1408670Y421585I1512J-1D01*
G01Y416490D01*
X1408660Y416406D01*
G02X1405646Y416572I-1502J167D01*
G01Y421576D01*
G37*
G36*
G01X1567475Y413282D02*
X1563574D01*
G02X1563575Y416106I1J1412D01*
G01X1564198D01*
G02X1564748Y415583I0J-551D01*
G03X1564766Y415433I777J17D01*
G02X1564909Y415127I-1189J-742D01*
G03X1566141I616J472D01*
G02X1566284Y415433I1332J-436D01*
G03X1566300Y415642I-759J163D01*
G02X1566800Y416106I500J-37D01*
G01X1567475D01*
G02X1568886Y414704I0J-1411D01*
G01Y414610D01*
X1568876Y414526D01*
G02X1567475Y413282I-1401J167D01*
G37*
G36*
G01X767237Y416062D02*
G03X767281Y415483I296J-269D01*
G02X765357Y415340I-887J-1086D01*
G03X765313Y415919I-296J269D01*
G02X766261Y418406I887J1086D01*
G03X766678Y418800I17J399D01*
G02X768019Y417379I1402J-20D01*
G03X767602Y416985I-17J-399D01*
G02X767237Y416062I-1402J21D01*
G37*
G36*
G01X47006Y415201D02*
G03Y414590I258J-306D01*
G02X45194I-906J-1070D01*
G03Y415201I-258J305D01*
G02X47006I906J1070D01*
G37*
G36*
G01X1471147Y413091D02*
G03X1471720Y413069I297J268D01*
G02X1471647Y411116I968J-1014D01*
G03X1471074Y411138I-297J-268D01*
G02X1471147Y413091I-968J1014D01*
G37*
G36*
G01X1588551Y411003D02*
G03X1587996Y410990I-271J-295D01*
G02X1587949Y413008I-996J986D01*
G03X1588504Y413021I271J295D01*
G02X1588551Y411003I996J-986D01*
G37*
G36*
G01X120018Y413220D02*
G03X120037Y412643I286J-279D01*
G02X118098Y412581I-937J-1043D01*
G03X118079Y413158I-286J279D01*
G02X120018Y413220I937J1043D01*
G37*
G36*
G01X20473Y414391D02*
G03X21740Y414794I-2J2199D01*
G02X21756Y410156I1488J-2314D01*
G03X20502Y410569I-1283J-1786D01*
G01X20471D01*
G03X19204Y410166I2J-2199D01*
G02X19188Y414804I-1488J2314D01*
G03X20442Y414391I1283J1786D01*
G01X20473D01*
G37*
G36*
G01X3938D02*
G03X5205Y414794I-2J2199D01*
G02X5221Y410156I1488J-2314D01*
G03X3967Y410569I-1283J-1786D01*
G01X3936D01*
G03X2669Y410166I2J-2199D01*
G02X2653Y414804I-1488J2314D01*
G03X3907Y414391I1283J1786D01*
G01X3938D01*
G37*
G36*
G01X-12598D02*
G03X-11331Y414794I-2J2199D01*
G02X-11315Y410156I1488J-2314D01*
G03X-12569Y410569I-1283J-1786D01*
G01X-12599D01*
G03X-13866Y410166I2J-2199D01*
G02X-13882Y414804I-1488J2314D01*
G03X-12628Y414391I1283J1786D01*
G01X-12598D01*
G37*
G36*
G01X749612Y408828D02*
G03X749058I-277J-288D01*
G02X747075Y410811I-973J1010D01*
G03Y411365I-288J277D01*
G02X749058Y413348I1010J973D01*
G03X749612I277J288D01*
G02X751558I973J-1010D01*
G03X752112I277J288D01*
G02X753991Y413408I973J-1010D01*
G03X754524Y413422I259J305D01*
G02X755905Y413741I963J-1019D01*
G03X756424Y414133I119J382D01*
G02X758799Y415177I1402J34D01*
G03X759353I277J288D01*
G02X761303Y415172I972J-1010D01*
G03X761912Y415233I279J287D01*
G02X763960Y413358I1157J-793D01*
G03X763942Y412756I254J-309D01*
G02X761975Y410760I-953J-1028D01*
G03X761384Y410747I-290J-276D01*
G02X759353Y410657I-1058J920D01*
G03X758799I-277J-288D01*
G02X757408Y410329I-972J1010D01*
G03X756889Y409937I-119J-382D01*
G02X754581Y408833I-1402J-34D01*
G03X754048Y408819I-259J-305D01*
G02X752112Y408828I-963J1019D01*
G03X751558I-277J-288D01*
G02X749612I-973J1010D01*
G37*
G36*
G01X1403912Y408281D02*
Y413282D01*
G02X1406934Y413291I1511J-1D01*
G01Y408281D01*
X1406935D01*
X1406934Y408196D01*
X1406925Y408112D01*
G02X1403912Y408281I-1502J169D01*
G37*
G36*
G01X1571375Y406522D02*
X1567474D01*
G02X1567475Y409346I1J1412D01*
G01X1568098D01*
G02X1568648Y408823I0J-551D01*
G03X1568666Y408673I777J17D01*
G02X1568809Y408367I-1189J-742D01*
G03X1570041I616J472D01*
G02X1570184Y408673I1332J-436D01*
G03X1570200Y408882I-759J163D01*
G02X1570700Y409346I500J-37D01*
G01X1571375D01*
G02X1572786Y407944I0J-1411D01*
G01Y407850D01*
X1572776Y407766D01*
G02X1571375Y406522I-1401J167D01*
G37*
G36*
G01X1444049Y407876D02*
G03X1443955Y407308I227J-329D01*
G02X1442033Y407625I-1125J-836D01*
G03X1442127Y408193I-227J329D01*
G02X1444049Y407876I1125J836D01*
G37*
G36*
G01X120709Y404984D02*
G03X120136Y405156I-363J-168D01*
G02X120670Y406937I-738J1192D01*
G03X121243Y406765I363J168D01*
G02X120709Y404984I738J-1192D01*
G37*
G36*
G01X53088Y406598D02*
X55227Y409137D01*
G02X57894Y408173I1156J-974D01*
G01Y408078D01*
X57885Y407994D01*
G02X57539Y407189I-1503J169D01*
G01X56228Y405632D01*
X56227D01*
X55422Y404678D01*
X55421Y404676D01*
G02X53088Y406598I-1177J948D01*
G37*
G36*
G01X1589833Y402984D02*
G03X1589253Y402806I-214J-338D01*
G02X1588716Y404554I-1285J562D01*
G03X1589296Y404732I214J338D01*
G02X1589833Y402984I1285J-562D01*
G37*
G36*
G01X25591Y406517D02*
G03X26858Y406920I-2J2199D01*
G02X26874Y402282I1488J-2314D01*
G03X25620Y402695I-1283J-1786D01*
G01X25590D01*
G03X24323Y402292I2J-2199D01*
G02X24307Y406930I-1488J2314D01*
G03X25561Y406517I1283J1786D01*
G01X25591D01*
G37*
G36*
G01X9056D02*
G03X10323Y406920I-2J2199D01*
G02X10339Y402282I1488J-2314D01*
G03X9085Y402695I-1283J-1786D01*
G01X9054D01*
G03X7787Y402292I2J-2199D01*
G02X7771Y406930I-1488J2314D01*
G03X9025Y406517I1283J1786D01*
G01X9056D01*
G37*
G36*
G01X-7480D02*
G03X-6213Y406920I-2J2199D01*
G02X-6197Y402282I1488J-2314D01*
G03X-7451Y402695I-1283J-1786D01*
G01X-7481D01*
G03X-8748Y402292I2J-2199D01*
G02X-8764Y406930I-1488J2314D01*
G03X-7510Y406517I1283J1786D01*
G01X-7480D01*
G37*
G36*
G01X66896Y403268D02*
Y403173D01*
X66886Y403089D01*
G02X64311Y402193I-1502J169D01*
G01X61973Y404550D01*
X61972Y404551D01*
G02X64097Y406701I1052J1085D01*
G01X65153Y405638D01*
X66457Y404323D01*
G02X66896Y403268I-1073J-1065D01*
G37*
G36*
G01X1383327Y397890D02*
G03X1382773I-277J-288D01*
G02X1380751Y399830I-973J1010D01*
G03X1380740Y400372I-299J265D01*
G02X1380658Y400466I1015J968D01*
G03X1380346I-156J-125D01*
G02X1378023Y400669I-1094J877D01*
G03X1377479Y400826I-350J-193D01*
G02X1375827Y401043I-679J1227D01*
G03X1375273I-277J-288D01*
G02Y403063I-973J1010D01*
G03X1375827I277J288D01*
G02X1378029Y402727I973J-1010D01*
G03X1378573Y402570I350J193D01*
G02X1380225Y402353I679J-1227D01*
G03X1380779I277J288D01*
G02X1382725I973J-1010D01*
G03X1383279I277J288D01*
G02X1385225I973J-1010D01*
G03X1385779I277J288D01*
G02X1387801Y400413I973J-1010D01*
G03X1387812Y399871I299J-265D01*
G02X1385827Y397890I-1012J-971D01*
G03X1385273I-277J-288D01*
G02X1383327I-973J1010D01*
G37*
G36*
G01X1586703Y396411D02*
G03X1586141Y396408I-279J-286D01*
G02X1586130Y398403I-991J992D01*
G03X1586692Y398406I279J286D01*
G02X1586703Y396411I991J-992D01*
G37*
G36*
G01X102066Y400958D02*
G03X102634I284J282D01*
G02X104766I1066J-1058D01*
G03X105334I284J282D01*
G02X107466I1066J-1058D01*
G03X108034I284J282D01*
G02X110499Y400446I1066J-1058D01*
G03X111017Y400219I373J146D01*
G02X111112Y397386I544J-1400D01*
G03X110594Y397045I-120J-382D01*
G02X108034Y396142I-1494J155D01*
G03X107466I-284J-282D01*
G02X105334I-1066J1058D01*
G03X104766I-284J-282D01*
G02X102634I-1066J1058D01*
G03X102066I-284J-282D01*
G02X99942Y398266I-1066J1058D01*
G03Y398834I-282J284D01*
G02X102066Y400958I1058J1066D01*
G37*
G36*
G01X1370996Y395697D02*
G03X1370418I-289J-277D01*
G02Y397639I-1011J971D01*
G03X1370996I289J277D01*
G02Y395697I1011J-971D01*
G37*
G36*
G01X1655811Y398206D02*
G03X1655831Y397649I297J-268D01*
G02X1653820Y397576I-970J-1012D01*
G03X1653800Y398133I-297J268D01*
G02X1653776Y400133I970J1012D01*
G03X1653784Y400688I-284J282D01*
G02X1655803Y400657I1024J957D01*
G03X1655795Y400102I284J-282D01*
G02X1655811Y398206I-1025J-957D01*
G37*
G36*
G01X3938Y398643D02*
G03X5205Y399046I-2J2199D01*
G02X5221Y394408I1488J-2314D01*
G03X3967Y394821I-1283J-1786D01*
G01X3936D01*
G03X2669Y394418I2J-2199D01*
G02X2653Y399056I-1488J2314D01*
G03X3907Y398643I1283J1786D01*
G01X3938D01*
G37*
G36*
G01X-12598D02*
G03X-11331Y399046I-2J2199D01*
G02X-11315Y394408I1488J-2314D01*
G03X-12569Y394821I-1283J-1786D01*
G01X-12599D01*
G03X-13866Y394418I2J-2199D01*
G02X-13882Y399056I-1488J2314D01*
G03X-12628Y398643I1283J1786D01*
G01X-12598D01*
G37*
G36*
G01X66236Y391560D02*
X66227Y391476D01*
G02X63214Y391645I-1502J169D01*
G01Y396645D01*
G02X66236Y396655I1511J0D01*
G01Y391560D01*
G37*
G36*
G01X1662125Y389274D02*
G03X1662056Y388723I251J-311D01*
G02X1660052Y388973I-1122J-840D01*
G03X1660121Y389524I-251J311D01*
G02X1660264Y391367I1122J840D01*
G03Y391940I-280J286D01*
G02X1662222I979J1003D01*
G03Y391367I280J-286D01*
G02X1662125Y389274I-979J-1003D01*
G37*
G36*
G01X25591Y390769D02*
G03X26858Y391172I-2J2199D01*
G02X26874Y386534I1488J-2314D01*
G03X25620Y386947I-1283J-1786D01*
G01X25590D01*
G03X24323Y386544I2J-2199D01*
G02X24307Y391182I-1488J2314D01*
G03X25561Y390769I1283J1786D01*
G01X25591D01*
G37*
G36*
G01X175673Y385123D02*
G03Y384493I246J-315D01*
G02X173827I-923J-1185D01*
G03Y385123I-246J315D01*
G02Y387493I923J1185D01*
G03Y388123I-246J315D01*
G02X175673I923J1185D01*
G03Y387493I246J-315D01*
G02Y385123I-923J-1185D01*
G37*
G36*
G01X822033Y382027D02*
G03X821403I-315J-246D01*
G02X819295Y384135I-1185J923D01*
G03Y384765I-246J315D01*
G02X821403Y386873I923J1185D01*
G03X822033I315J246D01*
G02X824364Y386921I1185J-923D01*
G03X824969Y386915I305J259D01*
G02X827152Y384854I1128J-992D01*
G03X827177Y384262I281J-285D01*
G02X825081Y382125I-961J-1154D01*
G03X824450Y382091I-302J-262D01*
G02X822033Y382027I-1232J859D01*
G37*
G36*
G01X1465365Y384296D02*
G03X1465373Y383729I286J-280D01*
G02X1463396Y383699I-973J-1009D01*
G03X1463388Y384266I-286J280D01*
G02X1465365Y384296I973J1009D01*
G37*
G36*
G01X172081Y384583D02*
G03Y383953I246J-315D01*
G02X170235I-923J-1185D01*
G03Y384583I-246J315D01*
G02Y386953I923J1185D01*
G03Y387583I-246J315D01*
G02X172081I923J1185D01*
G03Y386953I246J-315D01*
G02Y384583I-923J-1185D01*
G37*
G36*
G01X1571657Y384060D02*
G03X1571944Y383585I390J-89D01*
G02X1570217Y382538I-359J-1355D01*
G03X1569930Y383013I-390J89D01*
G02X1571657Y384060I359J1355D01*
G37*
G36*
G01X3938Y382895D02*
G03X5205Y383298I-2J2199D01*
G02X5221Y378660I1488J-2314D01*
G03X3967Y379073I-1283J-1786D01*
G01X3936D01*
G03X2669Y378670I2J-2199D01*
G02X2653Y383308I-1488J2314D01*
G03X3907Y382895I1283J1786D01*
G01X3938D01*
G37*
G36*
G01X-12598D02*
G03X-11331Y383298I-2J2199D01*
G02X-11315Y378660I1488J-2314D01*
G03X-12569Y379073I-1283J-1786D01*
G01X-12599D01*
G03X-13866Y378670I2J-2199D01*
G02X-13882Y383308I-1488J2314D01*
G03X-12628Y382895I1283J1786D01*
G01X-12598D01*
G37*
G36*
G01X1665868Y378253D02*
G03X1665885Y377698I296J-269D01*
G02X1663866Y377636I-980J-1003D01*
G03X1663849Y378191I-296J269D01*
G02X1665868Y378253I980J1003D01*
G37*
G36*
G01X1600490Y380354D02*
Y376261D01*
X1600480Y376176D01*
G02X1597266Y376346I-1603J170D01*
G01Y380344D01*
G02X1600490Y380354I1612J0D01*
G37*
G36*
G01X1609758Y380332D02*
Y376086D01*
X1609748Y376001D01*
G02X1606534Y376171I-1603J170D01*
G01Y380322D01*
G02X1609758Y380332I1612J0D01*
G37*
G36*
G01X852304Y377641D02*
G03Y377095I292J-273D01*
G02X852361Y375106I-1096J-1027D01*
G03X852470Y374502I307J-256D01*
G02X850602Y372202I-743J-1305D01*
G03X850014Y372215I-300J-265D01*
G02X847807Y374252I-1082J1042D01*
G03X847739Y374843I-300J265D01*
G02X847581Y374972I869J1225D01*
G03X847035I-273J-292D01*
G02X844912Y377095I-1027J1096D01*
G03Y377641I-292J273D01*
G02X847035Y379764I1096J1027D01*
G03X847581I273J292D01*
G02X849635I1027J-1096D01*
G03X850181I273J292D01*
G02X852304Y377641I1027J-1096D01*
G37*
G36*
G01X778810Y371129D02*
G03X778193Y371122I-306J-258D01*
G02X778172Y372904I-1093J878D01*
G03X778789Y372911I306J258D01*
G02X778810Y371129I1093J-878D01*
G37*
G36*
G01X25591Y375021D02*
G03X26858Y375424I-2J2199D01*
G02X26874Y370786I1488J-2314D01*
G03X25620Y371199I-1283J-1786D01*
G01X25590D01*
G03X24323Y370796I2J-2199D01*
G02X24307Y375434I-1488J2314D01*
G03X25561Y375021I1283J1786D01*
G01X25591D01*
G37*
G36*
G01X9056D02*
G03X10323Y375424I-2J2199D01*
G02X10339Y370786I1488J-2314D01*
G03X9085Y371199I-1283J-1786D01*
G01X9054D01*
G03X7787Y370796I2J-2199D01*
G02X7771Y375434I-1488J2314D01*
G03X9025Y375021I1283J1786D01*
G01X9056D01*
G37*
G36*
G01X197824Y376256D02*
G03X198316Y376525I109J385D01*
G02X200871Y375085I1438J-436D01*
G03X200901Y374520I297J-268D01*
G02X200823Y372215I-1001J-1120D01*
G03Y371585I246J-315D01*
G02X198977I-923J-1185D01*
G03Y372215I-246J315D01*
G02X198429Y373097I923J1185D01*
G03X197906Y373394I-392J-81D01*
G02X197824Y376256I-495J1418D01*
G37*
G36*
G01X102761Y370050D02*
G03X102792Y369428I266J-298D01*
G02X101032Y369342I-827J-1132D01*
G03X101001Y369964I-266J298D01*
G02X102761Y370050I827J1132D01*
G37*
G36*
G01X1598821Y368943D02*
G03X1598810Y368350I263J-301D01*
G02X1596929Y368386I-960J-1021D01*
G03X1596940Y368979I-263J301D01*
G02X1598821Y368943I960J1021D01*
G37*
G36*
G01X835863Y367760D02*
G03X836181Y367756I161J119D01*
G02X836282Y365787I1182J-926D01*
G03X835713Y365794I-288J-278D01*
G02X833631Y365767I-1055J1069D01*
G03X833085I-273J-292D01*
G02X831031I-1027J1096D01*
G03X830485I-273J-292D01*
G02X828431I-1027J1096D01*
G03X827885I-273J-292D01*
G02X825831I-1027J1096D01*
G03X825285I-273J-292D01*
G02X823231I-1027J1096D01*
G03X822685I-273J-292D01*
G02X820562Y367890I-1027J1096D01*
G03Y368436I-292J273D01*
G02X822685Y370559I1096J1027D01*
G03X823231I273J292D01*
G02X825285I1027J-1096D01*
G03X825831I273J292D01*
G02X827885I1027J-1096D01*
G03X828431I273J292D01*
G02X830485I1027J-1096D01*
G03X831031I273J292D01*
G02X833085I1027J-1096D01*
G03X833631I273J292D01*
G02X835754Y368436I1027J-1096D01*
G03Y367890I292J-273D01*
G02X835863Y367760I-1095J-1029D01*
G37*
G36*
G01X175215Y365864D02*
G03X174585I-315J-246D01*
G02X172477Y367972I-1185J923D01*
G03Y368602I-246J315D01*
G02X174585Y370710I923J1185D01*
G03X175215I315J246D01*
G02X177585I1185J-923D01*
G03X178215I315J246D01*
G02X180585I1185J-923D01*
G03X181215I315J246D01*
G02X183585I1185J-923D01*
G03X184215I315J246D01*
G02X186585I1185J-923D01*
G03X187215I315J246D01*
G02X189323Y368602I1185J-923D01*
G03Y367972I246J-315D01*
G02X187215Y365864I-923J-1185D01*
G03X186585I-315J-246D01*
G02X184215I-1185J923D01*
G03X183585I-315J-246D01*
G02X181215I-1185J923D01*
G03X180585I-315J-246D01*
G02X178215I-1185J923D01*
G03X177585I-315J-246D01*
G02X175215I-1185J923D01*
G37*
G36*
G01X746646Y362913D02*
G03X746100I-273J-292D01*
G02X744063Y365121I-1027J1096D01*
G03X744042Y365730I-269J296D01*
G02X746000Y368005I932J1178D01*
G03X746546I273J292D01*
G02X748600I1027J-1096D01*
G03X749146I273J292D01*
G02X751183Y365797I1027J-1096D01*
G03X751204Y365188I269J-296D01*
G02X749246Y362913I-932J-1178D01*
G03X748700I-273J-292D01*
G02X746646I-1027J1096D01*
G37*
G36*
G01X20473Y367147D02*
G03X21740Y367550I-2J2199D01*
G02X21756Y362912I1488J-2314D01*
G03X20502Y363325I-1283J-1786D01*
G01X20471D01*
G03X19204Y362922I2J-2199D01*
G02X19188Y367560I-1488J2314D01*
G03X20442Y367147I1283J1786D01*
G01X20473D01*
G37*
G36*
G01X3938D02*
G03X5205Y367550I-2J2199D01*
G02X5221Y362912I1488J-2314D01*
G03X3967Y363325I-1283J-1786D01*
G01X3936D01*
G03X2669Y362922I2J-2199D01*
G02X2653Y367560I-1488J2314D01*
G03X3907Y367147I1283J1786D01*
G01X3938D01*
G37*
G36*
G01X-12598D02*
G03X-11331Y367550I-2J2199D01*
G02X-11315Y362912I1488J-2314D01*
G03X-12569Y363325I-1283J-1786D01*
G01X-12599D01*
G03X-13866Y362922I2J-2199D01*
G02X-13882Y367560I-1488J2314D01*
G03X-12628Y367147I1283J1786D01*
G01X-12598D01*
G37*
G36*
G01X175286Y362358D02*
G03X174656I-315J-246D01*
G02Y364204I-1185J923D01*
G03X175286I315J246D01*
G02X177656I1185J-923D01*
G03X178286I315J246D01*
G02X180656I1185J-923D01*
G03X181286I315J246D01*
G02X183656I1185J-923D01*
G03X184286I315J246D01*
G02X186656I1185J-923D01*
G03X187286I315J246D01*
G02Y362358I1185J-923D01*
G03X186656I-315J-246D01*
G02X184286I-1185J923D01*
G03X183656I-315J-246D01*
G02X181286I-1185J923D01*
G03X180656I-315J-246D01*
G02X178286I-1185J923D01*
G03X177656I-315J-246D01*
G02X175286I-1185J923D01*
G37*
G36*
G01X1544310Y362427D02*
G03Y361873I288J-277D01*
G02X1542290I-1010J-973D01*
G03Y362427I-288J277D01*
G02X1544310I1010J973D01*
G37*
G36*
G01X1653798Y365610D02*
Y360515D01*
X1653788Y360430D01*
G02X1650574Y360600I-1603J170D01*
G01Y365601D01*
G02X1653798Y365610I1612J-1D01*
G37*
G36*
G01X1641878Y365510D02*
Y360415D01*
X1641868Y360330D01*
G02X1638654Y360500I-1603J170D01*
G01Y365501D01*
G02X1641878Y365510I1612J-1D01*
G37*
G36*
G01X1534756Y361839D02*
G03X1534771Y361284I295J-270D01*
G02X1532753Y361227I-982J-1001D01*
G03X1532738Y361782I-295J270D01*
G02X1534756Y361839I982J1001D01*
G37*
G36*
G01X823923Y358895D02*
G03X823292Y358882I-310J-252D01*
G02X821166Y360967I-1202J900D01*
G03Y361597I-246J315D01*
G02X823274Y363705I923J1185D01*
G03X823904I315J246D01*
G02X826274I1185J-923D01*
G03X826904I315J246D01*
G02X829274I1185J-923D01*
G03X829904I315J246D01*
G02X832274I1185J-923D01*
G03X832904I315J246D01*
G02X835042Y361621I1185J-923D01*
G03Y361002I253J-310D01*
G02X832904Y358918I-953J-1161D01*
G03X832274I-315J-246D01*
G02X829904I-1185J923D01*
G03X829274I-315J-246D01*
G02X826904I-1185J923D01*
G03X826274I-315J-246D01*
G02X823923Y358895I-1185J923D01*
G37*
G36*
G01X175239Y358698D02*
G03X174609I-315J-246D01*
G02Y360544I-1185J923D01*
G03X175239I315J246D01*
G02X177609I1185J-923D01*
G03X178239I315J246D01*
G02X180609I1185J-923D01*
G03X181239I315J246D01*
G02X183609I1185J-923D01*
G03X184239I315J246D01*
G02X186609I1185J-923D01*
G03X187239I315J246D01*
G02Y358698I1185J-923D01*
G03X186609I-315J-246D01*
G02X184239I-1185J923D01*
G03X183609I-315J-246D01*
G02X181239I-1185J923D01*
G03X180609I-315J-246D01*
G02X178239I-1185J923D01*
G03X177609I-315J-246D01*
G02X175239I-1185J923D01*
G37*
G36*
G01X49402Y358381D02*
G03X48839Y358449I-315J-246D01*
G02X49078Y360409I-869J1101D01*
G03X49641Y360341I315J246D01*
G02X49402Y358381I869J-1101D01*
G37*
G36*
G01X1479586Y360661D02*
G03X1479585Y360087I278J-287D01*
G02X1477633Y360091I-978J-1005D01*
G03X1477634Y360665I-278J287D01*
G02X1479586Y360661I978J1005D01*
G37*
G36*
G01X1588089Y357429D02*
G03X1587511I-289J-277D01*
G02Y359371I-1011J971D01*
G03X1588089I289J277D01*
G02Y357429I1011J-971D01*
G37*
G36*
G01X1489450Y359356D02*
G03Y358778I277J-289D01*
G02X1487508I-971J-1011D01*
G03Y359356I-277J289D01*
G02Y361378I971J1011D01*
G03Y361956I-277J289D01*
G02X1489450I971J1011D01*
G03Y361378I277J-289D01*
G02Y359356I-971J-1011D01*
G37*
G36*
G01X1484671Y358502D02*
G03X1484699Y357881I266J-299D01*
G02X1482936Y357801I-832J-1128D01*
G03X1482908Y358422I-266J299D01*
G02X1484671Y358502I832J1128D01*
G37*
G36*
G01X25591Y359273D02*
G03X26858Y359676I-2J2199D01*
G02X26874Y355038I1488J-2314D01*
G03X25620Y355451I-1283J-1786D01*
G01X25590D01*
G03X24323Y355048I2J-2199D01*
G02X24307Y359686I-1488J2314D01*
G03X25561Y359273I1283J1786D01*
G01X25591D01*
G37*
G36*
G01X9056D02*
G03X10323Y359676I-2J2199D01*
G02X10339Y355038I1488J-2314D01*
G03X9085Y355451I-1283J-1786D01*
G01X9054D01*
G03X7787Y355048I2J-2199D01*
G02X7771Y359686I-1488J2314D01*
G03X9025Y359273I1283J1786D01*
G01X9056D01*
G37*
G36*
G01X-7480D02*
G03X-6213Y359676I-2J2199D01*
G02X-6197Y355038I1488J-2314D01*
G03X-7451Y355451I-1283J-1786D01*
G01X-7481D01*
G03X-8748Y355048I2J-2199D01*
G02X-8764Y359686I-1488J2314D01*
G03X-7510Y359273I1283J1786D01*
G01X-7480D01*
G37*
G36*
G01X1631382Y356595D02*
G03X1631410Y355995I278J-288D01*
G02X1629560Y355908I-876J-1095D01*
G03X1629532Y356508I-278J288D01*
G02X1629425Y358603I876J1095D01*
G03X1629440Y359158I-280J285D01*
G02X1629414Y361018I1036J945D01*
G03X1629383Y361573I-303J261D01*
G02X1629291Y363533I954J1027D01*
G03X1629269Y364088I-299J266D01*
G02X1629267Y366108I971J1011D01*
G03X1629258Y366692I-278J288D01*
G02X1631173Y366721I942J1038D01*
G03X1631182Y366137I278J-288D01*
G02X1631286Y364166I-942J-1038D01*
G03X1631308Y363611I299J-266D01*
G02X1631399Y361685I-971J-1011D01*
G03X1631430Y361130I303J-261D01*
G02X1631459Y359103I-954J-1027D01*
G03X1631444Y358548I280J-285D01*
G02X1631382Y356595I-1036J-945D01*
G37*
G36*
G01X696625Y356247D02*
G03X696613Y355657I264J-300D01*
G02X694719Y355697I-969J-1013D01*
G03X694731Y356287I-264J300D01*
G02X696625Y356247I969J1013D01*
G37*
G36*
G01X1521289Y356063D02*
G03X1521315Y355466I279J-287D01*
G02X1519453Y355385I-885J-1087D01*
G03X1519427Y355982I-279J287D01*
G02X1521289Y356063I885J1087D01*
G37*
G36*
G01X1525756Y355744D02*
G03Y355190I288J-277D01*
G02X1523736I-1010J-973D01*
G03Y355744I-288J277D01*
G02Y357690I1010J973D01*
G03Y358244I-288J277D01*
G02X1525756I1010J973D01*
G03Y357690I288J-277D01*
G02Y355744I-1010J-973D01*
G37*
G36*
G01X1499217Y353894D02*
G03Y353316I277J-289D01*
G02X1497275I-971J-1011D01*
G03Y353894I-277J289D01*
G02Y355916I971J1011D01*
G03Y356494I-277J289D01*
G02X1497261Y358503I971J1011D01*
G03X1497275Y359058I-281J285D01*
G02X1497356Y361034I1034J947D01*
G03X1497342Y361633I-272J293D01*
G02X1497293Y363734I904J1072D01*
G03X1497279Y364333I-272J293D01*
G02X1499136Y364376I904J1072D01*
G03X1499150Y363777I272J-293D01*
G02X1499199Y361676I-904J-1072D01*
G03X1499213Y361077I272J-293D01*
G02X1499294Y359007I-904J-1072D01*
G03X1499280Y358452I281J-285D01*
G02X1499217Y356494I-1034J-947D01*
G03Y355916I277J-289D01*
G02Y353894I-971J-1011D01*
G37*
G36*
G01X1653157Y353689D02*
G03Y353111I277J-289D01*
G02X1651215I-971J-1011D01*
G03Y353689I-277J289D01*
G02X1653157I971J1011D01*
G37*
G36*
G01X767955Y352504D02*
G03X768121Y351953I349J-195D01*
G02X766254Y351393I-644J-1245D01*
G03X766088Y351944I-349J195D01*
G02X767955Y352504I644J1245D01*
G37*
G36*
G01X1539449Y352283D02*
G03Y351705I277J-289D01*
G02X1537507I-971J-1011D01*
G03Y352283I-277J289D01*
G02Y354305I971J1011D01*
G03Y354883I-277J289D01*
G02X1539449I971J1011D01*
G03Y354305I277J-289D01*
G02Y352283I-971J-1011D01*
G37*
G36*
G01X1416430Y352151D02*
G03X1416419Y351563I266J-299D01*
G02X1414520Y351599I-969J-1013D01*
G03X1414531Y352187I-266J299D01*
G02X1416430Y352151I969J1013D01*
G37*
G36*
G01X1447394Y350654D02*
G03X1446911Y350277I-83J-391D01*
G02X1445801Y351698I-1401J50D01*
G03X1446284Y352075I83J391D01*
G02X1447394Y350654I1401J-50D01*
G37*
G36*
G01X1490844Y351587D02*
G03X1490827Y351004I265J-299D01*
G02X1488909Y351061I-989J-993D01*
G03X1488926Y351644I-265J299D01*
G02X1490844Y351587I989J993D01*
G37*
G36*
G01X1544538Y351473D02*
G03Y350919I288J-277D01*
G02X1542518I-1010J-973D01*
G03Y351473I-288J277D01*
G02X1544538I1010J973D01*
G37*
G36*
G01X1331153Y351026D02*
G03X1331708Y350981I301J264D01*
G02X1331547Y348974I892J-1082D01*
G03X1330992Y349019I-301J-264D01*
G02X1331153Y351026I-892J1082D01*
G37*
G36*
G01X115528Y351963D02*
G03X115764Y352490I-135J377D01*
G02X117535Y351696I1299J526D01*
G03X117299Y351169I135J-377D01*
G02X117398Y350750I-1299J-528D01*
G03X117844Y350383I399J30D01*
G02X116610Y348884I164J-1392D01*
G03X116164Y349251I-399J-30D01*
G02X115528Y351963I-163J1392D01*
G37*
G36*
G01X746392Y343816D02*
G03X745804I-294J-270D01*
G02X743775Y346018I-1105J1018D01*
G03Y346648I-246J315D01*
G02X745804Y348850I924J1184D01*
G03X746392I294J270D01*
G02X748604I1106J-1017D01*
G03X749192I294J270D01*
G02X751221Y346648I1105J-1018D01*
G03Y346018I246J-315D01*
G02X749192Y343816I-924J-1184D01*
G03X748604I-294J-270D01*
G02X746392I-1106J1017D01*
G37*
G36*
G01X189515Y344231D02*
G03X190146Y344210I324J235D01*
G02X190085Y342365I1154J-962D01*
G03X189454Y342386I-324J-235D01*
G02X187115Y342425I-1154J962D01*
G03X186485I-315J-246D01*
G02X184085Y342465I-1185J923D01*
G03X183454Y342486I-324J-235D01*
G02X181115Y342525I-1154J962D01*
G03X180485I-315J-246D01*
G02X178115I-1185J923D01*
G03X177485I-315J-246D01*
G02X175115I-1185J923D01*
G03X174485I-315J-246D01*
G02Y344371I-1185J923D01*
G03X175115I315J246D01*
G02X177485I1185J-923D01*
G03X178115I315J246D01*
G02X180485I1185J-923D01*
G03X181115I315J246D01*
G02X183515Y344331I1185J-923D01*
G03X184146Y344310I324J235D01*
G02X186485Y344271I1154J-962D01*
G03X187115I315J246D01*
G02X189515Y344231I1185J-923D01*
G37*
G36*
G01X1643534Y343999D02*
G03X1643594Y343437I312J-251D01*
G02X1641621Y343227I-882J-1090D01*
G03X1641561Y343789I-312J251D01*
G02X1643534Y343999I882J1090D01*
G37*
G36*
G01X1556480Y340194D02*
G03X1555870I-305J-259D01*
G02Y342006I-1070J906D01*
G03X1556480I305J259D01*
G02Y340194I1070J-906D01*
G37*
G36*
G01X778862Y339127D02*
G03X778252I-305J-259D01*
G02Y340939I-1070J906D01*
G03X778862I305J259D01*
G02Y339127I1070J-906D01*
G37*
G36*
G01X700168Y337953D02*
G03X699613Y337931I-266J-299D01*
G02X699532Y339947I-1013J969D01*
G03X700087Y339969I266J299D01*
G02X700168Y337953I1013J-969D01*
G37*
G36*
G01X1582841Y337739D02*
G03X1582273Y337715I-272J-293D01*
G02X1579704Y339598I-1183J1080D01*
G03X1579581Y340130I-346J200D01*
G02X1581408Y342230I785J1162D01*
G03X1581962Y342189I298J267D01*
G02X1584152Y340570I897J-1077D01*
G03X1584360Y340050I369J-154D01*
G02X1582841Y337739I-566J-1283D01*
G37*
G36*
G01X1070007Y337750D02*
G03X1069377I-315J-246D01*
G02Y339596I-1185J923D01*
G03X1070007I315J246D01*
G02Y337750I1185J-923D01*
G37*
G36*
G01X1062807D02*
G03X1062177I-315J-246D01*
G02Y339596I-1185J923D01*
G03X1062807I315J246D01*
G02Y337750I1185J-923D01*
G37*
G36*
G01X824297Y336104D02*
G03X823667I-315J-246D01*
G02X821465Y338133I-1184J924D01*
G03Y338721I-270J294D01*
G02X821559Y341012I1017J1106D01*
G03Y341642I-246J315D01*
G02X823667Y343750I923J1185D01*
G03X824297I315J246D01*
G02X826667I1185J-923D01*
G03X827297I315J246D01*
G02X829667I1185J-923D01*
G03X830297I315J246D01*
G02X832667I1185J-923D01*
G03X833297I315J246D01*
G02X835610Y343818I1185J-923D01*
G03X836220Y343829I300J264D01*
G02X838474Y343909I1162J-952D01*
G03X839079Y343937I290J275D01*
G02X841293Y341919I1183J-926D01*
G03X841298Y341334I275J-290D01*
G02X841337Y339158I-1016J-1107D01*
G03X841358Y338569I281J-285D01*
G02X839303Y336382I-977J-1141D01*
G03X838672Y336308I-287J-278D01*
G02X836254Y336086I-1290J769D01*
G03X835644Y336075I-300J-264D01*
G02X833297Y336104I-1162J952D01*
G03X832667I-315J-246D01*
G02X830297I-1185J923D01*
G03X829667I-315J-246D01*
G02X827297I-1185J923D01*
G03X826667I-315J-246D01*
G02X824297I-1185J923D01*
G37*
G36*
G01X1620907Y337663D02*
G03Y337109I288J-277D01*
G02X1618887I-1010J-973D01*
G03Y337663I-288J277D01*
G02Y339609I1010J973D01*
G03Y340163I-288J277D01*
G02X1620907I1010J973D01*
G03Y339609I288J-277D01*
G02Y337663I-1010J-973D01*
G37*
G36*
G01X746392Y334499D02*
G03X745804I-294J-270D01*
G02X743681Y336622I-1106J1017D01*
G03Y337210I-270J294D01*
G02X745804Y339333I1017J1106D01*
G03X746392I294J270D01*
G02X748604I1106J-1017D01*
G03X749192I294J270D01*
G02X751315Y337210I1106J-1017D01*
G03Y336622I270J-294D01*
G02X749192Y334499I-1017J-1106D01*
G03X748604I-294J-270D01*
G02X746392I-1106J1017D01*
G37*
G36*
G01X852890Y334482D02*
G03X852260I-315J-246D01*
G02X850078Y336528I-1185J923D01*
G03X850058Y337143I-266J299D01*
G02X849797Y337404I924J1185D01*
G03X849167I-315J-246D01*
G02X847059Y339512I-1185J923D01*
G03Y340142I-246J315D01*
G02Y342512I923J1185D01*
G03Y343142I-246J315D01*
G02X849167Y345250I923J1185D01*
G03X849797I315J246D01*
G02X852167I1185J-923D01*
G03X852797I315J246D01*
G02X855167I1185J-923D01*
G03X855797I315J246D01*
G02X857905Y343142I1185J-923D01*
G03Y342512I246J-315D01*
G02Y340142I-923J-1185D01*
G03Y339512I246J-315D01*
G02X857979Y337204I-923J-1185D01*
G03X857999Y336589I266J-299D01*
G02X855890Y334482I-924J-1184D01*
G03X855260I-315J-246D01*
G02X852890I-1185J923D01*
G37*
G36*
G01X81379Y334629D02*
G03X80813Y334496I-220J-334D01*
G02X80371Y336371I-1213J704D01*
G03X80937Y336504I220J334D01*
G02X81379Y334629I1213J-704D01*
G37*
G36*
G01X102187Y334221D02*
G03X101599Y334210I-289J-277D01*
G02X101563Y336109I-1049J930D01*
G03X102151Y336120I289J277D01*
G02X102187Y334221I1049J-930D01*
G37*
G36*
G01X1497795Y336516D02*
G03X1498283Y336166I398J40D01*
G02X1497205Y334660I317J-1366D01*
G03X1496717Y335010I-398J-40D01*
G02X1495105Y336914I-317J1366D01*
G03X1494893Y337435I-369J153D01*
G02X1494589Y339834I552J1289D01*
G03X1494670Y340384I-244J317D01*
G02X1496666Y340090I1140J816D01*
G03X1496585Y339540I244J-317D01*
G02X1496620Y339488I-1145J-808D01*
G03X1496939Y339466I168J109D01*
G02X1498126Y337150I1058J-920D01*
G03X1497771Y336668I36J-398D01*
G02X1497795Y336516I-1371J-294D01*
G37*
G36*
G01X1473398Y336467D02*
G03X1473409Y335868I270J-295D01*
G02X1471552Y335833I-909J-1068D01*
G03X1471541Y336432I-270J295D01*
G02X1473398Y336467I909J1068D01*
G37*
G36*
G01X1416971Y334489D02*
G03Y333911I277J-289D01*
G02X1415029I-971J-1011D01*
G03Y334489I-277J289D01*
G02Y336511I971J1011D01*
G03Y337089I-277J289D01*
G02X1416971I971J1011D01*
G03Y336511I277J-289D01*
G02Y334489I-971J-1011D01*
G37*
G36*
G01X1570182Y333131D02*
G03Y332553I277J-289D01*
G02X1568240I-971J-1011D01*
G03Y333131I-277J289D01*
G02X1570182I971J1011D01*
G37*
G36*
G01X1548600Y333102D02*
G03X1548734Y332556I343J-205D01*
G02X1546798Y332082I-733J-1195D01*
G03X1546664Y332628I-343J205D01*
G02X1548600Y333102I733J1195D01*
G37*
G36*
G01X773426Y331585D02*
G03X773170Y331092I128J-379D01*
G02X770343Y331241I-1440J-427D01*
G03X770038Y331789I-369J153D01*
G02X771437Y334227I240J1483D01*
G03X771999Y334172I309J255D01*
G02X774055Y334025I950J-1163D01*
G03X774640Y334021I294J271D01*
G02X776466Y331678I1091J-1033D01*
G03X776330Y331104I195J-349D01*
G02X774427Y331504I-1159J-788D01*
G03X774533Y332084I-213J339D01*
G02X774498Y332133I1204J897D01*
G03X774171Y332135I-164J-114D01*
G02X773426Y331585I-1221J875D01*
G37*
G36*
G01X1526765Y328878D02*
G03X1526213Y328768I-220J-334D01*
G02X1525823Y330723I-1162J785D01*
G03X1526375Y330833I220J334D01*
G02X1526765Y328878I1162J-785D01*
G37*
G36*
G01X1560995Y330789D02*
G03Y330211I277J-289D01*
G02X1559053I-971J-1011D01*
G03Y330789I-277J289D01*
G02X1560995I971J1011D01*
G37*
G36*
G01X1654016Y328102D02*
G03X1654038Y327534I292J-273D01*
G02X1652066Y327457I-947J-1034D01*
G03X1652044Y328025I-292J273D01*
G02X1654016Y328102I947J1034D01*
G37*
G36*
G01X645706Y326977D02*
G03X645589Y327576I-312J250D01*
G02X647366Y327923I683J1224D01*
G03X647483Y327324I312J-250D01*
G02X645706Y326977I-683J-1224D01*
G37*
G36*
G01X1493775Y327586D02*
G03X1493930Y327048I352J-190D01*
G02X1492005Y326492I-690J-1220D01*
G03X1491850Y327030I-352J190D01*
G02X1493775Y327586I690J1220D01*
G37*
G36*
G01X376986Y330493D02*
G03X377603Y330507I303J261D01*
G02X379341Y328185I1182J-927D01*
G03X379154Y327595I148J-372D01*
G02X376831Y325716I-1260J-818D01*
G03X376269Y325720I-283J-283D01*
G02X374123Y325775I-1046J1078D01*
G03X373528Y325764I-293J-272D01*
G02X371284Y325731I-1137J982D01*
G03X370728Y325764I-295J-270D01*
G02X368647Y325881I-980J1138D01*
G03X368094Y325913I-293J-272D01*
G02X368087Y325906I-1062J1055D01*
G03X368024Y325360I257J-306D01*
G02X365856Y325610I-1202J-901D01*
G03X365919Y326156I-257J306D01*
G02X368222Y328078I1202J900D01*
G03X368775Y328046I293J272D01*
G02X370855Y327917I973J-1144D01*
G03X371411Y327884I295J270D01*
G02X373491Y327769I980J-1138D01*
G03X374086Y327780I293J272D01*
G02X374473Y328099I1135J-983D01*
G03X374604Y328670I-200J346D01*
G02X376986Y330493I1244J842D01*
G37*
G36*
G01X1017937Y325288D02*
G03X1017717Y324783I156J-368D01*
G02X1015855Y325596I-1318J-479D01*
G03X1016075Y326101I-156J368D01*
G02X1018366Y327590I1318J480D01*
G03X1018920I277J288D01*
G02X1020866I973J-1010D01*
G03X1021420I277J288D01*
G02X1023366I973J-1010D01*
G03X1023920I277J288D01*
G02X1024287Y327844I971J-1011D01*
G03X1024479Y328371I-172J361D01*
G02X1026567Y330094I1276J580D01*
G03X1027153Y330233I232J326D01*
G02X1028642Y328200I1240J-653D01*
G03X1028420Y327534I71J-394D01*
G02X1026420Y325570I-1027J-955D01*
G03X1025866I-277J-288D01*
G02X1023920I-973J1010D01*
G03X1023366I-277J-288D01*
G02X1021420I-973J1010D01*
G03X1020866I-277J-288D01*
G02X1018920I-973J1010D01*
G03X1018366I-277J-288D01*
G02X1017937Y325288I-972J1011D01*
G37*
G36*
G01X1543591Y324428D02*
G03X1543924Y323984I397J-49D01*
G02X1542309Y322772I-224J-1384D01*
G03X1541976Y323216I-397J49D01*
G02X1543591Y324428I224J1384D01*
G37*
G36*
G01X1590800Y323413D02*
G03X1591385Y323202I378J131D01*
G02X1590786Y321542I725J-1200D01*
G03X1590201Y321753I-378J-131D01*
G02X1590800Y323413I-725J1200D01*
G37*
G36*
G01X688320Y318775D02*
G03X688262Y318235I263J-301D01*
G02X686218Y318455I-1124J-838D01*
G03X686276Y318995I-263J301D01*
G02X688320Y318775I1124J838D01*
G37*
G36*
G01X647783Y319011D02*
G03Y318389I252J-311D01*
G02X646017I-883J-1089D01*
G03Y319011I-252J311D01*
G02X647783I883J1089D01*
G37*
G36*
G01X115528Y319963D02*
G03X115764Y320490I-135J377D01*
G02X117535Y319696I1299J526D01*
G03X117299Y319169I135J-377D01*
G02X117398Y318750I-1299J-528D01*
G03X117844Y318383I399J30D01*
G02X116610Y316884I164J-1392D01*
G03X116164Y317251I-399J-30D01*
G02X115528Y319963I-163J1392D01*
G37*
G36*
G01X1549195Y318450D02*
G03X1549443Y317930I374J-141D01*
G02X1547687Y317092I-443J-1330D01*
G03X1547439Y317612I-374J141D01*
G02X1549195Y318450I443J1330D01*
G37*
G36*
G01X82378Y317044D02*
G03X82972Y317036I301J264D01*
G02X82946Y315158I1028J-953D01*
G03X82352Y315166I-301J-264D01*
G02X82378Y317044I-1028J953D01*
G37*
G36*
G01X64971Y315489D02*
G03Y314911I277J-289D01*
G02X63029I-971J-1011D01*
G03Y315489I-277J289D01*
G02X64971I971J1011D01*
G37*
G36*
G01X1568271Y314778D02*
G03X1568629Y314283I388J-96D01*
G02X1567163Y313224I-105J-1398D01*
G03X1566805Y313719I-388J96D01*
G02X1565900Y314144I104J1398D01*
G03X1565346Y314165I-288J-277D01*
G02X1565421Y316183I-935J1045D01*
G03X1565975Y316162I288J277D01*
G02X1568271Y314778I935J-1045D01*
G37*
G36*
G01X1517245Y312208D02*
G03X1517209Y311654I269J-296D01*
G02X1515194Y311785I-1071J-905D01*
G03X1515230Y312339I-269J296D01*
G02X1517245Y312208I1071J905D01*
G37*
G36*
G01X1640423Y311762D02*
G03Y311208I288J-277D01*
G02X1638403I-1010J-973D01*
G03Y311762I-288J277D01*
G02X1640423I1010J973D01*
G37*
G36*
G01X1047773Y310863D02*
G03X1048390Y310862I309J254D01*
G02X1048386Y308951I1157J-958D01*
G03X1047769Y308952I-309J-254D01*
G02X1047773Y310863I-1157J958D01*
G37*
G36*
G01X1040555Y310849D02*
G03X1041179Y310848I312J250D01*
G02X1041175Y308965I1168J-944D01*
G03X1040551Y308966I-312J-250D01*
G02X1040555Y310849I-1168J944D01*
G37*
G36*
G01X405294Y310843D02*
G03X405920Y310841I314J248D01*
G02X405917Y308971I1174J-937D01*
G03X405291Y308973I-314J-248D01*
G02X405294Y310843I-1174J937D01*
G37*
G36*
G01X383682Y310833D02*
G03X384312Y310831I316J245D01*
G02X384309Y308981I1182J-927D01*
G03X383679Y308983I-316J-245D01*
G02X383682Y310833I-1182J927D01*
G37*
G36*
G01X1565345Y310023D02*
G03X1565339Y309424I262J-302D01*
G02X1563482Y309443I-939J-1041D01*
G03X1563488Y310042I-262J302D01*
G02X1565345Y310023I939J1041D01*
G37*
G36*
G01X714980Y309887D02*
G03Y309333I288J-277D01*
G02X712960I-1010J-973D01*
G03Y309887I-288J277D01*
G02X714980I1010J973D01*
G37*
G36*
G01X455158Y309368D02*
G03Y308814I288J-277D01*
G02X452981Y307064I-1010J-972D01*
G03X452426Y307175I-333J-222D01*
G02X450266Y308104I-778J1166D01*
G03X449789Y308428I-394J-67D01*
G02X448527Y308790I-289J1372D01*
G03X447973I-277J-288D01*
G02Y310810I-973J1010D01*
G03X448527I277J288D01*
G02X450882Y310037I973J-1010D01*
G03X451359Y309713I394J67D01*
G02X452218Y309622I289J-1372D01*
G03X452773Y310066I163J365D01*
G02X455158Y309368I1375J275D01*
G37*
G36*
G01X1561087Y309435D02*
G03X1561176Y308850I311J-252D01*
G02X1559310Y308565I-776J-1167D01*
G03X1559221Y309150I-311J252D01*
G02X1561087Y309435I776J1167D01*
G37*
G36*
G01X849497Y305804D02*
G03X848867I-315J-246D01*
G02X846586Y307754I-1185J923D01*
G03Y308300I-292J273D01*
G02X846624Y310393I1096J1027D01*
G03Y310961I-282J284D01*
G02X846586Y313054I1058J1066D01*
G03Y313600I-292J273D01*
G02X848867Y315550I1096J1027D01*
G03X849497I315J246D01*
G02X851867I1185J-923D01*
G03X852497I315J246D01*
G02X854867I1185J-923D01*
G03X855497I315J246D01*
G02X857778Y313600I1185J-923D01*
G03Y313054I292J-273D01*
G02X857740Y310961I-1096J-1027D01*
G03Y310393I282J-284D01*
G02X857778Y308300I-1058J-1066D01*
G03Y307754I292J-273D01*
G02X855497Y305804I-1096J-1027D01*
G03X854867I-315J-246D01*
G02X852497I-1185J923D01*
G03X851867I-315J-246D01*
G02X849497I-1185J923D01*
G37*
G36*
G01X1306859Y308248D02*
G03X1306876Y307664I281J-284D01*
G02X1304964Y307608I-926J-1053D01*
G03X1304947Y308192I-281J284D01*
G02X1304824Y308315I928J1051D01*
G03X1304271Y308358I-299J-266D01*
G02X1304429Y310371I-891J1083D01*
G03X1304982Y310328I299J266D01*
G02X1306859Y308248I891J-1083D01*
G37*
G36*
G01X198962Y305776D02*
G03X198423Y305919I-343J-205D01*
G02X196657Y308323I-739J1308D01*
G03X196667Y308898I-273J292D01*
G02X198757Y308863I1063J1061D01*
G03X198747Y308288I273J-292D01*
G02X198973Y307999I-1061J-1063D01*
G03X199512Y307856I343J205D01*
G02X198962Y305776I739J-1308D01*
G37*
G36*
G01X1537386Y305392D02*
G03X1537870Y305102I388J98D01*
G02X1536847Y303397I336J-1361D01*
G03X1536363Y303687I-388J-98D01*
G02X1537386Y305392I-336J1361D01*
G37*
G36*
G01X1637893Y304142D02*
G03X1637906Y303586I294J-271D01*
G02X1635890Y303537I-984J-998D01*
G03X1635877Y304093I-294J271D01*
G02X1637893Y304142I984J998D01*
G37*
G36*
G01X1564358Y302020D02*
G03X1564356Y302642I-253J310D01*
G02X1566121Y302648I879J1092D01*
G03X1566123Y302026I253J-310D01*
G02X1564358Y302020I-879J-1092D01*
G37*
G36*
G01X1584487Y302124D02*
G03Y301556I281J-284D01*
G02X1582513I-987J-996D01*
G03Y302124I-281J284D01*
G02X1584487I987J996D01*
G37*
G36*
G01X1300631Y300220D02*
G03X1300624Y299612I256J-307D01*
G02X1298804Y299635I-923J-1055D01*
G03X1298811Y300243I-256J307D01*
G02X1300631Y300220I923J1055D01*
G37*
G36*
G01X657627Y294985D02*
G03X657426Y295549I-350J193D01*
G02X659176Y296170I524J1301D01*
G03X659377Y295606I350J-193D01*
G02X657627Y294985I-524J-1301D01*
G37*
G36*
G01X1026147Y293881D02*
G03X1026758Y293878I307J256D01*
G02X1026749Y291941I1144J-974D01*
G03X1026138Y291944I-307J-256D01*
G02X1026147Y293881I-1144J974D01*
G37*
G36*
G01X405427Y293983D02*
G03X406022Y293956I310J253D01*
G02X405933Y291951I1072J-1052D01*
G03X405338Y291978I-310J-253D01*
G02X405427Y293983I-1072J1052D01*
G37*
G36*
G01X398128Y293919D02*
G03X398758Y293887I327J229D01*
G02X398663Y292043I1136J-983D01*
G03X398033Y292075I-327J-229D01*
G02X398128Y293919I-1136J983D01*
G37*
G36*
G01X383861Y294061D02*
G03X384464Y293997I329J227D01*
G02X384258Y292050I1030J-1093D01*
G03X383655Y292114I-329J-227D01*
G02X383861Y294061I-1030J1093D01*
G37*
G36*
G01X372760Y291927D02*
G03X372204Y291892I-260J-304D01*
G02X369861Y292046I-1110J1012D01*
G03X369235Y292085I-328J-228D01*
G02X369349Y293945I-1119J1002D01*
G03X369975Y293906I328J228D01*
G02X372070Y294045I1119J-1002D01*
G03X372626Y294080I260J304D01*
G02X372760Y291927I1110J-1012D01*
G37*
G36*
G01X1637832Y293973D02*
G03Y293419I288J-277D01*
G02X1635812I-1010J-973D01*
G03Y293973I-288J277D01*
G02X1635853Y295959I1010J973D01*
G03X1635876Y296514I-276J289D01*
G02X1637894Y296431I1049J930D01*
G03X1637871Y295876I276J-289D01*
G02X1637832Y293973I-1049J-930D01*
G37*
G36*
G01X1305637Y292913D02*
G03X1305262Y292476I23J-399D01*
G02X1303787Y293745I-1396J-131D01*
G03X1304162Y294182I-23J399D01*
G02X1305637Y292913I1396J131D01*
G37*
G36*
G01X1335501Y292918D02*
G03X1336123Y292909I315J247D01*
G02X1336099Y291144I1077J-897D01*
G03X1335477Y291153I-315J-247D01*
G02X1335501Y292918I-1077J897D01*
G37*
G36*
G01X1627281Y302600D02*
X1627279Y302503D01*
G02Y302891I-14210J194D01*
G01X1627280Y302796D01*
X1627281Y302702D01*
Y302600D01*
G37*
G36*
G01X49683Y291311D02*
G03Y290689I252J-311D01*
G02X47917I-883J-1089D01*
G03Y291311I-252J311D01*
G02X49683I883J1089D01*
G37*
G36*
G01X1534824Y287709D02*
G03X1534841Y287125I281J-284D01*
G02X1532928Y287070I-927J-1052D01*
G03X1532911Y287654I-281J284D01*
G02X1534824Y287709I927J1052D01*
G37*
G36*
G01X1548006Y287663D02*
G03X1548358Y287223I398J-43D01*
G02X1546805Y285979I-159J-1393D01*
G03X1546453Y286419I-398J43D01*
G02X1548006Y287663I159J1393D01*
G37*
G36*
G01X637881Y287185D02*
G03X637839Y286610I255J-308D01*
G02X636064Y286864I-1040J-940D01*
G03X636087Y287187I-105J170D01*
G02X635967Y287300I900J1076D01*
G03X635645Y287257I-146J-137D01*
G02X635280Y289012I-1238J658D01*
G03X635852Y289090I249J313D01*
G02X637881Y287185I1133J-827D01*
G37*
G36*
G01X115528Y287963D02*
G03X115764Y288490I-135J377D01*
G02X117535Y287696I1299J526D01*
G03X117299Y287169I135J-377D01*
G02X117398Y286750I-1299J-528D01*
G03X117844Y286383I399J30D01*
G02X116610Y284884I164J-1392D01*
G03X116164Y285251I-399J-30D01*
G02X115528Y287963I-163J1392D01*
G37*
G36*
G01X663911Y283917D02*
G03X663289I-311J-252D01*
G02X660957Y285448I-1089J883D01*
G03X660742Y286007I-355J184D01*
G02X662475Y286673I490J1314D01*
G03X662690Y286114I355J-184D01*
G02X663289Y285683I-491J-1314D01*
G03X663911I311J252D01*
G02Y283917I1089J-883D01*
G37*
G36*
G01X1580115Y283805D02*
G03X1579560Y283799I-274J-291D01*
G02X1579539Y285819I-983J1000D01*
G03X1580094Y285825I274J291D01*
G02X1580115Y283805I983J-1000D01*
G37*
G36*
G01X1570790Y286064D02*
G03X1571021Y286576I-144J373D01*
G02X1573704Y286758I1315J487D01*
G03X1574027Y286277I391J-87D01*
G02X1572875Y283833I-237J-1382D01*
G03X1572321Y283802I-261J-303D01*
G02X1570790Y286064I-1028J953D01*
G37*
G36*
G01X560979Y284997D02*
G03X560608Y284565I28J-399D01*
G02X559116Y285846I-1397J-118D01*
G03X559487Y286278I-28J399D01*
G02X560979Y284997I1397J118D01*
G37*
G36*
G01X1315646Y285315D02*
G03X1315579Y284745I243J-318D01*
G02X1313636Y284974I-1089J-883D01*
G03X1313703Y285544I-243J318D01*
G02X1315646Y285315I1089J883D01*
G37*
G36*
G01X69311Y282571D02*
G03X69889I289J277D01*
G02Y280629I1011J-971D01*
G03X69311I-289J-277D01*
G02Y282571I-1011J971D01*
G37*
G36*
G01X1399552Y283306D02*
G03X1399680Y282764I343J-205D01*
G02X1397721Y282299I-754J-1182D01*
G03X1397593Y282841I-343J205D01*
G02X1399552Y283306I754J1182D01*
G37*
G36*
G01X1097703Y279975D02*
G03X1098242I269J295D01*
G02X1098239Y277904I944J-1037D01*
G03X1097700I-269J-295D01*
G02X1097703Y279975I-944J1037D01*
G37*
G36*
G01X448798Y277912D02*
G03X448198I-300J-265D01*
G02Y279770I-1050J929D01*
G03X448798I300J265D01*
G02Y277912I1050J-929D01*
G37*
G36*
G01X1434372Y279771D02*
G03Y279217I288J-277D01*
G02X1432352I-1010J-973D01*
G03Y279771I-288J277D01*
G02X1434372I1010J973D01*
G37*
G36*
G01X662303Y279878D02*
G03X662721Y279485I400J6D01*
G02X661384Y278062I65J-1401D01*
G03X660966Y278455I-400J-6D01*
G02X662303Y279878I-65J1401D01*
G37*
G36*
G01X60473Y279010D02*
G03X61027I277J288D01*
G02Y276990I973J-1010D01*
G03X60473I-277J-288D01*
G02Y279010I-973J1010D01*
G37*
G36*
G01X648422Y279263D02*
G03X648418Y278671I267J-298D01*
G02X646534Y278684I-949J-1032D01*
G03X646538Y279276I-267J298D01*
G02X648422Y279263I949J1032D01*
G37*
G36*
G01X1333680Y274524D02*
X1330171D01*
G02Y277546I0J1511D01*
G01X1333681D01*
G02X1335192Y276045I0J-1512D01*
G01Y275950D01*
X1335182Y275866D01*
G02X1333680Y274524I-1502J169D01*
G37*
G36*
G01X452389Y274629D02*
G03X451811I-289J-277D01*
G02Y276571I-1011J971D01*
G03X452389I289J277D01*
G02Y274629I1011J-971D01*
G37*
G36*
G01X778572Y275068D02*
G03X777973Y274913I-236J-323D01*
G02X777528Y276632I-1273J588D01*
G03X778127Y276787I236J323D01*
G02X778572Y275068I1273J-588D01*
G37*
G36*
G01X1637694Y276342D02*
G03Y275788I288J-277D01*
G02X1635674I-1010J-973D01*
G03Y276342I-288J277D01*
G02Y278288I1010J973D01*
G03Y278842I-288J277D01*
G02X1637694I1010J973D01*
G03Y278288I288J-277D01*
G02Y276342I-1010J-973D01*
G37*
G36*
G01X824279Y273987D02*
G03X823649I-315J-246D01*
G02X821368Y275937I-1185J923D01*
G03Y276483I-292J273D01*
G02Y278537I1096J1027D01*
G03Y279083I-292J273D01*
G02X823649Y281033I1096J1027D01*
G03X824279I315J246D01*
G02X826649I1185J-923D01*
G03X827279I315J246D01*
G02X829649I1185J-923D01*
G03X830279I315J246D01*
G02X832649I1185J-923D01*
G03X833279I315J246D01*
G02X835570Y281127I1185J-923D01*
G03X836158I294J270D01*
G02X838370I1106J-1017D01*
G03X838958I294J270D01*
G02X841160Y279083I1106J-1017D01*
G03Y278537I292J-273D01*
G02X838958Y276493I-1096J-1027D01*
G03X838370I-294J-270D01*
G02X838360Y276483I-1067J1056D01*
G03Y275937I292J-273D01*
G02X836158Y273893I-1096J-1027D01*
G03X835570I-294J-270D01*
G02X833279Y273987I-1106J1017D01*
G03X832649I-315J-246D01*
G02X830279I-1185J923D01*
G03X829649I-315J-246D01*
G02X827279I-1185J923D01*
G03X826649I-315J-246D01*
G02X824279I-1185J923D01*
G37*
G36*
G01X850197Y273504D02*
G03X849567I-315J-246D01*
G02X847286Y275454I-1185J923D01*
G03Y276000I-292J273D01*
G02X847324Y278093I1096J1027D01*
G03Y278661I-282J284D01*
G02X847286Y280754I1058J1066D01*
G03Y281300I-292J273D01*
G02X849567Y283250I1096J1027D01*
G03X850197I315J246D01*
G02X852567I1185J-923D01*
G03X853197I315J246D01*
G02X855567I1185J-923D01*
G03X856197I315J246D01*
G02X858478Y281300I1185J-923D01*
G03Y280754I292J-273D01*
G02X858440Y278661I-1096J-1027D01*
G03Y278093I282J-284D01*
G02X858478Y276000I-1058J-1066D01*
G03Y275454I292J-273D01*
G02X856197Y273504I-1096J-1027D01*
G03X855567I-315J-246D01*
G02X853197I-1185J923D01*
G03X852567I-315J-246D01*
G02X850197I-1185J923D01*
G37*
G36*
G01X1340248Y270244D02*
X1336448D01*
G02Y273266I0J1511D01*
G01X1340249D01*
G02X1341760Y271765I0J-1512D01*
G01Y271670D01*
X1341750Y271586D01*
G02X1340248Y270244I-1502J169D01*
G37*
G36*
G01X1412345Y270158D02*
G03X1412700Y269670I390J-90D01*
G02X1411213Y268588I-121J-1397D01*
G03X1410858Y269076I-390J90D01*
G02X1412345Y270158I121J1397D01*
G37*
G36*
G01X1010655Y269874D02*
G03X1011064Y269502I399J28D01*
G02X1009701Y268003I36J-1402D01*
G03X1009292Y268375I-399J-28D01*
G02X1007949Y269270I-36J1402D01*
G03X1007382Y269475I-373J-145D01*
G02X1005785Y271762I-682J1225D01*
G03X1005777Y272375I-261J303D01*
G02X1007580Y272398I888J1085D01*
G03X1007588Y271785I261J-303D01*
G02X1008007Y271207I-888J-1085D01*
G03X1008574Y271002I373J145D01*
G02X1010655Y269874I682J-1225D01*
G37*
G36*
G01X361047D02*
G03X361456Y269502I399J28D01*
G02X360093Y268003I36J-1402D01*
G03X359684Y268375I-399J-28D01*
G02X358341Y269270I-36J1402D01*
G03X357774Y269475I-373J-145D01*
G02X356177Y271762I-682J1225D01*
G03X356169Y272375I-261J303D01*
G02X357972Y272398I888J1085D01*
G03X357980Y271785I261J-303D01*
G02X358399Y271207I-888J-1085D01*
G03X358966Y271002I373J145D01*
G02X361047Y269874I682J-1225D01*
G37*
G36*
G01X1347468Y266584D02*
X1343668D01*
G02Y269606I0J1511D01*
G01X1347469D01*
G02X1348980Y268105I0J-1512D01*
G01Y268010D01*
X1348970Y267926D01*
G02X1347468Y266584I-1502J169D01*
G37*
G36*
G01X748148Y268571D02*
G03X748170Y269192I-241J319D01*
G02X749932Y269129I920J1058D01*
G03X749910Y268508I241J-319D01*
G02X748148Y268571I-920J-1058D01*
G37*
G36*
G01X773888Y267630D02*
G03X774434Y267508I335J218D01*
G02X774041Y265487I737J-1192D01*
G03X773489Y265578I-323J-237D01*
G02X771498Y265822I-859J1232D01*
G03X770869Y265788I-301J-263D01*
G02X769071Y268038I-1232J859D01*
G03X769249Y268636I-151J370D01*
G02X771051Y268098I1236J853D01*
G03X770873Y267500I151J-370D01*
G02X770919Y267430I-1232J-860D01*
G03X771271Y267449I171J104D01*
G02X773888Y267630I1359J-639D01*
G37*
G36*
G01X1452990Y267710D02*
G03X1453522Y267465I380J125D01*
G02X1452703Y265803I534J-1296D01*
G03X1452184Y266075I-386J-105D01*
G02X1452990Y267710I-431J1229D01*
G37*
G36*
G01X1356268Y264184D02*
X1352468D01*
G02Y267206I0J1511D01*
G01X1356269D01*
G02X1357780Y265705I0J-1512D01*
G01Y265610D01*
X1357770Y265526D01*
G02X1356268Y264184I-1502J170D01*
G37*
G36*
G01X1217244Y267082D02*
G03Y266528I288J-277D01*
G02X1215224I-1010J-973D01*
G03Y267082I-288J277D01*
G02X1217244I1010J973D01*
G37*
G36*
G01X567936D02*
G03Y266528I288J-277D01*
G02X565916I-1010J-973D01*
G03Y267082I-288J277D01*
G02X567936I1010J973D01*
G37*
G36*
G01X1381031Y264088D02*
X1377522D01*
G02Y267112I0J1512D01*
G01X1381032D01*
G02X1382542Y265610I-1J-1512D01*
G01Y265515D01*
X1382533Y265431D01*
G02X1381031Y264088I-1502J168D01*
G37*
G36*
G01X1362803Y267036D02*
X1366313D01*
G02X1367824Y265535I0J-1512D01*
G01Y265440D01*
X1367814Y265356D01*
G02X1366312Y264014I-1502J169D01*
G01X1362803D01*
G02Y267036I1J1511D01*
G37*
G36*
G01X437497Y263882D02*
G03X437537Y263336I311J-252D01*
G02X435351Y263176I-1018J-1104D01*
G03X435311Y263722I-311J252D01*
G02X437497Y263882I1018J1104D01*
G37*
G36*
G01X1628763Y261318D02*
G03X1628481Y260782I90J-390D01*
G02X1626286Y261349I-1304J-515D01*
G03X1626299Y261955I-255J309D01*
G02X1628763Y261318I1843J2044D01*
G37*
G36*
G01X1160308Y261401D02*
G03X1160313Y260793I262J-302D01*
G02X1158492Y260779I-902J-1073D01*
G03X1158487Y261387I-262J302D01*
G02X1160308Y261401I902J1073D01*
G37*
G36*
G01X1455205Y261089D02*
G03X1455127Y260534I244J-317D01*
G02X1453298Y260914I-1127J-834D01*
G03X1453342Y261226I-100J173D01*
G02X1453256Y261323I1005J978D01*
G03X1452944I-156J-125D01*
G02X1452823Y263210I-1094J877D01*
G03X1453377I277J288D01*
G02X1455205Y261089I972J-1010D01*
G37*
G36*
G01X1226918Y260827D02*
G03Y260273I288J-277D01*
G02X1224898I-1010J-973D01*
G03Y260827I-288J277D01*
G02X1226918I1010J973D01*
G37*
G36*
G01X576610D02*
G03Y260273I288J-277D01*
G02X574590I-1010J-973D01*
G03Y260827I-288J277D01*
G02X576610I1010J973D01*
G37*
G36*
G01X510478Y259111D02*
G03X510102Y258672I22J-399D01*
G02X508630Y259932I-1395J-140D01*
G03X509006Y260371I-22J399D01*
G02X510478Y259111I1395J140D01*
G37*
G36*
G01X1494858Y254727D02*
G03X1494307Y254648I-235J-324D01*
G02X1494023Y256641I-1108J859D01*
G03X1494574Y256720I235J324D01*
G02X1494678Y256839I1106J-861D01*
G03X1494681Y257394I-287J279D01*
G02X1496700Y257383I1015J967D01*
G03X1496697Y256828I287J-279D01*
G02X1494858Y254727I-1015J-967D01*
G37*
G36*
G01X1465810Y255243D02*
G03X1465890Y254676I316J-244D01*
G02X1463781Y252976I-827J-1132D01*
G03X1463257Y253182I-366J-161D01*
G02X1462861Y255863I-553J1288D01*
G03X1463304Y256225I44J398D01*
G02X1465810Y255243I1396J-125D01*
G37*
G36*
G01X621974Y254930D02*
G03X621904Y254340I231J-327D01*
G02X620041Y254561I-1054J-924D01*
G03X620111Y255151I-231J327D01*
G02X621974Y254930I1054J924D01*
G37*
G36*
G01X1275468Y254991D02*
G03X1275795Y254508I390J-88D01*
G02X1274209Y253432I-218J-1385D01*
G03X1273882Y253915I-390J88D01*
G02X1275468Y254991I218J1385D01*
G37*
G36*
G01X116610Y252884D02*
G03X116164Y253251I-399J-30D01*
G02X115528Y255963I-163J1392D01*
G03X115764Y256490I-135J377D01*
G02X117535Y255696I1299J526D01*
G03X117299Y255169I135J-377D01*
G02X117398Y254750I-1299J-528D01*
G03X117844Y254383I399J30D01*
G02X116610Y252884I164J-1392D01*
G37*
G36*
G01X1469444Y253888D02*
G03X1469999Y253876I284J282D01*
G02X1469956Y251858I951J-1030D01*
G03X1469401Y251870I-284J-282D01*
G02X1469444Y253888I-951J1030D01*
G37*
G36*
G01X766693Y253259D02*
G03X766354Y252751I45J-397D01*
G02X764846Y253756I-1347J-388D01*
G03X765185Y254264I-45J397D01*
G02X765602Y255701I1347J388D01*
G03X765624Y256278I-266J299D01*
G02X767562Y256203I1008J974D01*
G03X767540Y255626I266J-299D01*
G02X766693Y253259I-1008J-974D01*
G37*
G36*
G01X1479777Y253333D02*
G03X1479666Y252778I222J-333D01*
G02X1477723Y253167I-1166J-778D01*
G03X1477834Y253722I-222J333D01*
G02X1477627Y254782I1166J778D01*
G03X1477271Y255261I-392J80D01*
G02X1478770Y256375I126J1396D01*
G03X1479126Y255896I392J-80D01*
G02X1479777Y253333I-126J-1396D01*
G37*
G36*
G01X1434852Y253400D02*
G03X1434985Y252823I328J-228D01*
G02X1433148Y252400I-686J-1223D01*
G03X1433015Y252977I-328J228D01*
G02X1434852Y253400I686J1223D01*
G37*
G36*
G01X1817282Y248886D02*
X1812281D01*
G02X1812282Y252110I1J1612D01*
G01X1817282D01*
G02X1818894Y250508I0J-1612D01*
G01Y250413D01*
X1818884Y250328D01*
G02X1817282Y248886I-1602J169D01*
G37*
G36*
G01X1798384D02*
X1793384D01*
G02Y252110I0J1612D01*
G01X1798385D01*
G02X1799996Y250508I-1J-1612D01*
G01Y250413D01*
X1799986Y250328D01*
G02X1798384Y248886I-1602J169D01*
G37*
G36*
G01X1825702Y251794D02*
G03X1826143Y251395I400J-1D01*
G02X1824885Y250006I144J-1395D01*
G03X1824444Y250405I-400J1D01*
G02X1825702Y251794I-144J1395D01*
G37*
G36*
G01X1736815Y249077D02*
G03X1736185I-315J-246D01*
G02Y250923I-1185J923D01*
G03X1736815I315J246D01*
G02X1739185I1185J-923D01*
G03X1739815I315J246D01*
G02Y249077I1185J-923D01*
G03X1739185I-315J-246D01*
G02X1736815I-1185J923D01*
G37*
G36*
G01X1690282Y249679D02*
G03X1689813Y249382I-80J-392D01*
G02X1687183Y249118I-1362J334D01*
G03X1686664Y249315I-362J-171D01*
G02X1685186Y249552I-551J1289D01*
G03X1684632Y249528I-265J-300D01*
G02X1684542Y251545I-1017J965D01*
G03X1685096Y251569I265J300D01*
G02X1687381Y251202I1017J-965D01*
G03X1687900Y251005I362J171D01*
G02X1688734Y251089I551J-1289D01*
G03X1689203Y251386I80J392D01*
G02X1690282Y249679I1362J-334D01*
G37*
G36*
G01X1597653Y247276D02*
G03X1598245Y247267I300J264D01*
G02X1598217Y245384I1025J-957D01*
G03X1597625Y245393I-300J-264D01*
G02X1597653Y247276I-1025J957D01*
G37*
G36*
G01X1468298Y245076D02*
G03X1467721Y244868I-201J-345D01*
G02X1467110Y246561I-1317J482D01*
G03X1467687Y246769I201J345D01*
G02X1470015Y247258I1317J-482D01*
G03X1470593I289J277D01*
G02Y245316I1011J-971D01*
G03X1470015I-289J-277D01*
G02X1468298Y245076I-1011J971D01*
G37*
G36*
G01X1510804Y246222D02*
G03X1510800Y245658I282J-284D01*
G02X1508810Y245669I-1000J-982D01*
G03X1508814Y246233I-282J284D01*
G02X1510804Y246222I1000J982D01*
G37*
G36*
G01X89773Y243304D02*
G03X89227I-273J-292D01*
G02X87277Y245585I-1027J1096D01*
G03Y246215I-246J315D01*
G02Y248585I923J1185D01*
G03Y249215I-246J315D01*
G02Y251585I923J1185D01*
G03Y252215I-246J315D01*
G02X87228Y254545I923J1185D01*
G03Y255155I-259J305D01*
G02X87104Y257327I972J1145D01*
G03Y257873I-292J273D01*
G02X89227Y259996I1096J1027D01*
G03X89773I273J292D01*
G02X91827I1027J-1096D01*
G03X92373I273J292D01*
G02X94427I1027J-1096D01*
G03X94973I273J292D01*
G02X97027I1027J-1096D01*
G03X97573I273J292D01*
G02X99696Y257873I1027J-1096D01*
G03Y257327I292J-273D01*
G02X99572Y255155I-1096J-1027D01*
G03Y254545I259J-305D01*
G02X99523Y252215I-972J-1145D01*
G03Y251585I246J-315D01*
G02Y249215I-923J-1185D01*
G03Y248585I246J-315D01*
G02Y246215I-923J-1185D01*
G03Y245585I246J-315D01*
G02X97573Y243304I-923J-1185D01*
G03X97027I-273J-292D01*
G02X94973I-1027J1096D01*
G03X94427I-273J-292D01*
G02X92373I-1027J1096D01*
G03X91827I-273J-292D01*
G02X89773I-1027J1096D01*
G37*
G36*
G01X1662588Y245377D02*
G03X1662981Y244984I400J7D01*
G02X1661554Y243557I-25J-1402D01*
G03X1661161Y243950I-400J-7D01*
G02X1662588Y245377I25J1402D01*
G37*
G36*
G01X1215804Y244399D02*
G03X1216413Y244396I306J258D01*
G02X1216404Y242579I1063J-914D01*
G03X1215795Y242582I-306J-258D01*
G02X1215804Y244399I-1063J914D01*
G37*
G36*
G01X569422Y242495D02*
G03X568860Y242491I-279J-286D01*
G02X566796Y242579I-992J991D01*
G03X566187Y242582I-306J-258D01*
G02X566196Y244399I-1063J914D01*
G03X566805Y244396I306J258D01*
G02X568846Y244487I1063J-914D01*
G03X569408Y244491I279J286D01*
G02X569422Y242495I992J-991D01*
G37*
G36*
G01X1548542Y245073D02*
G03X1548652Y244519I333J-222D01*
G02X1546702Y244133I-783J-1163D01*
G03X1546592Y244687I-333J222D01*
G02X1548542Y245073I783J1163D01*
G37*
G36*
G01X1515446Y244968D02*
G03X1515447Y244410I287J-278D01*
G02X1513296Y244409I-1075J-1049D01*
G03X1513295Y244967I-287J278D01*
G02X1513274Y247043I1075J1049D01*
G03X1513275Y247590I-291J274D01*
G02X1515468Y247589I1097J1026D01*
G03X1515467Y247042I291J-274D01*
G02X1515446Y244968I-1097J-1026D01*
G37*
G36*
G01X1626025Y242615D02*
G03X1626599Y242478I350J194D01*
G02X1625390Y240152I1543J-2279D01*
G03X1624948Y240543I-400J-7D01*
G02X1626025Y242615I-150J1394D01*
G37*
G36*
G01X1779451Y236100D02*
X1774450D01*
G02X1774451Y239324I1J1612D01*
G01X1779451D01*
G02X1781062Y237722I0J-1611D01*
G01Y237627D01*
X1781053Y237542D01*
G02X1779451Y236100I-1602J169D01*
G37*
G36*
G01X1760554D02*
X1755554D01*
G02Y239324I0J1612D01*
G01X1760555D01*
G02X1762166Y237722I-1J-1612D01*
G01Y237627D01*
X1762156Y237542D01*
G02X1760554Y236100I-1602J169D01*
G37*
G36*
G01X642637Y237601D02*
G03Y237055I292J-273D01*
G02X640445I-1096J-1027D01*
G03Y237601I-292J273D01*
G02Y239655I1096J1027D01*
G03Y240201I-292J273D01*
G02Y242255I1096J1027D01*
G03Y242801I-292J273D01*
G02X642637I1096J1027D01*
G03Y242255I292J-273D01*
G02Y240201I-1096J-1027D01*
G03Y239655I292J-273D01*
G02Y237601I-1096J-1027D01*
G37*
G36*
G01X1572141Y234659D02*
G03X1571596Y234427I-167J-363D01*
G02X1570861Y236161I-1324J462D01*
G03X1571406Y236393I167J363D01*
G02X1572753Y237333I1324J-462D01*
G03X1573159Y237717I6J400D01*
G02X1573165Y237800I1401J-60D01*
G03X1572933Y238017I-199J20D01*
G02X1572213Y238085I-233J1383D01*
G03X1571684Y237800I-139J-375D01*
G02X1570805Y239431I-1366J316D01*
G03X1571334Y239716I139J375D01*
G02X1573024Y240764I1366J-316D01*
G03X1573512Y241097I92J389D01*
G02X1574377Y239599I1388J-197D01*
G03X1574102Y239412I-75J-185D01*
G02X1574095Y239260I-1402J-12D01*
G03X1574327Y239043I199J-20D01*
G02X1574537Y236258I232J-1383D01*
G03X1574131Y235874I-6J-400D01*
G02X1572141Y234659I-1401J57D01*
G37*
G36*
G01X771881Y236329D02*
G03X771811Y235764I244J-317D01*
G02X769716Y236023I-1179J-931D01*
G03X769786Y236588I-244J317D01*
G02X769698Y236712I1179J930D01*
G03X769395Y236752I-168J-108D01*
G02X769546Y238811I-1013J1109D01*
G03X770089Y238739I310J253D01*
G02X772021Y238587I876J-1220D01*
G03X772617Y238625I281J285D01*
G02X772744Y236632I1183J-925D01*
G03X772148Y236594I-281J-285D01*
G02X771881Y236329I-1183J925D01*
G37*
G36*
G01X1844293Y237781D02*
G03X1844175Y237187I197J-348D01*
G02X1839851Y237383I-2246J-1757D01*
G03X1839724Y238022I-291J274D01*
G02X1841617Y238819I576J1278D01*
G03X1841985Y238281I376J-138D01*
G02X1842075Y238278I-50J-2851D01*
G03X1842275Y238543I11J200D01*
G02X1844293Y237781I1325J457D01*
G37*
G36*
G01X1682700Y234573D02*
G03X1683292Y234554I305J259D01*
G02X1683232Y232671I1008J-975D01*
G03X1682640Y232690I-305J-259D01*
G02X1682700Y234573I-1008J975D01*
G37*
G36*
G01X1767985Y232438D02*
G03X1767403Y232224I-204J-344D01*
G02X1766792Y233887I-1326J457D01*
G03X1767374Y234101I204J344D01*
G02X1767985Y232438I1326J-457D01*
G37*
G36*
G01X1804379Y233482D02*
G03X1805001Y233476I313J248D01*
G02X1804984Y231713I1082J-892D01*
G03X1804362Y231719I-313J-248D01*
G02X1804379Y233482I-1082J892D01*
G37*
G36*
G01X1794608Y234126D02*
G03X1794630Y233549I288J-278D01*
G02X1792692Y233474I-930J-1049D01*
G03X1792670Y234051I-288J278D01*
G02X1794608Y234126I930J1049D01*
G37*
G36*
G01X1883239Y233459D02*
G03X1883271Y232890I296J-269D01*
G02X1881306Y232778I-926J-1053D01*
G03X1881274Y233347I-296J269D01*
G02X1882924Y235600I926J1052D01*
G03X1883468Y235728I206J343D01*
G02X1883927Y233775I1183J-752D01*
G03X1883383Y233647I-206J-343D01*
G02X1883239Y233459I-1181J755D01*
G37*
G36*
G01X824285Y230658D02*
G03X823732Y230653I-274J-292D01*
G02X821586Y232754I-1050J1074D01*
G03Y233300I-292J273D01*
G02X821624Y235393I1096J1027D01*
G03Y235961I-282J284D01*
G02X821586Y238054I1058J1066D01*
G03Y238600I-292J273D01*
G02X823867Y240550I1096J1027D01*
G03X824497I315J246D01*
G02X826867I1185J-923D01*
G03X827497I315J246D01*
G02X829867I1185J-923D01*
G03X830497I315J246D01*
G02X832867I1185J-923D01*
G03X833497I315J246D01*
G02X835840Y240583I1185J-923D01*
G03X836433Y240557I308J255D01*
G02X838495Y238375I1068J-1056D01*
G03Y237775I265J-300D01*
G02X838596Y235623I-995J-1125D01*
G03Y235077I292J-273D01*
G02X838603Y235070I-1058J-1065D01*
G03X838915Y235092I147J135D01*
G02X839185Y233098I1240J-847D01*
G03X838627Y233057I-258J-305D01*
G02X836340Y233096I-1127J993D01*
G03X835751Y233127I-309J-254D01*
G02X833470Y233338I-1051J1073D01*
G03X832835Y233365I-328J-229D01*
G02X830497Y233404I-1153J962D01*
G03X829867I-315J-246D01*
G02X829550Y233101I-1185J923D01*
G03X829444Y232559I231J-327D01*
G02X827046Y230763I-1264J-811D01*
G03X826443Y230764I-302J-262D01*
G02X824285Y230658I-1130J989D01*
G37*
G36*
G01X175339Y230666D02*
G03X174685Y230622I-312J-251D01*
G02X172428Y232545I-1285J778D01*
G03Y233155I-259J305D01*
G02X172342Y235366I972J1145D01*
G03Y235934I-282J284D01*
G02X172428Y238145I1058J1066D01*
G03Y238755I-259J305D01*
G02X174585Y240823I972J1145D01*
G03X175215I315J246D01*
G02X177585I1185J-923D01*
G03X178215I315J246D01*
G02X180585I1185J-923D01*
G03X181215I315J246D01*
G02X183543Y240875I1185J-923D01*
G03X184142Y240864I304J259D01*
G02X186393Y240825I1108J-1014D01*
G03X186992Y240814I304J259D01*
G02X189062Y238646I1108J-1015D01*
G03X189083Y238015I256J-307D01*
G02X189255Y235731I-883J-1215D01*
G03X189276Y235142I281J-285D01*
G02X187023Y233210I-976J-1142D01*
G03X186381Y233262I-340J-211D01*
G02X184107Y233275I-1131J988D01*
G03X183508Y233286I-304J-259D01*
G02X181215Y233377I-1108J1014D01*
G03X180585I-315J-246D01*
G02X178215I-1185J923D01*
G03X177585I-315J-246D01*
G02X177503Y233280I-1187J920D01*
G03X177525Y232714I293J-272D01*
G02X175339Y230666I-1017J-1106D01*
G37*
G36*
G01X1926924Y232852D02*
G03X1926983Y232289I311J-252D01*
G02X1925011Y232083I-883J-1089D01*
G03X1924952Y232646I-311J252D01*
G02X1926924Y232852I883J1089D01*
G37*
G36*
G01X1499741Y233065D02*
G03X1499981Y232510I360J-174D01*
G02X1498296Y231783I-422J-1337D01*
G03X1498056Y232338I-360J174D01*
G02X1499741Y233065I422J1337D01*
G37*
G36*
G01X578805Y232720D02*
G03X578809Y232141I278J-288D01*
G02X576876Y232128I-960J-1022D01*
G03X576872Y232707I-278J288D01*
G02X578805Y232720I960J1022D01*
G37*
G36*
G01X1387761Y232456D02*
G03X1388231Y232161I388J96D01*
G02X1387157Y230451I287J-1372D01*
G03X1386687Y230746I-388J-96D01*
G02X1387761Y232456I-287J1372D01*
G37*
G36*
G01X571477Y230511D02*
G03X571449Y229950I270J-295D01*
G02X569455Y230047I-1045J-935D01*
G03X569483Y230608I-270J295D01*
G02X571477Y230511I1045J935D01*
G37*
G36*
G01X1939213Y229053D02*
G03X1939785Y229046I289J276D01*
G02X1939761Y226947I1062J-1062D01*
G03X1939189Y226954I-289J-276D01*
G02X1939213Y229053I-1062J1062D01*
G37*
G36*
G01X90173Y226354D02*
G03X89627I-273J-292D01*
G02X87677Y228635I-1027J1096D01*
G03Y229265I-246J315D01*
G02Y231635I923J1185D01*
G03Y232265I-246J315D01*
G02Y234635I923J1185D01*
G03Y235265I-246J315D01*
G02X89627Y237546I923J1185D01*
G03X90173I273J292D01*
G02X92227I1027J-1096D01*
G03X92773I273J292D01*
G02X94827I1027J-1096D01*
G03X95373I273J292D01*
G02X97427I1027J-1096D01*
G03X97973I273J292D01*
G02X99923Y235265I1027J-1096D01*
G03Y234635I246J-315D01*
G02Y232265I-923J-1185D01*
G03Y231635I246J-315D01*
G02Y229265I-923J-1185D01*
G03Y228635I246J-315D01*
G02X97973Y226354I-923J-1185D01*
G03X97427I-273J-292D01*
G02X95373I-1027J1096D01*
G03X94827I-273J-292D01*
G02X92773I-1027J1096D01*
G03X92227I-273J-292D01*
G02X90173I-1027J1096D01*
G37*
G36*
G01X703380Y225694D02*
G03X702770I-305J-259D01*
G02Y227506I-1070J906D01*
G03X703380I305J259D01*
G02Y225694I1070J-906D01*
G37*
G36*
G01X1253531Y228169D02*
G03X1253880Y227627I374J-143D01*
G02X1252796Y225241I-89J-1399D01*
G03X1252264Y225273I-284J-282D01*
G02X1250295Y225504I-869J1100D01*
G03X1249691Y225531I-314J-248D01*
G02X1249772Y227363I-1019J963D01*
G03X1250376Y227336I314J248D01*
G02X1250745Y227615I1018J-963D01*
G03X1250929Y228125I-185J355D01*
G02X1253531Y228169I1292J543D01*
G37*
G36*
G01X1945635Y227689D02*
G03X1945738Y227143I334J-220D01*
G02X1943753Y226770I-813J-1142D01*
G03X1943650Y227316I-334J220D01*
G02X1945635Y227689I813J1142D01*
G37*
G36*
G01X1627679Y224282D02*
G03X1627124Y224267I-270J-295D01*
G02X1627069Y226286I-1000J983D01*
G03X1627624Y226301I270J295D01*
G02X1627679Y224282I1000J-983D01*
G37*
G36*
G01X1883427Y223090D02*
G03X1882873I-277J-288D01*
G02Y225110I-973J1010D01*
G03X1883427I277J288D01*
G02Y223090I973J-1010D01*
G37*
G36*
G01X1401311Y222717D02*
G03X1400689I-311J-252D01*
G02Y224483I-1089J883D01*
G03X1401311I311J252D01*
G02Y222717I1089J-883D01*
G37*
G36*
G01X1622167Y224930D02*
G03Y224372I286J-279D01*
G02X1620161I-1003J-980D01*
G03Y224930I-286J279D01*
G02X1622167I1003J980D01*
G37*
G36*
G01X1245144Y223407D02*
G03X1244700Y223029I-44J-398D01*
G02X1243456Y224493I-1400J71D01*
G03X1243900Y224871I44J398D01*
G02X1245144Y223407I1400J-71D01*
G37*
G36*
G01X767662Y224140D02*
G03X767640Y223563I266J-299D01*
G02X765702Y223638I-1008J-974D01*
G03X765724Y224215I-266J299D01*
G02X767662Y224140I1008J974D01*
G37*
G36*
G01X638097Y223710D02*
G03Y223164I292J-273D01*
G02X635905I-1096J-1027D01*
G03Y223710I-292J273D01*
G02Y225764I1096J1027D01*
G03Y226310I-292J273D01*
G02Y228364I1096J1027D01*
G03Y228910I-292J273D01*
G02X638097I1096J1027D01*
G03Y228364I292J-273D01*
G02Y226310I-1096J-1027D01*
G03Y225764I292J-273D01*
G02Y223710I-1096J-1027D01*
G37*
G36*
G01X714708Y223170D02*
G03X714730Y222593I288J-278D01*
G02X712792Y222518I-930J-1049D01*
G03X712770Y223095I-288J278D01*
G02X714708Y223170I930J1049D01*
G37*
G36*
G01X115652Y224178D02*
G03X115823Y224709I-187J353D01*
G02X117738Y224092I1257J621D01*
G03X117567Y223561I187J-353D01*
G02X117707Y222824I-1257J-621D01*
G03X118084Y222391I399J-34D01*
G02X116611Y221107I-76J-1400D01*
G03X116234Y221540I-399J34D01*
G02X115652Y224178I76J1400D01*
G37*
G36*
G01X1911301Y222317D02*
G03X1911312Y221751I288J-278D01*
G02X1909279Y221657I-972J-1010D01*
G03X1909237Y222221I-303J261D01*
G02X1909148Y224412I982J1137D01*
G03X1909135Y224986I-285J281D01*
G02X1911224Y225036I1019J1104D01*
G03X1911237Y224462I285J-281D01*
G02X1911301Y222317I-1018J-1104D01*
G37*
G36*
G01X1627988Y218701D02*
G03X1628578Y218690I300J264D01*
G02X1628542Y216799I1017J-965D01*
G03X1627952Y216810I-300J-264D01*
G02X1627988Y218701I-1017J965D01*
G37*
G36*
G01X94077Y218891D02*
G03X94053Y219509I-266J299D01*
G02X93755Y219794I1088J1436D01*
G03X93150Y219805I-307J-256D01*
G02X90389Y219899I-1341J1204D01*
G03X89779Y219922I-315J-247D01*
G02X87038Y220013I-1332J1214D01*
G03X86446Y220050I-313J-249D01*
G02X86597Y222464I-1258J1290D01*
G03X87189Y222427I313J249D01*
G02X89867Y222246I1258J-1291D01*
G03X90477Y222223I315J247D01*
G02X93194Y222161I1332J-1214D01*
G03X93799Y222150I307J256D01*
G02X96338Y219600I1341J-1204D01*
G03X96362Y218982I266J-299D01*
G02X94077Y218891I-1087J-1437D01*
G37*
G36*
G01X1592264Y213948D02*
G03X1591703Y213814I-216J-337D01*
G02X1589500Y215513I-1208J711D01*
G03X1589507Y216069I-284J282D01*
G02X1590941Y218372I1018J964D01*
G03X1591421Y218583I118J382D01*
G02X1593973Y216738I1449J-683D01*
G03X1593975Y216155I275J-291D01*
G02X1592264Y213948I-955J-1026D01*
G37*
G36*
G01X1898421Y215540D02*
G03Y214962I277J-289D01*
G02X1896479I-971J-1011D01*
G03Y215540I-277J289D01*
G02X1898421I971J1011D01*
G37*
G36*
G01X1612670Y215183D02*
G03Y214574I260J-305D01*
G02X1610852I-909J-1067D01*
G03Y215183I-260J304D01*
G02X1612670I909J1067D01*
G37*
G36*
G01X715613Y215122D02*
G03X715771Y214575I349J-196D01*
G02X713878Y214031I-671J-1231D01*
G03X713720Y214578I-349J196D01*
G02X714134Y217187I671J1231D01*
G03X714431Y217733I-73J393D01*
G02X715984Y216889I1296J534D01*
G03X715687Y216343I73J-393D01*
G02X715613Y215122I-1296J-534D01*
G37*
G36*
G01X591383Y214711D02*
G03Y214089I252J-311D01*
G02X589617I-883J-1089D01*
G03Y214711I-252J311D01*
G02X591383I883J1089D01*
G37*
G36*
G01X824103Y213363D02*
G03X823732Y212838I9J-400D01*
G02X821128Y212989I-1332J-438D01*
G03X820912Y213529I-363J168D01*
G02X820541Y216108I554J1396D01*
G03X820606Y216674I-247J315D01*
G02X822886Y218628I1169J943D01*
G03X823448Y218598I296J269D01*
G02X825597Y218441I998J-1122D01*
G03X826202Y218431I307J257D01*
G02X828681Y216791I1120J-1001D01*
G03X829103Y216225I362J-170D01*
G02X830487Y215694I224J-1485D01*
G03X831107Y215697I309J254D01*
G02X831116Y213800I1169J-943D01*
G03X830496Y213797I-309J-254D01*
G02X828264Y213679I-1169J943D01*
G03X827712Y213692I-283J-283D01*
G02X825636Y213742I-1012J1110D01*
G03X825084Y213755I-283J-283D01*
G02X824103Y213363I-1012J1110D01*
G37*
G36*
G01X1814125Y210720D02*
X1809125D01*
G02Y213742I0J1511D01*
G01X1814126D01*
G02X1815636Y212241I-1J-1511D01*
G01Y212146D01*
X1815627Y212062D01*
G02X1814125Y210720I-1502J169D01*
G37*
G36*
G01X1801526D02*
X1796526D01*
G02Y213742I0J1511D01*
G01X1801527D01*
G02X1803038Y212241I0J-1512D01*
G01Y212146D01*
X1803028Y212062D01*
G02X1801526Y210720I-1502J169D01*
G37*
G36*
G01X1826685Y210650D02*
X1821685D01*
G02Y213672I0J1511D01*
G01X1826686D01*
G02X1828196Y212171I-1J-1511D01*
G01Y212076D01*
X1828187Y211992D01*
G02X1826685Y210650I-1502J169D01*
G37*
G36*
G01X778862Y211127D02*
G03X778252I-305J-259D01*
G02Y212939I-1070J906D01*
G03X778862I305J259D01*
G02Y211127I1070J-906D01*
G37*
G36*
G01X129393Y210985D02*
G03X128822Y210945I-266J-299D01*
G02X128685Y212901I-1068J908D01*
G03X129256Y212941I266J299D01*
G02X129393Y210985I1068J-908D01*
G37*
G36*
G01X1788925Y210120D02*
X1783925D01*
G02Y213142I0J1511D01*
G01X1788926D01*
G02X1790436Y211641I-1J-1511D01*
G01Y211546D01*
X1790427Y211462D01*
G02X1788925Y210120I-1502J169D01*
G37*
G36*
G01X1776325D02*
X1771325D01*
G02Y213142I0J1511D01*
G01X1776326D01*
G02X1777836Y211641I-1J-1511D01*
G01Y211546D01*
X1777827Y211462D01*
G02X1776325Y210120I-1502J169D01*
G37*
G36*
G01X1763725D02*
X1758725D01*
G02Y213142I0J1511D01*
G01X1763726D01*
G02X1765236Y211641I-1J-1511D01*
G01Y211546D01*
X1765227Y211462D01*
G02X1763725Y210120I-1502J169D01*
G37*
G36*
G01X1751125D02*
X1746125D01*
G02Y213142I0J1511D01*
G01X1751126D01*
G02X1752636Y211641I-1J-1511D01*
G01Y211546D01*
X1752627Y211462D01*
G02X1751125Y210120I-1502J169D01*
G37*
G36*
G01X1738484D02*
X1733484D01*
G02Y213142I0J1511D01*
G01X1738485D01*
G02X1739996Y211641I0J-1512D01*
G01Y211546D01*
X1739986Y211462D01*
G02X1738484Y210120I-1502J169D01*
G37*
G36*
G01X1863263Y210799D02*
G03X1862670Y210713I-259J-305D01*
G02X1860096Y211423I-1173J768D01*
G03X1859676Y211806I-400J-16D01*
G02X1861005Y213264I-72J1400D01*
G03X1861425Y212881I400J16D01*
G02X1862404Y212551I73J-1400D01*
G03X1862997Y212637I259J305D01*
G02X1863263Y210799I1173J-769D01*
G37*
G36*
G01X1726494Y210283D02*
G03X1725906I-294J-270D01*
G02Y212317I-1106J1017D01*
G03X1726494I294J270D01*
G02Y210283I1106J-1017D01*
G37*
G36*
G01X89628Y210958D02*
G03X89293Y210468I54J-396D01*
G02X85796Y210488I-1751J-425D01*
G03X85362Y210984I-388J99D01*
G02X83439Y213322I-206J1790D01*
G03X83114Y213840I-381J122D01*
G02X85083Y215076I252J1784D01*
G03X85408Y214558I381J-122D01*
G02X85527Y214537I-253J-1784D01*
G03X85753Y214810I41J196D01*
G02X89158Y215043I1663J694D01*
G03X89516Y214541I387J-103D01*
G02X89697Y214519I-127J-1797D01*
G03X89921Y214781I35J197D01*
G02X91562Y213563I1705J583D01*
G03X91155Y213087I-14J-400D01*
G02X89628Y210958I-1769J-343D01*
G37*
G36*
G01X1358537Y208181D02*
G03X1357965Y208159I-275J-290D01*
G02X1357889Y210119I-1039J941D01*
G03X1358461Y210141I275J290D01*
G02X1360432Y210247I1039J-941D01*
G03X1360987Y210269I266J299D01*
G02X1361068Y208253I1013J-969D01*
G03X1360513Y208231I-266J-299D01*
G02X1358537Y208181I-1013J969D01*
G37*
G36*
G01X1227826Y209464D02*
G03X1227844Y208909I297J-268D01*
G02X1225826Y208843I-977J-1005D01*
G03X1225808Y209398I-297J268D01*
G02X1225814Y211414I977J1005D01*
G03Y211992I-277J289D01*
G02X1225978Y214149I971J1011D01*
G03X1226070Y214713I-230J327D01*
G02X1228007Y214397I1130J830D01*
G03X1227915Y213833I230J-327D01*
G02X1227756Y211992I-1130J-830D01*
G03Y211414I277J-289D01*
G02X1227826Y209464I-971J-1011D01*
G37*
G36*
G01X1475934Y208720D02*
G03X1475721Y208189I153J-369D01*
G02X1473906Y208918I-1282J-568D01*
G03X1474119Y209449I-153J369D01*
G02X1475934Y208720I1282J568D01*
G37*
G36*
G01X1479760Y208891D02*
G03X1479846Y208343I328J-229D01*
G02X1477851Y208029I-846J-1118D01*
G03X1477765Y208577I-328J229D01*
G02X1479760Y208891I846J1118D01*
G37*
G36*
G01X617675Y205984D02*
G03X617121I-277J-288D01*
G02Y208004I-973J1010D01*
G03X617675I277J288D01*
G02X617771Y208088I970J-1012D01*
G03Y208400I-125J156D01*
G02X619658Y208521I877J1094D01*
G03Y207967I288J-277D01*
G02X619742Y207871I-1012J-970D01*
G03X620054I156J125D01*
G02X622121Y208004I1094J-877D01*
G03X622675I277J288D01*
G02X622771Y208088I970J-1012D01*
G03Y208400I-125J156D01*
G02X622638Y210467I877J1094D01*
G03Y211021I-288J277D01*
G02X622554Y211117I1012J970D01*
G03X622242I-156J-125D01*
G02X622121Y213004I-1094J877D01*
G03X622675I277J288D01*
G02X622771Y213088I970J-1012D01*
G03Y213400I-125J156D01*
G02X622638Y215467I877J1094D01*
G03Y216021I-288J277D01*
G02X622554Y216117I1012J970D01*
G03X622242I-156J-125D01*
G02X622121Y218004I-1094J877D01*
G03X622675I277J288D01*
G02X622771Y218088I970J-1012D01*
G03Y218400I-125J156D01*
G02X622638Y220467I877J1094D01*
G03Y221021I-288J277D01*
G02X622554Y221117I1012J970D01*
G03X622242I-156J-125D01*
G02X622121Y223004I-1094J877D01*
G03X622675I277J288D01*
G02X622771Y223088I970J-1012D01*
G03Y223400I-125J156D01*
G02X622638Y225467I877J1094D01*
G03Y226021I-288J277D01*
G02X622554Y226117I1012J970D01*
G03X622242I-156J-125D01*
G02X620175Y225984I-1094J877D01*
G03X619621I-277J-288D01*
G02X619525Y225900I-970J1012D01*
G03Y225588I125J-156D01*
G02X617638Y225467I-877J-1094D01*
G03Y226021I-288J277D01*
G02X617554Y226117I1012J970D01*
G03X617242I-156J-125D01*
G02X615175Y225984I-1094J877D01*
G03X614621I-277J-288D01*
G02X614525Y225900I-970J1012D01*
G03Y225588I125J-156D01*
G02X614658Y223521I-877J-1094D01*
G03Y222967I288J-277D01*
G02X614742Y222871I-1012J-970D01*
G03X615054I156J125D01*
G02X615175Y220984I1094J-877D01*
G03X614621I-277J-288D01*
G02X614525Y220900I-970J1012D01*
G03Y220588I125J-156D01*
G02X614658Y218521I-877J-1094D01*
G03Y217967I288J-277D01*
G02X614742Y217871I-1012J-970D01*
G03X615054I156J125D01*
G02X615175Y215984I1094J-877D01*
G03X614621I-277J-288D01*
G02X614525Y215900I-970J1012D01*
G03Y215588I125J-156D01*
G02X614658Y213521I-877J-1094D01*
G03Y212967I288J-277D01*
G02X614742Y212871I-1012J-970D01*
G03X615054I156J125D01*
G02X615175Y210984I1094J-877D01*
G03X614621I-277J-288D01*
G02X614525Y210900I-970J1012D01*
G03Y210588I125J-156D01*
G02X612638Y210467I-877J-1094D01*
G03Y211021I-288J277D01*
G02Y212967I1010J973D01*
G03Y213521I-288J277D01*
G02Y215467I1010J973D01*
G03Y216021I-288J277D01*
G02Y217967I1010J973D01*
G03Y218521I-288J277D01*
G02Y220467I1010J973D01*
G03Y221021I-288J277D01*
G02X612554Y221117I1012J970D01*
G03X612242I-156J-125D01*
G02X610138Y222967I-1094J877D01*
G03Y223521I-288J277D01*
G02X610054Y223617I1012J970D01*
G03X609742I-156J-125D01*
G02X607638Y225467I-1094J877D01*
G03Y226021I-288J277D01*
G02X609658I1010J973D01*
G03Y225467I288J-277D01*
G02X609742Y225371I-1012J-970D01*
G03X610054I156J125D01*
G02X612121Y225504I1094J-877D01*
G03X612675I277J288D01*
G02X612771Y225588I970J-1012D01*
G03Y225900I-125J156D01*
G02X612638Y227967I877J1094D01*
G03Y228521I-288J277D01*
G02X612554Y228617I1012J970D01*
G03X612242I-156J-125D01*
G02X612121Y230504I-1094J877D01*
G03X612675I277J288D01*
G02X614658Y228521I973J-1010D01*
G03Y227967I288J-277D01*
G02X614742Y227871I-1012J-970D01*
G03X615054I156J125D01*
G02X617121Y228004I1094J-877D01*
G03X617675I277J288D01*
G02X617771Y228088I970J-1012D01*
G03Y228400I-125J156D01*
G02X619621Y230504I877J1094D01*
G03X620175I277J288D01*
G02X622158Y228521I973J-1010D01*
G03Y227967I288J-277D01*
G02X622242Y227871I-1012J-970D01*
G03X622554I156J125D01*
G02X624658Y226021I1094J-877D01*
G03Y225467I288J-277D01*
G02Y223521I-1010J-973D01*
G03Y222967I288J-277D01*
G02Y221021I-1010J-973D01*
G03Y220467I288J-277D01*
G02Y218521I-1010J-973D01*
G03Y217967I288J-277D01*
G02Y216021I-1010J-973D01*
G03Y215467I288J-277D01*
G02Y213521I-1010J-973D01*
G03Y212967I288J-277D01*
G02Y211021I-1010J-973D01*
G03Y210467I288J-277D01*
G02Y208521I-1010J-973D01*
G03Y207967I288J-277D01*
G02X622675Y205984I-1010J-973D01*
G03X622121I-277J-288D01*
G02X620175I-973J1010D01*
G03X619621I-277J-288D01*
G02X617675I-973J1010D01*
G37*
G36*
G01X1856789Y207274D02*
G03X1857411Y207253I319J241D01*
G02X1857351Y205491I1059J-918D01*
G03X1856729Y205512I-319J-241D01*
G02X1856789Y207274I-1059J918D01*
G37*
G36*
G01X1222271Y206989D02*
G03Y206411I277J-289D01*
G02X1220329I-971J-1011D01*
G03Y206989I-277J289D01*
G02X1222271I971J1011D01*
G37*
G36*
G01X1517619Y204557D02*
G03X1517615Y204002I286J-280D01*
G02X1515595Y204017I-1017J-965D01*
G03X1515599Y204572I-286J280D01*
G02X1517619Y204557I1017J965D01*
G37*
G36*
G01X708189Y200329D02*
G03X707611I-289J-277D01*
G02X705762Y202424I-1011J971D01*
G03X705753Y203071I-240J320D01*
G02X707678Y205064I808J1146D01*
G03X708260Y205004I319J241D01*
G02X710479Y204479I922J-1056D01*
G03X711061Y204291I370J152D01*
G02X711171Y201847I739J-1191D01*
G03X710594Y201447I-179J-358D01*
G02X708189Y200329I-1394J-147D01*
G37*
G36*
G01X1884247Y201333D02*
G03X1884271Y201009I128J-153D01*
G02X1882499Y200753I-732J-1196D01*
G03X1882457Y201329I-297J268D01*
G02X1884491Y203224I893J1081D01*
G03X1885100Y203174I326J232D01*
G02X1884952Y201370I993J-990D01*
G03X1884343Y201420I-326J-232D01*
G02X1884247Y201333I-988J994D01*
G37*
G36*
G01X1227471Y201389D02*
G03Y200811I277J-289D01*
G02X1225529I-971J-1011D01*
G03Y201389I-277J289D01*
G02X1227471I971J1011D01*
G37*
G36*
G01X1546924Y199009D02*
G03X1546944Y198437I289J-276D01*
G02X1544986Y198368I-944J-1037D01*
G03X1544966Y198940I-289J276D01*
G02X1546924Y199009I944J1037D01*
G37*
G36*
G01X1763668Y195332D02*
X1758668D01*
G02Y198354I0J1511D01*
G01X1763669D01*
G02X1765180Y196853I0J-1512D01*
G01Y196758D01*
X1765170Y196674D01*
G02X1763668Y195332I-1502J169D01*
G37*
G36*
G01X1751082D02*
X1746082D01*
G02Y198354I0J1511D01*
G01X1751083D01*
G02X1752594Y196853I0J-1512D01*
G01Y196758D01*
X1752584Y196674D01*
G02X1751082Y195332I-1502J169D01*
G37*
G36*
G01X1826682Y195330D02*
X1821682D01*
G02Y198352I0J1511D01*
G01X1826683D01*
G02X1828194Y196851I0J-1512D01*
G01Y196756D01*
X1828184Y196672D01*
G02X1826682Y195330I-1502J169D01*
G37*
G36*
G01X1814041D02*
X1809041D01*
G02Y198352I0J1511D01*
G01X1814042D01*
G02X1815552Y196851I-1J-1511D01*
G01Y196756D01*
X1815543Y196672D01*
G02X1814041Y195330I-1502J169D01*
G37*
G36*
G01X1801441D02*
X1796441D01*
G02Y198352I0J1511D01*
G01X1801442D01*
G02X1802952Y196851I-1J-1511D01*
G01Y196756D01*
X1802943Y196672D01*
G02X1801441Y195330I-1502J169D01*
G37*
G36*
G01X1788841D02*
X1783841D01*
G02Y198352I0J1511D01*
G01X1788842D01*
G02X1790352Y196851I-1J-1511D01*
G01Y196756D01*
X1790343Y196672D01*
G02X1788841Y195330I-1502J169D01*
G37*
G36*
G01X1776241D02*
X1771241D01*
G02Y198352I0J1511D01*
G01X1776242D01*
G02X1777752Y196851I-1J-1511D01*
G01Y196756D01*
X1777743Y196672D01*
G02X1776241Y195330I-1502J169D01*
G37*
G36*
G01X720641Y196447D02*
G03X721181Y196442I273J293D01*
G02X721162Y194373I936J-1043D01*
G03X720622Y194378I-273J-293D01*
G02X720641Y196447I-936J1043D01*
G37*
G36*
G01X1638880Y196604D02*
G03Y196050I288J-277D01*
G02X1636860I-1010J-973D01*
G03Y196604I-288J277D01*
G02X1638880I1010J973D01*
G37*
G36*
G01X44856Y266869D02*
X44734Y266817D01*
Y197413D01*
X39300Y191980D01*
X11160D01*
X7096Y196043D01*
Y230657D01*
X2126Y235627D01*
Y264825D01*
X8820Y271518D01*
Y338949D01*
X14153Y344282D01*
X40824D01*
X44734Y340373D01*
Y269503D01*
X44856Y269451D01*
G02Y266869I-546J-1291D01*
G37*
G36*
G01X1708794Y193293D02*
G02X1712894Y191735I3218J2294D01*
G02X1708794Y193293I-882J3852D01*
G37*
G36*
G01X1210925Y194189D02*
G03X1210909Y193567I243J-317D01*
G02X1209145Y193611I-909J-1067D01*
G03X1209161Y194233I-243J317D01*
G02X1210925Y194189I909J1067D01*
G37*
G36*
G01X1621217Y184110D02*
G03X1620607Y184084I-294J-271D01*
G02X1620531Y185894I-1107J860D01*
G03X1621141Y185920I294J271D01*
G02X1621217Y184110I1107J-860D01*
G37*
G36*
G01X1609625Y183827D02*
G03X1609071Y183803I-265J-300D01*
G02X1608985Y185821I-1015J968D01*
G03X1609539Y185845I265J300D01*
G02X1611497Y185914I1014J-968D01*
G03X1612052Y185930I269J296D01*
G02X1614042Y185943I1001J-981D01*
G03X1614597Y185934I282J283D01*
G02X1614564Y183914I956J-1026D01*
G03X1614009Y183923I-282J-283D01*
G02X1612110Y183912I-955J1026D01*
G03X1611555Y183896I-269J-296D01*
G02X1609625Y183827I-1001J981D01*
G37*
G36*
G01X1682294Y182678D02*
G03X1681795Y182531I-164J-365D01*
G02X1679261Y184475I-1345J870D01*
G03X1679252Y184752I-148J134D01*
G02X1681967Y186024I1118J1148D01*
G03X1682483Y185672I399J31D01*
G02X1682294Y182678I467J-1532D01*
G37*
G36*
G01X1656005Y183496D02*
G03X1656044Y182887I277J-288D01*
G02X1654235Y182770I-835J-1126D01*
G03X1654196Y183379I-277J288D01*
G02X1656005Y183496I835J1126D01*
G37*
G36*
G01X1493491Y178427D02*
G03X1493498Y177872I291J-274D01*
G02X1491478Y177847I-998J-985D01*
G03X1491471Y178402I-291J274D01*
G02X1493491Y178427I998J985D01*
G37*
G36*
G01X1615377Y178062D02*
G03X1615891Y177756I393J75D01*
G02X1615021Y176207I395J-1241D01*
G03X1614492Y176487I-389J-94D01*
G02X1615377Y178062I-492J1313D01*
G37*
G36*
G01X1820382Y175014D02*
X1815382D01*
G02Y178036I0J1511D01*
G01X1820383D01*
G02X1821894Y176535I0J-1512D01*
G01Y176440D01*
X1821884Y176356D01*
G02X1820382Y175014I-1502J169D01*
G37*
G36*
G01X1807784D02*
X1802784D01*
G02Y178036I0J1511D01*
G01X1807785D01*
G02X1809296Y176535I0J-1512D01*
G01Y176440D01*
X1809286Y176356D01*
G02X1807784Y175014I-1502J169D01*
G37*
G36*
G01X1795185D02*
X1790185D01*
G02Y178036I0J1511D01*
G01X1795185D01*
G02X1796696Y176535I0J-1511D01*
G01Y176440D01*
X1796687Y176356D01*
G02X1795185Y175014I-1502J169D01*
G37*
G36*
G01X1782587D02*
X1777587D01*
G02Y178036I0J1511D01*
G01X1782588D01*
G02X1784098Y176535I-1J-1511D01*
G01Y176440D01*
X1784089Y176356D01*
G02X1782587Y175014I-1502J169D01*
G37*
G36*
G01X1764988Y178036D02*
X1769989D01*
G02X1771500Y176535I0J-1512D01*
G01Y176440D01*
X1771490Y176356D01*
G02X1769988Y175014I-1502J169D01*
G01X1764987D01*
G02X1764988Y178036I1J1511D01*
G37*
G36*
G01X1739792D02*
X1744793D01*
G02X1746304Y176535I0J-1512D01*
G01Y176440D01*
X1746294Y176356D01*
G02X1744792Y175014I-1502J169D01*
G01X1739792D01*
G02Y178036I1J1511D01*
G37*
G36*
G01X1732193Y175014D02*
X1727193D01*
G02Y178036I1J1511D01*
G01X1732193D01*
G02X1733704Y176535I0J-1511D01*
G01Y176440D01*
X1733695Y176356D01*
G02X1732193Y175014I-1502J169D01*
G37*
G36*
G01X1254266Y174954D02*
G03X1253734I-266J-298D01*
G02Y177046I-934J1046D01*
G03X1254266I266J298D01*
G02Y174954I934J-1046D01*
G37*
G36*
G01X1856427Y174890D02*
G03X1855873I-277J-288D01*
G02Y176910I-973J1010D01*
G03X1856427I277J288D01*
G02Y174890I973J-1010D01*
G37*
G36*
G01X1876467Y175734D02*
G03X1876859Y175321I400J-13D01*
G02X1875431Y173967I-27J-1402D01*
G03X1875039Y174380I-400J13D01*
G02X1876467Y175734I27J1402D01*
G37*
G36*
G01X1472924Y172703D02*
G03X1472369Y172698I-275J-290D01*
G02X1472352Y174718I-981J1002D01*
G03X1472907Y174723I275J290D01*
G02X1472924Y172703I981J-1002D01*
G37*
G36*
G01X1245937Y172140D02*
G03X1245383I-277J-288D01*
G02X1243022Y173350I-973J1010D01*
G03X1242665Y173805I-396J57D01*
G02X1244188Y175000I135J1395D01*
G03X1244545Y174545I396J-57D01*
G02X1245383Y174160I-134J-1396D01*
G03X1245937I277J288D01*
G02Y172140I973J-1010D01*
G37*
G36*
G01X1614863Y174222D02*
G03X1615392Y173999I373J145D01*
G02X1614687Y172328I508J-1199D01*
G03X1614158Y172551I-373J-145D01*
G02X1613179Y172536I-508J1199D01*
G03X1612674Y172336I-144J-373D01*
G02X1610429Y172159I-1174J564D01*
G03X1609894Y172274I-329J-228D01*
G02X1610293Y174130I-672J1115D01*
G03X1610828Y174015I329J228D01*
G02X1611971Y174114I672J-1115D01*
G03X1612476Y174314I144J373D01*
G02X1614863Y174222I1174J-564D01*
G37*
G36*
G01X43144Y170972D02*
X43129Y170974D01*
X36880D01*
Y177224D01*
X36877Y177239D01*
G02Y179533I7414J1147D01*
G01X36880Y179548D01*
Y185798D01*
X43129D01*
X43144Y185800D01*
G02X45438I1147J-7414D01*
G01X45453Y185798D01*
X51702D01*
Y179548D01*
X51705Y179533D01*
G02Y177239I-7414J-1147D01*
G01X51702Y177224D01*
Y170974D01*
X45453D01*
X45438Y170972D01*
G02X43144I-1147J7414D01*
G37*
G36*
G01X1596648Y171344D02*
G03X1596036I-306J-258D01*
G02Y173024I-994J840D01*
G03X1596648I306J258D01*
G02Y171344I994J-840D01*
G37*
G36*
G01X1887371Y171589D02*
G03Y171011I277J-289D01*
G02X1885429I-971J-1011D01*
G03Y171589I-277J289D01*
G02X1887371I971J1011D01*
G37*
G36*
G01X1701968Y162401D02*
G03X1702523Y162390I283J283D01*
G02X1702478Y160081I1087J-1176D01*
G03X1701923Y160092I-283J-283D01*
G02X1701968Y162401I-1087J1176D01*
G37*
G36*
G01X1840909Y158413D02*
G03X1840924Y157858I295J-270D01*
G02X1838905Y157803I-983J-1000D01*
G03X1838890Y158358I-295J270D01*
G02X1840909Y158413I983J1000D01*
G37*
G36*
G01X1531912Y157489D02*
G03X1532143Y156930I358J-179D01*
G02X1530362Y155182I-443J-1330D01*
G03X1529807Y155424I-382J-119D01*
G02X1531912Y157489I-1963J4107D01*
G37*
G36*
G01X20473Y158250D02*
G03X21740Y158653I-2J2199D01*
G02X21756Y154015I1488J-2314D01*
G03X20502Y154428I-1283J-1786D01*
G01X20471D01*
G03X19204Y154025I2J-2199D01*
G02X19188Y158663I-1488J2314D01*
G03X20442Y158250I1283J1786D01*
G01X20473D01*
G37*
G36*
G01X3938D02*
G03X5205Y158653I-2J2199D01*
G02X5221Y154015I1488J-2314D01*
G03X3967Y154428I-1283J-1786D01*
G01X3936D01*
G03X2669Y154025I2J-2199D01*
G02X2653Y158663I-1488J2314D01*
G03X3907Y158250I1283J1786D01*
G01X3938D01*
G37*
G36*
G01X-12598D02*
G03X-11331Y158653I-2J2199D01*
G02X-11315Y154015I1488J-2314D01*
G03X-12569Y154428I-1283J-1786D01*
G01X-12599D01*
G03X-13866Y154025I2J-2199D01*
G02X-13882Y158663I-1488J2314D01*
G03X-12628Y158250I1283J1786D01*
G01X-12598D01*
G37*
G36*
G01X51309Y152844D02*
X47309D01*
G02Y155868I0J1512D01*
G01X51310D01*
G02X52820Y154366I-1J-1512D01*
G01Y154271D01*
X52811Y154187D01*
G02X51309Y152844I-1502J168D01*
G37*
G36*
G01X1788818Y155649D02*
G03X1789375Y155428I376J136D01*
G02X1788550Y153595I725J-1428D01*
G03X1788016Y153866I-387J-101D01*
G02X1788818Y155649I-516J1304D01*
G37*
G36*
G01X1700076Y154255D02*
G03X1700357Y154249I144J140D01*
G02X1700306Y151967I1098J-1166D01*
G03X1700025Y151973I-144J-140D01*
G02X1700076Y154255I-1098J1166D01*
G37*
G36*
G01X1876493Y153833D02*
G03X1877086Y153815I305J259D01*
G02X1877028Y151935I1010J-972D01*
G03X1876435Y151953I-305J-259D01*
G02X1876493Y153833I-1010J972D01*
G37*
G36*
G01X1913160Y153727D02*
G03X1913765Y153634I342J208D01*
G02X1913491Y151853I925J-1054D01*
G03X1912886Y151946I-342J-208D01*
G02X1913160Y153727I-925J1054D01*
G37*
G36*
G01X1514888Y153600D02*
G03X1515300Y153144I396J-57D01*
G02X1513970Y151943I58J-1401D01*
G03X1513558Y152399I-396J57D01*
G02X1514888Y153600I-58J1401D01*
G37*
G36*
G01X1885299Y154911D02*
G03X1885233Y155526I-285J280D01*
G02X1887000Y155717I767J1174D01*
G03X1887066Y155102I285J-280D01*
G02X1887203Y152857I-767J-1173D01*
G03X1887148Y152303I258J-305D01*
G02X1885146Y152502I-1098J-872D01*
G03X1885201Y153056I-258J305D01*
G02X1885299Y154911I1098J872D01*
G37*
G36*
G01X68098Y149962D02*
X63098D01*
G02Y152984I0J1511D01*
G01X68099D01*
G02X69610Y151483I0J-1512D01*
G01Y151388D01*
X69600Y151304D01*
G02X68098Y149962I-1502J169D01*
G37*
G36*
G01X1265136Y151576D02*
G03X1265691Y151567I282J284D01*
G02X1265656Y149548I955J-1026D01*
G03X1265101Y149557I-282J-284D01*
G02X1263135Y149613I-955J1027D01*
G03X1262557I-289J-277D01*
G02Y151555I-1011J971D01*
G03X1263135I289J277D01*
G02X1265136Y151576I1011J-971D01*
G37*
G36*
G01X1574971Y151089D02*
G03Y150511I277J-289D01*
G02X1573029I-971J-1011D01*
G03Y151089I-277J289D01*
G02X1574971I971J1011D01*
G37*
G36*
G01X1945607Y150725D02*
G03X1945609Y150166I287J-278D01*
G02X1943602Y150159I-1000J-982D01*
G03X1943600Y150718I-287J278D01*
G02X1945607Y150725I1000J982D01*
G37*
G36*
G01X1295155Y148431D02*
G03X1294732Y148064I-24J-400D01*
G02X1291935Y148249I-1397J113D01*
G03X1291580Y148668I-400J21D01*
G02X1291742Y151463I156J1393D01*
G03X1292143Y151839I2J400D01*
G02X1292145Y151862I1398J-110D01*
G03X1291752Y152292I-399J30D01*
G02X1293170Y153588I20J1402D01*
G03X1293563Y153158I399J-30D01*
G02X1293594Y153157I-30J-1402D01*
G03X1293797Y153396I7J200D01*
G02X1295303Y152274I1375J274D01*
G03X1294942Y151849I38J-398D01*
G02Y151657I-1399J-96D01*
G03X1295318Y151230I399J-28D01*
G02X1295155Y148431I-78J-1400D01*
G37*
G36*
G01X1496967Y149755D02*
G03X1497034Y149203I319J-241D01*
G02X1495031Y148960I-884J-1088D01*
G03X1494964Y149512I-319J241D01*
G02X1496967Y149755I884J1088D01*
G37*
G36*
G01X1964194Y149150D02*
G03X1964545Y148710I398J-43D01*
G02X1962988Y147468I-163J-1392D01*
G03X1962637Y147908I-398J43D01*
G02X1964194Y149150I163J1392D01*
G37*
G36*
G01X25591Y150376D02*
G03X26858Y150779I-2J2199D01*
G02X26874Y146141I1488J-2314D01*
G03X25620Y146554I-1283J-1786D01*
G01X25590D01*
G03X24323Y146151I2J-2199D01*
G02X24307Y150789I-1488J2314D01*
G03X25561Y150376I1283J1786D01*
G01X25591D01*
G37*
G36*
G01X9056D02*
G03X10323Y150779I-2J2199D01*
G02X10339Y146141I1488J-2314D01*
G03X9085Y146554I-1283J-1786D01*
G01X9054D01*
G03X7787Y146151I2J-2199D01*
G02X7771Y150789I-1488J2314D01*
G03X9025Y150376I1283J1786D01*
G01X9056D01*
G37*
G36*
G01X-7480D02*
G03X-6213Y150779I-2J2199D01*
G02X-6197Y146141I1488J-2314D01*
G03X-7451Y146554I-1283J-1786D01*
G01X-7481D01*
G03X-8748Y146151I2J-2199D01*
G02X-8764Y150789I-1488J2314D01*
G03X-7510Y150376I1283J1786D01*
G01X-7480D01*
G37*
G36*
G01X1278933Y147438D02*
G03X1278927Y146832I258J-306D01*
G02X1277097Y146852I-927J-1052D01*
G03X1277103Y147458I-258J306D01*
G02X1278933Y147438I927J1052D01*
G37*
G36*
G01X1490661Y145218D02*
G03X1490195Y144863I-68J-394D01*
G02X1489039Y146382I-1395J138D01*
G03X1489505Y146737I68J394D01*
G02X1490661Y145218I1395J-138D01*
G37*
G36*
G01X1533237Y146370D02*
G03X1533446Y145819I358J-180D01*
G02X1531671Y145148I-523J-1301D01*
G03X1531462Y145699I-358J180D01*
G02X1533237Y146370I523J1301D01*
G37*
G36*
G01X1849616Y143180D02*
G03X1849627Y142581I270J-295D01*
G02X1847506Y142540I-1037J-1221D01*
G03X1847495Y143139I-270J295D01*
G02X1849616Y143180I1037J1221D01*
G37*
G36*
G01X1267743Y140626D02*
G03X1267208Y140322I-141J-375D01*
G02X1266321Y141880I-1380J246D01*
G03X1266856Y142184I141J375D01*
G02X1267743Y140626I1380J-246D01*
G37*
G36*
G01X62342Y144760D02*
Y139665D01*
X62333Y139581D01*
G02X59320Y139750I-1502J169D01*
G01Y144750D01*
G02X62342Y144760I1511J0D01*
G37*
G36*
G01X48412D02*
Y139665D01*
X48402Y139581D01*
G02X45388Y139750I-1502J169D01*
G01Y144750D01*
G02X48412Y144760I1512J0D01*
G37*
G36*
G01X3938Y142502D02*
G03X5205Y142905I-2J2199D01*
G02X5221Y138267I1488J-2314D01*
G03X3967Y138680I-1283J-1786D01*
G01X3936D01*
G03X2669Y138277I2J-2199D01*
G02X2653Y142915I-1488J2314D01*
G03X3907Y142502I1283J1786D01*
G01X3938D01*
G37*
G36*
G01X-12598D02*
G03X-11331Y142905I-2J2199D01*
G02X-11315Y138267I1488J-2314D01*
G03X-12569Y138680I-1283J-1786D01*
G01X-12599D01*
G03X-13866Y138277I2J-2199D01*
G02X-13882Y142915I-1488J2314D01*
G03X-12628Y142502I1283J1786D01*
G01X-12598D01*
G37*
G36*
G01X1452354Y140426D02*
G03X1452435Y139869I322J-238D01*
G02X1450464Y139585I-845J-1119D01*
G03X1450383Y140142I-322J238D01*
G02X1450207Y142221I845J1118D01*
G03X1450200Y142776I-292J274D01*
G02X1450259Y144802I998J985D01*
G03X1450267Y145389I-268J297D01*
G02X1452172Y145364I966J1016D01*
G03X1452164Y144777I268J-297D01*
G02X1452219Y142801I-966J-1016D01*
G03X1452226Y142246I292J-274D01*
G02X1452354Y140426I-998J-985D01*
G37*
G36*
G01X1856050Y137539D02*
G03X1855450I-300J-265D01*
G02Y139661I-1200J1061D01*
G03X1856050I300J265D01*
G02Y137539I1200J-1061D01*
G37*
G36*
G01X1846743Y136086D02*
G03X1847327Y135919I364J167D01*
G02X1846826Y134164I773J-1170D01*
G03X1846242Y134331I-364J-167D01*
G02X1846743Y136086I-773J1170D01*
G37*
G36*
G01X67198Y137760D02*
Y132665D01*
X67189Y132581D01*
G02X64176Y132750I-1502J169D01*
G01Y137750D01*
G02X67198Y137760I1511J0D01*
G37*
G36*
G01X53080D02*
Y132665D01*
X53071Y132581D01*
G02X50058Y132750I-1502J169D01*
G01Y137751D01*
G02X53080Y137760I1511J-1D01*
G37*
G36*
G01X1920235Y133456D02*
G03X1920306Y132858I297J-268D01*
G02X1918474Y132641I-792J-1157D01*
G03X1918403Y133239I-297J268D01*
G02X1920235Y133456I792J1157D01*
G37*
G36*
G01X25591Y134628D02*
G03X26858Y135031I-2J2199D01*
G02X26874Y130393I1488J-2314D01*
G03X25620Y130806I-1283J-1786D01*
G01X25590D01*
G03X24323Y130403I2J-2199D01*
G02X24307Y135041I-1488J2314D01*
G03X25561Y134628I1283J1786D01*
G01X25591D01*
G37*
G36*
G01X1855539Y132335D02*
G03X1855351Y131782I165J-364D01*
G02X1853538Y132399I-1236J-661D01*
G03X1853726Y132952I-165J364D01*
G02X1855539Y132335I1236J661D01*
G37*
G36*
G01X1580308Y130140D02*
G03X1580312Y129585I290J-275D01*
G02X1578292Y129568I-1002J-981D01*
G03X1578288Y130123I-290J275D01*
G02X1580308Y130140I1002J981D01*
G37*
G36*
G01X1469569Y130197D02*
G03X1469606Y129592I279J-287D01*
G02X1467776Y129481I-851J-1114D01*
G03X1467739Y130086I-279J287D01*
G02X1469569Y130197I851J1114D01*
G37*
G36*
G01X1920681Y127497D02*
G03Y126924I279J-287D01*
G02X1918723I-979J-1004D01*
G03Y127497I-279J286D01*
G02X1920681I979J1004D01*
G37*
G36*
G01X62342Y130760D02*
Y125665D01*
X62333Y125581D01*
G02X59320Y125750I-1502J169D01*
G01Y130750D01*
G02X62342Y130760I1511J0D01*
G37*
G36*
G01X48412D02*
Y125665D01*
X48402Y125581D01*
G02X45388Y125750I-1502J169D01*
G01Y130750D01*
G02X48412Y130760I1512J0D01*
G37*
G36*
G01X-12598Y126754D02*
G03X-11331Y127157I-2J2199D01*
G02X-11315Y122519I1488J-2314D01*
G03X-12569Y122932I-1283J-1786D01*
G01X-12599D01*
G03X-13866Y122529I2J-2199D01*
G02X-13882Y127167I-1488J2314D01*
G03X-12628Y126754I1283J1786D01*
G01X-12598D01*
G37*
G36*
G01X1270489Y121529D02*
G03X1269911I-289J-277D01*
G02Y123471I-1011J971D01*
G03X1270489I289J277D01*
G02Y121529I1011J-971D01*
G37*
G36*
G01X1543504Y120435D02*
G03X1543326Y119880I172J-361D01*
G02X1541496Y120465I-1226J-680D01*
G03X1541674Y121020I-172J361D01*
G02X1543504Y120435I1226J680D01*
G37*
G36*
G01X1760020Y118137D02*
G03X1759380I-320J-240D01*
G02Y120063I-1280J963D01*
G03X1760020I320J240D01*
G02Y118137I1280J-963D01*
G37*
G36*
G01X53080Y123760D02*
Y118665D01*
X53071Y118581D01*
G02X50058Y118750I-1502J169D01*
G01Y123751D01*
G02X53080Y123760I1511J-1D01*
G37*
G36*
G01X63894Y123731D02*
G02X66916Y123740I1511J-1D01*
G01Y118730D01*
X66917D01*
X66916Y118645D01*
X66907Y118561D01*
G02X63894Y118730I-1502J169D01*
G01Y123731D01*
G37*
G36*
G01X1474064Y119985D02*
G03X1474087Y119386I276J-289D01*
G02X1472232Y119314I-887J-1086D01*
G03X1472209Y119913I-276J289D01*
G02X1471986Y121856I887J1086D01*
G03X1471854Y122456I-316J245D01*
G02X1473610Y122843I646J1244D01*
G03X1473742Y122243I316J-245D01*
G02X1474064Y119985I-646J-1244D01*
G37*
G36*
G01X1528024Y120779D02*
Y115684D01*
X1528015Y115600D01*
G02X1525002Y115769I-1502J169D01*
G01Y120769D01*
G02X1528024Y120779I1511J0D01*
G37*
G36*
G01X25591Y118880D02*
G03X26858Y119283I-2J2199D01*
G02X26874Y114645I1488J-2314D01*
G03X25620Y115058I-1283J-1786D01*
G01X25590D01*
G03X24323Y114655I2J-2199D01*
G02X24307Y119293I-1488J2314D01*
G03X25561Y118880I1283J1786D01*
G01X25591D01*
G37*
G36*
G01X9054Y115058D02*
G03X7787Y114655I2J-2199D01*
G02X7771Y119293I-1488J2314D01*
G03X9025Y118880I1283J1786D01*
G01X9056D01*
G03X10323Y119283I-2J2199D01*
G02X10339Y114645I1488J-2314D01*
G03X9085Y115058I-1283J-1786D01*
G01X9054D01*
G37*
G36*
G01X1907363Y116972D02*
G03X1907375Y116373I271J-294D01*
G02X1905518Y116337I-908J-1068D01*
G03X1905506Y116936I-271J294D01*
G02X1907363Y116972I908J1068D01*
G37*
G36*
G01X1303475Y113289D02*
G03Y112711I277J-289D01*
G02X1301533I-971J-1011D01*
G03Y113289I-277J289D01*
G02X1301458Y115234I971J1011D01*
G03Y115766I-298J266D01*
G02X1301467Y117644I1046J934D01*
G03X1301472Y118177I-295J269D01*
G02X1303563Y118158I1054J925D01*
G03X1303558Y117625I295J-269D01*
G02X1303550Y115766I-1054J-925D01*
G03Y115234I298J-266D01*
G02X1303475Y113289I-1046J-934D01*
G37*
G36*
G01X62212Y116760D02*
Y111665D01*
X62202Y111581D01*
G02X59188Y111750I-1502J169D01*
G01Y116750D01*
G02X62212Y116760I1512J0D01*
G37*
G36*
G01X48412D02*
Y111665D01*
X48402Y111581D01*
G02X45388Y111750I-1502J169D01*
G01Y116750D01*
G02X48412Y116760I1512J0D01*
G37*
G36*
G01X1599633Y109786D02*
G03X1599093Y109773I-263J-301D01*
G02X1599047Y111691I-903J938D01*
G03X1599587Y111704I263J301D01*
G02X1599633Y109786I903J-938D01*
G37*
G36*
G01X1188924Y109493D02*
G03X1188929Y108905I274J-292D01*
G02X1187028Y108886I-940J-1040D01*
G03X1187023Y109474I-274J292D01*
G02X1188924Y109493I940J1040D01*
G37*
G36*
G01X1152113D02*
G03X1152118Y108905I274J-292D01*
G02X1150217Y108886I-940J-1040D01*
G03X1150212Y109474I-274J292D01*
G02X1152113Y109493I940J1040D01*
G37*
G36*
G01X934593D02*
G03X934598Y108905I274J-292D01*
G02X932697Y108886I-940J-1040D01*
G03X932692Y109474I-274J292D01*
G02X934593Y109493I940J1040D01*
G37*
G36*
G01X897782D02*
G03X897787Y108905I274J-292D01*
G02X895886Y108886I-940J-1040D01*
G03X895881Y109474I-274J292D01*
G02X897782Y109493I940J1040D01*
G37*
G36*
G01X539316D02*
G03X539321Y108905I274J-292D01*
G02X537420Y108886I-940J-1040D01*
G03X537415Y109474I-274J292D01*
G02X539316Y109493I940J1040D01*
G37*
G36*
G01X502505D02*
G03X502510Y108905I274J-292D01*
G02X500609Y108886I-940J-1040D01*
G03X500604Y109474I-274J292D01*
G02X502505Y109493I940J1040D01*
G37*
G36*
G01X284985D02*
G03X284990Y108905I274J-292D01*
G02X283089Y108886I-940J-1040D01*
G03X283084Y109474I-274J292D01*
G02X284985Y109493I940J1040D01*
G37*
G36*
G01X248174D02*
G03X248179Y108905I274J-292D01*
G02X246278Y108886I-940J-1040D01*
G03X246273Y109474I-274J292D01*
G02X248174Y109493I940J1040D01*
G37*
G36*
G01X20473Y111006D02*
G03X21740Y111409I-2J2199D01*
G02X21756Y106771I1488J-2314D01*
G03X20502Y107184I-1283J-1786D01*
G01X20471D01*
G03X19204Y106781I2J-2199D01*
G02X19188Y111419I-1488J2314D01*
G03X20442Y111006I1283J1786D01*
G01X20473D01*
G37*
G36*
G01X3936Y107184D02*
G03X2669Y106781I2J-2199D01*
G02X2653Y111419I-1488J2314D01*
G03X3907Y111006I1283J1786D01*
G01X3938D01*
G03X5205Y111409I-2J2199D01*
G02X5221Y106771I1488J-2314D01*
G03X3967Y107184I-1283J-1786D01*
G01X3936D01*
G37*
G36*
G01X-12598Y111006D02*
G03X-11331Y111409I-2J2199D01*
G02X-11315Y106771I1488J-2314D01*
G03X-12569Y107184I-1283J-1786D01*
G01X-12599D01*
G03X-13866Y106781I2J-2199D01*
G02X-13882Y111419I-1488J2314D01*
G03X-12628Y111006I1283J1786D01*
G01X-12598D01*
G37*
G36*
G01X1194046Y109239D02*
G03X1194040Y108660I273J-292D01*
G02X1192106Y108680I-977J-1005D01*
G03X1192112Y109259I-273J292D01*
G02X1194046Y109239I977J1005D01*
G37*
G36*
G01X1157235D02*
G03X1157229Y108660I273J-292D01*
G02X1155295Y108680I-977J-1005D01*
G03X1155301Y109259I-273J292D01*
G02X1157235Y109239I977J1005D01*
G37*
G36*
G01X939715D02*
G03X939709Y108660I273J-292D01*
G02X937775Y108680I-977J-1005D01*
G03X937781Y109259I-273J292D01*
G02X939715Y109239I977J1005D01*
G37*
G36*
G01X902904D02*
G03X902898Y108660I273J-292D01*
G02X900964Y108680I-977J-1005D01*
G03X900970Y109259I-273J292D01*
G02X902904Y109239I977J1005D01*
G37*
G36*
G01X544438D02*
G03X544432Y108660I273J-292D01*
G02X542498Y108680I-977J-1005D01*
G03X542504Y109259I-273J292D01*
G02X544438Y109239I977J1005D01*
G37*
G36*
G01X507627D02*
G03X507621Y108660I273J-292D01*
G02X505687Y108680I-977J-1005D01*
G03X505693Y109259I-273J292D01*
G02X507627Y109239I977J1005D01*
G37*
G36*
G01X290107D02*
G03X290101Y108660I273J-292D01*
G02X288167Y108680I-977J-1005D01*
G03X288173Y109259I-273J292D01*
G02X290107Y109239I977J1005D01*
G37*
G36*
G01X253296D02*
G03X253290Y108660I273J-292D01*
G02X251356Y108680I-977J-1005D01*
G03X251362Y109259I-273J292D01*
G02X253296Y109239I977J1005D01*
G37*
G36*
G01X1853181Y106802D02*
G03X1852743Y106393I-38J-398D01*
G02X1851477Y107753I-1402J-35D01*
G03X1851915Y108162I38J398D01*
G02X1853181Y106802I1402J35D01*
G37*
G36*
G01X66896Y109760D02*
Y104665D01*
X66886Y104581D01*
G02X63872Y104750I-1502J169D01*
G01Y109751D01*
G02X66896Y109760I1512J-1D01*
G37*
G36*
G01X52892D02*
Y104665D01*
X52883Y104581D01*
G02X49870Y104750I-1502J169D01*
G01Y109750D01*
G02X52892Y109760I1511J0D01*
G37*
G36*
G01X1512424Y108332D02*
G02X1515446Y108342I1511J0D01*
G01Y104447D01*
X1515437Y104363D01*
G02X1512424Y104532I-1502J169D01*
G01Y108332D01*
G37*
G36*
G01X1811259Y105468D02*
G03X1811814Y105445I289J276D01*
G02X1811729Y103427I929J-1050D01*
G03X1811174Y103450I-289J-276D01*
G02X1811259Y105468I-929J1050D01*
G37*
G36*
G01X1525004Y103876D02*
X1524995Y104048D01*
X1524994D01*
X1525295Y109060D01*
X1525327Y109232D01*
G02X1528314Y109136I1486J-275D01*
G01X1528335Y108960D01*
X1528378D01*
X1528498Y108816D01*
X1528246Y107442D01*
X1528032Y103868D01*
X1528031Y103867D01*
X1528027Y103788D01*
X1528015Y103789D01*
G02X1525004Y103876I-1502J168D01*
G37*
G36*
G01X1490430Y104578D02*
G03X1490268Y104024I185J-355D01*
G02X1488403Y104567I-1215J-699D01*
G03X1488565Y105121I-185J355D01*
G02X1490430Y104578I1215J699D01*
G37*
G36*
G01X700017Y103801D02*
G03X699840Y103255I176J-359D01*
G02X697587Y101631I-1240J-655D01*
G03X697032Y101653I-289J-277D01*
G02X694970Y101870I-932J1047D01*
G03X694415Y101959I-323J-236D01*
G02X692290Y103599I-815J1141D01*
G03X691892Y104140I-374J142D01*
G02X692897Y106425I-82J1400D01*
G03X693485Y106390I310J253D01*
G02X695554Y106258I974J-1008D01*
G03X696081Y106170I312J249D01*
G02X697803Y105998I751J-1184D01*
G03X698373Y106014I277J288D01*
G02X700454Y105984I1027J-954D01*
G03X701021Y105949I301J264D01*
G02X703095Y105716I932J-1047D01*
G03X703642Y105615I326J232D01*
G02X703277Y103634I777J-1167D01*
G03X702730Y103735I-326J-232D01*
G02X700899Y103978I-777J1167D01*
G03X700332Y104013I-301J-264D01*
G02X700017Y103801I-933J1046D01*
G37*
G36*
G01X743520Y101574D02*
G03X742965Y101396I-194J-350D01*
G02X742380Y103226I-1265J604D01*
G03X742935Y103404I194J350D01*
G02X744736Y104095I1265J-604D01*
G03X745269Y104340I153J370D01*
G02X746064Y102605I1331J-440D01*
G03X745531Y102360I-153J-370D01*
G02X743520Y101574I-1331J440D01*
G37*
G36*
G01X25591Y103132D02*
G03X26858Y103535I-2J2199D01*
G02X26874Y98897I1488J-2314D01*
G03X25620Y99310I-1283J-1786D01*
G01X25590D01*
G03X24323Y98907I2J-2199D01*
G02X24307Y103545I-1488J2314D01*
G03X25561Y103132I1283J1786D01*
G01X25591D01*
G37*
G36*
G01X9054Y99310D02*
G03X7787Y98907I2J-2199D01*
G02X7771Y103545I-1488J2314D01*
G03X9025Y103132I1283J1786D01*
G01X9056D01*
G03X10323Y103535I-2J2199D01*
G02X10339Y98897I1488J-2314D01*
G03X9085Y99310I-1283J-1786D01*
G01X9054D01*
G37*
G36*
G01X-7480Y103132D02*
G03X-6213Y103535I-2J2199D01*
G02X-6197Y98897I1488J-2314D01*
G03X-7451Y99310I-1283J-1786D01*
G01X-7481D01*
G03X-8748Y98907I2J-2199D01*
G02X-8764Y103545I-1488J2314D01*
G03X-7510Y103132I1283J1786D01*
G01X-7480D01*
G37*
G36*
G01X1500216Y99529D02*
G02X1497194Y99501I-1511J-7D01*
G01X1497149Y102725D01*
G02X1500161Y102924I1511J21D01*
G01X1500169Y102860D01*
X1500171Y102795D01*
G02X1500172Y102767I-1510J-68D01*
G01Y102746D01*
X1500216Y99544D01*
G02Y99529I-1511J-8D01*
G37*
G36*
G01X757771Y100989D02*
G03Y100411I277J-289D01*
G02X755829I-971J-1011D01*
G03Y100989I-277J289D01*
G02X757771I971J1011D01*
G37*
G36*
G01X1375685Y100772D02*
G03Y100460I125J-156D01*
G02X1373798Y100339I-877J-1094D01*
G03Y100893I-288J277D01*
G02Y102839I1010J973D01*
G03Y103393I-288J277D01*
G02Y105339I1010J973D01*
G03Y105893I-288J277D01*
G02X1375781Y107876I1010J973D01*
G03X1376335I277J288D01*
G02X1378318Y105893I973J-1010D01*
G03Y105339I288J-277D01*
G02Y103393I-1010J-973D01*
G03Y102839I288J-277D01*
G02X1376335Y100856I-1010J-973D01*
G03X1375781I-277J-288D01*
G02X1375685Y100772I-970J1012D01*
G37*
G36*
G01X1687931Y99885D02*
G03X1688484Y99838I301J264D01*
G02X1688313Y97827I884J-1088D01*
G03X1687760Y97874I-301J-264D01*
G02X1687931Y99885I-884J1088D01*
G37*
G36*
G01X1659322Y99975D02*
G03X1659840Y99785I359J177D01*
G02X1659108Y97957I560J-1285D01*
G03X1658601Y98177I-369J-155D01*
G02X1659322Y99975I-447J1223D01*
G37*
G36*
G01X62312Y102760D02*
Y97665D01*
X62303Y97581D01*
G02X59290Y97750I-1502J169D01*
G01Y102751D01*
G02X62312Y102760I1511J-1D01*
G37*
G36*
G01X48412D02*
Y97665D01*
X48402Y97581D01*
G02X45388Y97750I-1502J169D01*
G01Y102751D01*
G02X48412Y102760I1512J-1D01*
G37*
G36*
G01X1542883Y98810D02*
G03X1542905Y98277I309J-254D01*
G02X1540817Y98190I-1005J-977D01*
G03X1540795Y98723I-309J254D01*
G02X1542883Y98810I1005J977D01*
G37*
G36*
G01X763520Y94433D02*
G03X762998Y94166I-137J-376D01*
G02X762130Y95867I-1348J384D01*
G03X762652Y96134I137J376D01*
G02X763520Y94433I1348J-384D01*
G37*
G36*
G01X1525232Y98265D02*
G02X1528256Y98275I1512J0D01*
G01Y93180D01*
X1528246Y93096D01*
G02X1525232Y93265I-1502J169D01*
G01Y98265D01*
G37*
G36*
G01X1405579Y90903D02*
G03X1404913I-333J-222D01*
G02X1403448Y93050I-1167J777D01*
G03X1403759Y93494I-85J391D01*
G02X1406205Y94601I1390J185D01*
G03X1406829Y94628I301J263D01*
G02X1408382Y92463I1131J-828D01*
G03X1408113Y91993I121J-381D01*
G02X1405579Y90903I-1367J-313D01*
G37*
G36*
G01X35367Y93038D02*
G03X35733Y92550I390J-89D01*
G02X34283Y91462I-83J-1400D01*
G03X33917Y91950I-390J89D01*
G02X35367Y93038I83J1400D01*
G37*
G36*
G01X1908421Y92839D02*
G03X1908430Y92252I276J-289D01*
G02X1906392Y92220I-1002J-1119D01*
G03X1906383Y92807I-276J289D01*
G02X1906348Y92840I1013J1109D01*
G03X1905778Y92823I-277J-289D01*
G02X1903649Y94939I-1100J1022D01*
G03X1903662Y95508I-274J291D01*
G02X1905786Y97632I1080J1044D01*
G03X1906355Y97645I278J288D01*
G02X1908485Y95528I1092J-1031D01*
G03X1908472Y94963I276J-289D01*
G02X1908421Y92839I-1087J-1037D01*
G37*
G36*
G01X68725Y89388D02*
X63724D01*
G02X63725Y92412I1J1512D01*
G01X68725D01*
G02X70236Y90910I-1J-1512D01*
G01Y90815D01*
X70227Y90731D01*
G02X68725Y89388I-1502J168D01*
G37*
G36*
G01X52892Y95760D02*
Y90665D01*
X52883Y90581D01*
G02X49870Y90750I-1502J169D01*
G01Y95750D01*
G02X52892Y95760I1511J0D01*
G37*
G36*
G01X1676372Y91718D02*
G03X1676946Y91514I374J142D01*
G02X1676339Y89802I703J-1213D01*
G03X1675765Y90006I-374J-142D01*
G02X1676372Y91718I-703J1213D01*
G37*
G36*
G01X733655Y89330D02*
G03X734242Y89312I302J263D01*
G02X734185Y87407I999J-983D01*
G03X733598Y87425I-302J-263D01*
G02X731603Y87422I-999J983D01*
G03X731034I-284J-282D01*
G02Y89394I-996J986D01*
G03X731603I285J282D01*
G02X733655Y89330I996J-986D01*
G37*
G36*
G01X1542878Y89123D02*
G03X1542807Y88580I253J-309D01*
G02X1540780Y88844I-1137J-820D01*
G03X1540851Y89387I-253J309D01*
G02X1540978Y91180I1137J820D01*
G03Y91734I-288J277D01*
G02X1543287Y93234I1010J973D01*
G03X1543774Y93002I371J151D01*
G02X1543857Y90296I406J-1342D01*
G03X1543370Y89973I-92J-389D01*
G02X1542878Y89123I-1383J233D01*
G37*
G36*
G01X1230845Y89103D02*
G03Y88525I277J-289D01*
G02X1228903I-971J-1011D01*
G03Y89103I-277J289D01*
G02X1230845I971J1011D01*
G37*
G36*
G01X1194034D02*
G03Y88525I277J-289D01*
G02X1192092I-971J-1011D01*
G03Y89103I-277J289D01*
G02X1194034I971J1011D01*
G37*
G36*
G01X1157223D02*
G03Y88525I277J-289D01*
G02X1155281I-971J-1011D01*
G03Y89103I-277J289D01*
G02X1157223I971J1011D01*
G37*
G36*
G01X1120411D02*
G03Y88525I277J-289D01*
G02X1118469I-971J-1011D01*
G03Y89103I-277J289D01*
G02X1120411I971J1011D01*
G37*
G36*
G01X939703D02*
G03Y88525I277J-289D01*
G02X937761I-971J-1011D01*
G03Y89103I-277J289D01*
G02X939703I971J1011D01*
G37*
G36*
G01X902892D02*
G03Y88525I277J-289D01*
G02X900950I-971J-1011D01*
G03Y89103I-277J289D01*
G02X902892I971J1011D01*
G37*
G36*
G01X866081D02*
G03Y88525I277J-289D01*
G02X864139I-971J-1011D01*
G03Y89103I-277J289D01*
G02X866081I971J1011D01*
G37*
G36*
G01X829270D02*
G03Y88525I277J-289D01*
G02X827328I-971J-1011D01*
G03Y89103I-277J289D01*
G02X829270I971J1011D01*
G37*
G36*
G01X792459D02*
G03Y88525I277J-289D01*
G02X790517I-971J-1011D01*
G03Y89103I-277J289D01*
G02X792459I971J1011D01*
G37*
G36*
G01X581237D02*
G03Y88525I277J-289D01*
G02X579295I-971J-1011D01*
G03Y89103I-277J289D01*
G02X581237I971J1011D01*
G37*
G36*
G01X544426D02*
G03Y88525I277J-289D01*
G02X542484I-971J-1011D01*
G03Y89103I-277J289D01*
G02X544426I971J1011D01*
G37*
G36*
G01X507615D02*
G03Y88525I277J-289D01*
G02X505673I-971J-1011D01*
G03Y89103I-277J289D01*
G02X507615I971J1011D01*
G37*
G36*
G01X470803D02*
G03Y88525I277J-289D01*
G02X468861I-971J-1011D01*
G03Y89103I-277J289D01*
G02X470803I971J1011D01*
G37*
G36*
G01X290095D02*
G03Y88525I277J-289D01*
G02X288153I-971J-1011D01*
G03Y89103I-277J289D01*
G02X290095I971J1011D01*
G37*
G36*
G01X253284D02*
G03Y88525I277J-289D01*
G02X251342I-971J-1011D01*
G03Y89103I-277J289D01*
G02X253284I971J1011D01*
G37*
G36*
G01X216473D02*
G03Y88525I277J-289D01*
G02X214531I-971J-1011D01*
G03Y89103I-277J289D01*
G02X216473I971J1011D01*
G37*
G36*
G01X179662D02*
G03Y88525I277J-289D01*
G02X177720I-971J-1011D01*
G03Y89103I-277J289D01*
G02X179662I971J1011D01*
G37*
G36*
G01X142851D02*
G03Y88525I277J-289D01*
G02X140909I-971J-1011D01*
G03Y89103I-277J289D01*
G02X142851I971J1011D01*
G37*
G36*
G01X1225745Y88889D02*
G03Y88311I277J-289D01*
G02X1223803I-971J-1011D01*
G03Y88889I-277J289D01*
G02X1225745I971J1011D01*
G37*
G36*
G01X1188934D02*
G03Y88311I277J-289D01*
G02X1186992I-971J-1011D01*
G03Y88889I-277J289D01*
G02X1188934I971J1011D01*
G37*
G36*
G01X1152123D02*
G03Y88311I277J-289D01*
G02X1150181I-971J-1011D01*
G03Y88889I-277J289D01*
G02X1152123I971J1011D01*
G37*
G36*
G01X1115311D02*
G03Y88311I277J-289D01*
G02X1113369I-971J-1011D01*
G03Y88889I-277J289D01*
G02X1115311I971J1011D01*
G37*
G36*
G01X934603D02*
G03Y88311I277J-289D01*
G02X932661I-971J-1011D01*
G03Y88889I-277J289D01*
G02X934603I971J1011D01*
G37*
G36*
G01X897792D02*
G03Y88311I277J-289D01*
G02X895850I-971J-1011D01*
G03Y88889I-277J289D01*
G02X897792I971J1011D01*
G37*
G36*
G01X860981D02*
G03Y88311I277J-289D01*
G02X859039I-971J-1011D01*
G03Y88889I-277J289D01*
G02X860981I971J1011D01*
G37*
G36*
G01X824170D02*
G03Y88311I277J-289D01*
G02X822228I-971J-1011D01*
G03Y88889I-277J289D01*
G02X824170I971J1011D01*
G37*
G36*
G01X787359D02*
G03Y88311I277J-289D01*
G02X785417I-971J-1011D01*
G03Y88889I-277J289D01*
G02X787359I971J1011D01*
G37*
G36*
G01X576137D02*
G03Y88311I277J-289D01*
G02X574195I-971J-1011D01*
G03Y88889I-277J289D01*
G02X576137I971J1011D01*
G37*
G36*
G01X539326D02*
G03Y88311I277J-289D01*
G02X537384I-971J-1011D01*
G03Y88889I-277J289D01*
G02X539326I971J1011D01*
G37*
G36*
G01X502515D02*
G03Y88311I277J-289D01*
G02X500573I-971J-1011D01*
G03Y88889I-277J289D01*
G02X502515I971J1011D01*
G37*
G36*
G01X465703D02*
G03Y88311I277J-289D01*
G02X463761I-971J-1011D01*
G03Y88889I-277J289D01*
G02X465703I971J1011D01*
G37*
G36*
G01X284995D02*
G03Y88311I277J-289D01*
G02X283053I-971J-1011D01*
G03Y88889I-277J289D01*
G02X284995I971J1011D01*
G37*
G36*
G01X248184D02*
G03Y88311I277J-289D01*
G02X246242I-971J-1011D01*
G03Y88889I-277J289D01*
G02X248184I971J1011D01*
G37*
G36*
G01X211373D02*
G03Y88311I277J-289D01*
G02X209431I-971J-1011D01*
G03Y88889I-277J289D01*
G02X211373I971J1011D01*
G37*
G36*
G01X174562D02*
G03Y88311I277J-289D01*
G02X172620I-971J-1011D01*
G03Y88889I-277J289D01*
G02X174562I971J1011D01*
G37*
G36*
G01X137751D02*
G03Y88311I277J-289D01*
G02X135809I-971J-1011D01*
G03Y88889I-277J289D01*
G02X137751I971J1011D01*
G37*
G36*
G01X1810901Y85810D02*
G03X1810333I-284J-282D01*
G02X1808171Y87895I-1065J1059D01*
G03Y88441I-292J273D01*
G02X1808209Y90534I1096J1027D01*
G03Y91102I-282J284D01*
G02Y93234I1058J1066D01*
G03Y93802I-282J284D01*
G02X1810333Y95926I1058J1066D01*
G03X1810901I284J282D01*
G02X1813033I1066J-1058D01*
G03X1813601I284J282D01*
G02X1815725Y93802I1066J-1058D01*
G03Y93234I282J-284D01*
G02Y91102I-1058J-1066D01*
G03Y90534I282J-284D01*
G02X1815763Y88441I-1058J-1066D01*
G03Y87895I292J-273D01*
G02X1813601Y85810I-1097J-1026D01*
G03X1813033I-284J-282D01*
G02X1810901I-1066J1058D01*
G37*
G36*
G01X1501386Y90491D02*
Y86596D01*
X1501377Y86512D01*
G02X1498364Y86681I-1502J169D01*
G01Y90481D01*
G02X1501386Y90491I1511J0D01*
G37*
G36*
G01X1598489Y83529D02*
G03X1597911I-289J-277D01*
G02Y85471I-1011J971D01*
G03X1598489I289J277D01*
G02X1600473Y85510I1011J-971D01*
G03X1601027I277J288D01*
G02Y83490I973J-1010D01*
G03X1600473I-277J-288D01*
G02X1598489Y83529I-973J1010D01*
G37*
G36*
G01X1953132Y85697D02*
G03X1953664Y85419I388J95D01*
G02X1952807Y83777I505J-1308D01*
G03X1952275Y84055I-388J-95D01*
G02X1950797Y84353I-505J1308D01*
G03X1950243I-277J-288D01*
G02X1948259Y84392I-973J1010D01*
G03X1947681I-289J-277D01*
G02X1945660Y86336I-1010J972D01*
G03Y86890I-288J277D01*
G02X1945623Y88795I1010J972D01*
G03X1945601Y89350I-299J266D01*
G02X1945560Y91336I969J1013D01*
G03Y91890I-288J277D01*
G02X1947581Y93834I1011J972D01*
G03X1948159I289J277D01*
G02X1948419Y94047I1012J-970D01*
G03X1948517Y94635I-214J338D01*
G02X1950583Y96523I1092J879D01*
G03X1951137I277J288D01*
G02X1953293Y96265I973J-1010D01*
G03X1953904Y96187I338J214D01*
G02X1955834Y96173I958J-1024D01*
G03X1956388I277J288D01*
G02X1958096Y93969I972J-1010D01*
G03X1957992Y93381I210J-340D01*
G02X1955918Y91503I-1100J-869D01*
G03X1955364I-277J-288D01*
G02X1953216Y91747I-973J1010D01*
G03X1952613Y91825I-335J-218D01*
G02X1952547Y91769I-940J1041D01*
G03Y91457I125J-156D01*
G02X1952717Y89431I-877J-1094D01*
G03X1952739Y88876I299J-266D01*
G02X1952780Y86890I-969J-1013D01*
G03Y86336I288J-277D01*
G02X1953132Y85697I-1010J-973D01*
G37*
G36*
G01X753559Y85177D02*
G03X753577Y84578I274J-292D01*
G02X751721Y84523I-897J-1078D01*
G03X751703Y85122I-274J292D01*
G02X753559Y85177I897J1078D01*
G37*
G36*
G01X1491579Y84665D02*
G03X1491783Y84181I380J-125D01*
G02X1489789Y83197I-619J-1258D01*
G03X1489529Y83653I-392J78D01*
G02X1491579Y84665I528J1512D01*
G37*
G36*
G01X1664527Y80590D02*
G03X1663973I-277J-288D01*
G02Y82610I-973J1010D01*
G03X1664527I277J288D01*
G02X1666473I973J-1010D01*
G03X1667027I277J288D01*
G02X1668973I973J-1010D01*
G03X1669527I277J288D01*
G02X1671473I973J-1010D01*
G03X1672027I277J288D01*
G02X1673973I973J-1010D01*
G03X1674527I277J288D01*
G02X1676473I973J-1010D01*
G03X1677027I277J288D01*
G02Y80590I973J-1010D01*
G03X1676473I-277J-288D01*
G02X1674527I-973J1010D01*
G03X1673973I-277J-288D01*
G02X1672027I-973J1010D01*
G03X1671473I-277J-288D01*
G02X1669527I-973J1010D01*
G03X1668973I-277J-288D01*
G02X1667027I-973J1010D01*
G03X1666473I-277J-288D01*
G02X1664527I-973J1010D01*
G37*
G36*
G01X1540631Y78303D02*
G03X1540043Y78212I-253J-310D01*
G02X1539759Y80064I-1173J768D01*
G03X1540347Y80155I253J310D01*
G02X1540631Y78303I1173J-768D01*
G37*
G36*
G01X1695009Y79103D02*
G03X1695533Y79134I244J317D01*
G02Y76848I1122J-1143D01*
G03X1695009Y76879I-280J-286D01*
G02X1693182Y76981I-854J1112D01*
G03X1692628I-277J-288D01*
G02X1690682I-973J1010D01*
G03X1690128I-277J-288D01*
G02Y79001I-973J1010D01*
G03X1690682I277J288D01*
G02X1692628I973J-1010D01*
G03X1693182I277J288D01*
G02X1695009Y79103I973J-1010D01*
G37*
G36*
G01X1822089Y76271D02*
G03X1821521I-284J-282D01*
G02X1819377Y78375I-1065J1059D01*
G03X1819384Y78925I-287J279D01*
G02X1821554Y81001I1104J1018D01*
G03X1822122I284J282D01*
G02X1824266Y78897I1065J-1059D01*
G03X1824259Y78347I287J-279D01*
G02X1822089Y76271I-1104J-1018D01*
G37*
G36*
G01X1394060Y75160D02*
G03X1393524I-268J-297D01*
G02X1391612Y77211I-940J1040D01*
G03Y77787I-277J288D01*
G02X1393523Y79839I972J1011D01*
G03X1394059Y79840I267J297D01*
G02X1395934Y79846I941J-1040D01*
G03X1396466I266J298D01*
G02X1398371Y77789I934J-1045D01*
G03Y77211I277J-289D01*
G02X1396466Y75154I-971J-1012D01*
G03X1395934I-266J-298D01*
G02X1394060Y75160I-934J1046D01*
G37*
G36*
G01X1581396Y74870D02*
G03X1580818I-289J-277D01*
G02Y76812I-1011J971D01*
G03X1581396I289J277D01*
G02Y74870I1011J-971D01*
G37*
G36*
G01X1571535Y76354D02*
G03X1572104Y76339I292J273D01*
G02X1572052Y74370I972J-1011D01*
G03X1571483Y74385I-292J-273D01*
G02X1571535Y76354I-972J1011D01*
G37*
G36*
G01X732634Y74469D02*
G03X732024Y74447I-296J-270D01*
G02X731960Y76258I-1101J868D01*
G03X732570Y76280I296J270D01*
G02X732634Y74469I1101J-868D01*
G37*
G36*
G01X1622583Y74541D02*
G03X1622036Y74329I-175J-359D01*
G02X1621350Y76106I-1303J518D01*
G03X1621897Y76318I175J359D01*
G02X1622583Y74541I1303J-518D01*
G37*
G36*
G01X1675015Y75899D02*
G03X1675598Y75776I347J200D01*
G02X1675213Y73947I830J-1130D01*
G03X1674630Y74070I-347J-200D01*
G02X1675015Y75899I-830J1130D01*
G37*
G36*
G01X1680934Y75447D02*
G03X1681488Y75412I295J270D01*
G02X1681362Y73397I908J-1068D01*
G03X1680808Y73432I-295J-270D01*
G02X1680934Y75447I-908J1068D01*
G37*
G36*
G01X1454277Y74673D02*
G03X1454869Y74662I301J263D01*
G02X1454833Y72777I1020J-962D01*
G03X1454241Y72788I-301J-263D01*
G02X1454277Y74673I-1020J962D01*
G37*
G36*
G01X1563646Y75326D02*
G03X1563707Y74752I306J-258D01*
G02X1561779Y74547I-857J-1110D01*
G03X1561718Y75121I-306J258D01*
G02X1563646Y75326I857J1110D01*
G37*
G36*
G01X1895824Y72653D02*
G03X1895156Y72632I-327J-230D01*
G02X1893701Y74743I-1195J733D01*
G03X1894010Y75250I-74J393D01*
G02X1896722Y75344I1344J400D01*
G03X1897081Y74858I390J-87D01*
G02X1895824Y72653I-111J-1398D01*
G37*
G36*
G01X1825029Y71312D02*
G03X1825054Y70681I258J-306D01*
G02X1823028Y68497I-873J-1222D01*
G03X1822416Y68499I-307J-257D01*
G02X1820278Y70598I-1146J971D01*
G03X1820236Y71231I-264J300D01*
G02X1822257Y73401I834J1249D01*
G03X1822886Y73396I316J245D01*
G02X1825029Y71312I1175J-936D01*
G37*
G36*
G01X1795700Y70821D02*
G03X1796100Y70402I400J-19D01*
G01X1796101D01*
G02X1794500Y68877I-1J-1602D01*
G03X1794100Y69296I-400J19D01*
G01X1794099D01*
G02X1795700Y70821I1J1602D01*
G37*
G36*
G01X1225735Y70178D02*
G03X1225740Y69590I274J-292D01*
G02X1223839Y69571I-940J-1040D01*
G03X1223834Y70159I-274J292D01*
G02X1225735Y70178I940J1040D01*
G37*
G36*
G01X1188924D02*
G03X1188929Y69590I274J-292D01*
G02X1187028Y69571I-940J-1040D01*
G03X1187023Y70159I-274J292D01*
G02X1188924Y70178I940J1040D01*
G37*
G36*
G01X1152113D02*
G03X1152118Y69590I274J-292D01*
G02X1150217Y69571I-940J-1040D01*
G03X1150212Y70159I-274J292D01*
G02X1152113Y70178I940J1040D01*
G37*
G36*
G01X1115301D02*
G03X1115306Y69590I274J-292D01*
G02X1113405Y69571I-940J-1040D01*
G03X1113400Y70159I-274J292D01*
G02X1115301Y70178I940J1040D01*
G37*
G36*
G01X934593D02*
G03X934598Y69590I274J-292D01*
G02X932697Y69571I-940J-1040D01*
G03X932692Y70159I-274J292D01*
G02X934593Y70178I940J1040D01*
G37*
G36*
G01X897782D02*
G03X897787Y69590I274J-292D01*
G02X895886Y69571I-940J-1040D01*
G03X895881Y70159I-274J292D01*
G02X897782Y70178I940J1040D01*
G37*
G36*
G01X860971D02*
G03X860976Y69590I274J-292D01*
G02X859075Y69571I-940J-1040D01*
G03X859070Y70159I-274J292D01*
G02X860971Y70178I940J1040D01*
G37*
G36*
G01X824160D02*
G03X824165Y69590I274J-292D01*
G02X822264Y69571I-940J-1040D01*
G03X822259Y70159I-274J292D01*
G02X824160Y70178I940J1040D01*
G37*
G36*
G01X787349D02*
G03X787354Y69590I274J-292D01*
G02X785453Y69571I-940J-1040D01*
G03X785448Y70159I-274J292D01*
G02X787349Y70178I940J1040D01*
G37*
G36*
G01X576127D02*
G03X576132Y69590I274J-292D01*
G02X574231Y69571I-940J-1040D01*
G03X574226Y70159I-274J292D01*
G02X576127Y70178I940J1040D01*
G37*
G36*
G01X539316D02*
G03X539321Y69590I274J-292D01*
G02X537420Y69571I-940J-1040D01*
G03X537415Y70159I-274J292D01*
G02X539316Y70178I940J1040D01*
G37*
G36*
G01X502505D02*
G03X502510Y69590I274J-292D01*
G02X500609Y69571I-940J-1040D01*
G03X500604Y70159I-274J292D01*
G02X502505Y70178I940J1040D01*
G37*
G36*
G01X465693D02*
G03X465698Y69590I274J-292D01*
G02X463797Y69571I-940J-1040D01*
G03X463792Y70159I-274J292D01*
G02X465693Y70178I940J1040D01*
G37*
G36*
G01X284985D02*
G03X284990Y69590I274J-292D01*
G02X283089Y69571I-940J-1040D01*
G03X283084Y70159I-274J292D01*
G02X284985Y70178I940J1040D01*
G37*
G36*
G01X248174D02*
G03X248179Y69590I274J-292D01*
G02X246278Y69571I-940J-1040D01*
G03X246273Y70159I-274J292D01*
G02X248174Y70178I940J1040D01*
G37*
G36*
G01X211363D02*
G03X211368Y69590I274J-292D01*
G02X209467Y69571I-940J-1040D01*
G03X209462Y70159I-274J292D01*
G02X211363Y70178I940J1040D01*
G37*
G36*
G01X174552D02*
G03X174557Y69590I274J-292D01*
G02X172656Y69571I-940J-1040D01*
G03X172651Y70159I-274J292D01*
G02X174552Y70178I940J1040D01*
G37*
G36*
G01X137741D02*
G03X137746Y69590I274J-292D01*
G02X135845Y69571I-940J-1040D01*
G03X135840Y70159I-274J292D01*
G02X137741Y70178I940J1040D01*
G37*
G36*
G01X1230841Y69934D02*
G03Y69355I276J-289D01*
G02X1228907I-967J-1015D01*
G03Y69934I-276J290D01*
G02X1230841I967J1015D01*
G37*
G36*
G01X1194030D02*
G03Y69355I276J-289D01*
G02X1192096I-967J-1015D01*
G03Y69934I-276J290D01*
G02X1194030I967J1015D01*
G37*
G36*
G01X1157219D02*
G03Y69355I276J-289D01*
G02X1155285I-967J-1015D01*
G03Y69934I-276J290D01*
G02X1157219I967J1015D01*
G37*
G36*
G01X1120407D02*
G03Y69355I276J-289D01*
G02X1118473I-967J-1015D01*
G03Y69934I-276J290D01*
G02X1120407I967J1015D01*
G37*
G36*
G01X939699D02*
G03Y69355I276J-289D01*
G02X937765I-967J-1015D01*
G03Y69934I-276J290D01*
G02X939699I967J1015D01*
G37*
G36*
G01X902888D02*
G03Y69355I276J-289D01*
G02X900954I-967J-1015D01*
G03Y69934I-276J290D01*
G02X902888I967J1015D01*
G37*
G36*
G01X866077D02*
G03Y69355I276J-289D01*
G02X864143I-967J-1015D01*
G03Y69934I-276J290D01*
G02X866077I967J1015D01*
G37*
G36*
G01X829266D02*
G03Y69355I276J-289D01*
G02X827332I-967J-1015D01*
G03Y69934I-276J290D01*
G02X829266I967J1015D01*
G37*
G36*
G01X792455D02*
G03Y69355I276J-289D01*
G02X790521I-967J-1015D01*
G03Y69934I-276J290D01*
G02X792455I967J1015D01*
G37*
G36*
G01X581233D02*
G03Y69355I276J-289D01*
G02X579299I-967J-1015D01*
G03Y69934I-276J290D01*
G02X581233I967J1015D01*
G37*
G36*
G01X544422D02*
G03Y69355I276J-289D01*
G02X542488I-967J-1015D01*
G03Y69934I-276J290D01*
G02X544422I967J1015D01*
G37*
G36*
G01X507611D02*
G03Y69355I276J-289D01*
G02X505677I-967J-1015D01*
G03Y69934I-276J290D01*
G02X507611I967J1015D01*
G37*
G36*
G01X470799D02*
G03Y69355I276J-289D01*
G02X468865I-967J-1015D01*
G03Y69934I-276J290D01*
G02X470799I967J1015D01*
G37*
G36*
G01X290091D02*
G03Y69355I276J-289D01*
G02X288157I-967J-1015D01*
G03Y69934I-276J290D01*
G02X290091I967J1015D01*
G37*
G36*
G01X253280D02*
G03Y69355I276J-289D01*
G02X251346I-967J-1015D01*
G03Y69934I-276J290D01*
G02X253280I967J1015D01*
G37*
G36*
G01X216469D02*
G03Y69355I276J-289D01*
G02X214535I-967J-1015D01*
G03Y69934I-276J290D01*
G02X216469I967J1015D01*
G37*
G36*
G01X179658D02*
G03Y69355I276J-289D01*
G02X177724I-967J-1015D01*
G03Y69934I-276J290D01*
G02X179658I967J1015D01*
G37*
G36*
G01X142847D02*
G03Y69355I276J-289D01*
G02X140913I-967J-1015D01*
G03Y69934I-276J290D01*
G02X142847I967J1015D01*
G37*
G36*
G01X1733Y66210D02*
G03X1351Y66698I-390J88D01*
G02X2749Y67790I31J1402D01*
G03X3131Y67302I390J-88D01*
G02X1733Y66210I-31J-1402D01*
G37*
G36*
G01X1328429Y66950D02*
G03Y66350I265J-300D01*
G02X1326571I-929J-1050D01*
G03Y66950I-265J300D01*
G02X1326598Y69073I929J1050D01*
G03X1326591Y69692I-257J307D01*
G02X1328369Y69713I876J1094D01*
G03X1328376Y69094I257J-307D01*
G02X1328429Y66950I-876J-1094D01*
G37*
G36*
G01X1649871Y64260D02*
G03X1649293Y64256I-287J-279D01*
G02X1649281Y66198I-1017J965D01*
G03X1649859Y66202I287J279D01*
G02X1649871Y64260I1017J-965D01*
G37*
G36*
G01X734722Y65252D02*
G03X734742Y64719I308J-255D01*
G02X732775Y62723I-1010J-972D01*
G03X732242Y62735I-273J-292D01*
G02X730252Y64695I-910J1067D01*
G03X730232Y65228I-308J255D01*
G02X730180Y67115I1010J972D01*
G03X730171Y67648I-303J261D01*
G02X732157Y69624I1029J952D01*
G03X732690Y69612I273J292D01*
G02X734662Y67631I909J-1067D01*
G03X734671Y67098I303J-261D01*
G02X734722Y65252I-1029J-952D01*
G37*
G36*
G01X1785725Y65065D02*
G03X1786169Y64732I395J64D01*
G02X1784957Y63117I172J-1391D01*
G03X1784513Y63450I-395J-64D01*
G02X1785725Y65065I-172J1391D01*
G37*
G36*
G01X1610284Y62579D02*
G03X1609752Y62364I-162J-365D01*
G02X1607065Y63094I-1300J526D01*
G03X1606698Y63551I-396J58D01*
G02X1608184Y64745I99J1398D01*
G03X1608551Y64288I396J-58D01*
G02X1609021Y64172I-96J-1399D01*
G03X1609553Y64387I162J365D01*
G02X1610284Y62579I1300J-526D01*
G37*
G36*
G01X1734177Y57140D02*
G03X1733623I-277J-288D01*
G02X1731640Y59123I-973J1010D01*
G03Y59677I-288J277D01*
G02X1733660I1010J973D01*
G03Y59123I288J-277D01*
G02X1733744Y59027I-1012J-970D01*
G03X1734056I156J125D01*
G02X1734177Y57140I1094J-877D01*
G37*
G36*
G01X15614Y55240D02*
G03X15036I-289J-277D01*
G02Y57182I-1011J971D01*
G03X15614I289J277D01*
G02Y55240I1011J-971D01*
G37*
G36*
G01X1816718Y55668D02*
G03X1817330Y55663I308J255D01*
G02X1817315Y53859I1066J-911D01*
G03X1816703Y53864I-308J-255D01*
G02X1816718Y55668I-1066J911D01*
G37*
G36*
G01X1825763Y54670D02*
G03X1825948Y54402I188J-68D01*
G02X1824461Y53215I-18J-1502D01*
G03X1824129Y53694I-391J84D01*
G02X1823379Y56326I221J1486D01*
G03X1823392Y56926I-258J306D01*
G02X1823160Y58862I1018J1104D01*
G03X1823038Y59424I-333J222D01*
G02X1825080Y59868I792J1276D01*
G03X1825202Y59306I333J-222D01*
G02X1825897Y58245I-792J-1277D01*
G03X1826420Y57923I396J57D01*
G02X1826346Y55104I480J-1423D01*
G03X1825810Y54826I-147J-372D01*
G02X1825763Y54670I-1460J355D01*
G37*
G36*
G01X1668527Y50490D02*
G03X1667973I-277J-288D01*
G02Y52510I-973J1010D01*
G03X1668527I277J288D01*
G02Y50490I973J-1010D01*
G37*
G36*
G01X939703Y51303D02*
G03Y50725I277J-289D01*
G02X937761I-971J-1011D01*
G03Y51303I-277J289D01*
G02X939703I971J1011D01*
G37*
G36*
G01X902892D02*
G03Y50725I277J-289D01*
G02X900950I-971J-1011D01*
G03Y51303I-277J289D01*
G02X902892I971J1011D01*
G37*
G36*
G01X866081D02*
G03Y50725I277J-289D01*
G02X864139I-971J-1011D01*
G03Y51303I-277J289D01*
G02X866081I971J1011D01*
G37*
G36*
G01X829270D02*
G03Y50725I277J-289D01*
G02X827328I-971J-1011D01*
G03Y51303I-277J289D01*
G02X829270I971J1011D01*
G37*
G36*
G01X792459D02*
G03Y50725I277J-289D01*
G02X790517I-971J-1011D01*
G03Y51303I-277J289D01*
G02X792459I971J1011D01*
G37*
G36*
G01X581237D02*
G03Y50725I277J-289D01*
G02X579295I-971J-1011D01*
G03Y51303I-277J289D01*
G02X581237I971J1011D01*
G37*
G36*
G01X544426D02*
G03Y50725I277J-289D01*
G02X542484I-971J-1011D01*
G03Y51303I-277J289D01*
G02X544426I971J1011D01*
G37*
G36*
G01X507614D02*
G03Y50725I277J-289D01*
G02X505672I-971J-1011D01*
G03Y51303I-277J289D01*
G02X507614I971J1011D01*
G37*
G36*
G01X470803D02*
G03Y50725I277J-289D01*
G02X468861I-971J-1011D01*
G03Y51303I-277J289D01*
G02X470803I971J1011D01*
G37*
G36*
G01X934603Y51089D02*
G03Y50511I277J-289D01*
G02X932661I-971J-1011D01*
G03Y51089I-277J289D01*
G02X934603I971J1011D01*
G37*
G36*
G01X897792D02*
G03Y50511I277J-289D01*
G02X895850I-971J-1011D01*
G03Y51089I-277J289D01*
G02X897792I971J1011D01*
G37*
G36*
G01X860981D02*
G03Y50511I277J-289D01*
G02X859039I-971J-1011D01*
G03Y51089I-277J289D01*
G02X860981I971J1011D01*
G37*
G36*
G01X824170D02*
G03Y50511I277J-289D01*
G02X822228I-971J-1011D01*
G03Y51089I-277J289D01*
G02X824170I971J1011D01*
G37*
G36*
G01X787359D02*
G03Y50511I277J-289D01*
G02X785417I-971J-1011D01*
G03Y51089I-277J289D01*
G02X787359I971J1011D01*
G37*
G36*
G01X576137D02*
G03Y50511I277J-289D01*
G02X574195I-971J-1011D01*
G03Y51089I-277J289D01*
G02X576137I971J1011D01*
G37*
G36*
G01X539326D02*
G03Y50511I277J-289D01*
G02X537384I-971J-1011D01*
G03Y51089I-277J289D01*
G02X539326I971J1011D01*
G37*
G36*
G01X502514D02*
G03Y50511I277J-289D01*
G02X500572I-971J-1011D01*
G03Y51089I-277J289D01*
G02X502514I971J1011D01*
G37*
G36*
G01X465703D02*
G03Y50511I277J-289D01*
G02X463761I-971J-1011D01*
G03Y51089I-277J289D01*
G02X465703I971J1011D01*
G37*
G36*
G01X1744121Y46096D02*
G03X1743567I-277J-288D01*
G02Y48116I-973J1010D01*
G03X1744121I277J288D01*
G02Y46096I973J-1010D01*
G37*
G36*
G01X1363531Y44948D02*
G03X1363481Y44361I244J-316D01*
G02X1361591Y44523I-1033J-948D01*
G03X1361641Y45110I-244J316D01*
G02X1363531Y44948I1033J948D01*
G37*
G36*
G01X1721758Y38368D02*
X1717958D01*
G02Y41392I0J1512D01*
G01X1721759D01*
G02X1723270Y39890I-1J-1512D01*
G01Y39795D01*
X1723260Y39711D01*
G02X1721758Y38368I-1502J169D01*
G37*
G36*
G01X1703073Y38168D02*
X1699273D01*
G02Y41190I0J1511D01*
G01X1703074D01*
G02X1704584Y39689I-1J-1511D01*
G01Y39594D01*
X1704575Y39510D01*
G02X1703073Y38168I-1502J169D01*
G37*
G36*
G01X1740556Y37975D02*
Y37965D01*
X1736654Y38080D01*
X1736483Y38104D01*
G02X1736742Y41111I217J1496D01*
G01Y41121D01*
X1740642Y41006D01*
X1740650Y40998D01*
X1740723Y40992D01*
G02X1742110Y39496I-125J-1506D01*
G01Y39401D01*
X1742100Y39317D01*
G02X1740556Y37975I-1502J169D01*
G37*
G36*
G01X1731183Y37954D02*
X1727383D01*
G02Y40976I0J1511D01*
G01X1731183D01*
G02X1732694Y39475I0J-1511D01*
G01Y39380D01*
X1732685Y39296D01*
G02X1731183Y37954I-1502J169D01*
G37*
G36*
G01X1694098Y37950D02*
X1689098D01*
G02Y40974I0J1512D01*
G01X1694098D01*
G02X1695610Y39472I0J-1512D01*
G01Y39377D01*
X1695600Y39293D01*
G02X1694098Y37950I-1502J169D01*
G37*
G36*
G01X1684648D02*
X1679648D01*
G02Y40974I0J1512D01*
G01X1684649D01*
G02X1686160Y39472I-1J-1512D01*
G01Y39377D01*
X1686150Y39293D01*
G02X1684648Y37950I-1502J169D01*
G37*
G36*
G01X1675198D02*
X1670198D01*
G02Y40974I0J1512D01*
G01X1675199D01*
G02X1676710Y39472I-1J-1512D01*
G01Y39377D01*
X1676700Y39293D01*
G02X1675198Y37950I-1502J169D01*
G37*
G36*
G01X1646848D02*
X1641848D01*
G02Y40974I0J1512D01*
G01X1646849D01*
G02X1648360Y39472I-1J-1512D01*
G01Y39377D01*
X1648350Y39293D01*
G02X1646848Y37950I-1502J169D01*
G37*
G36*
G01X1712308Y37838D02*
X1708508D01*
G02Y40862I0J1512D01*
G01X1712309D01*
G02X1713820Y39360I-1J-1512D01*
G01Y39265D01*
X1713810Y39181D01*
G02X1712308Y37838I-1502J168D01*
G37*
G36*
G01X1368689Y36829D02*
G03X1368111I-289J-277D01*
G02Y38771I-1011J971D01*
G03X1368689I289J277D01*
G02Y36829I1011J-971D01*
G37*
G36*
G01X1660748Y40974D02*
X1665749D01*
G02X1667260Y39472I-1J-1512D01*
G01Y39377D01*
X1667250Y39293D01*
G02X1665748Y37950I-1502J169D01*
G01X1662563D01*
G03X1662204Y37375I1J-400D01*
G02X1659887Y37682I-1260J-614D01*
G03X1659829Y38262I-302J263D01*
G02X1660748Y40974I919J1200D01*
G37*
G36*
G01X1651297D02*
X1656299D01*
G02X1657810Y39472I-1J-1512D01*
G01Y39377D01*
X1657800Y39293D01*
G02X1656298Y37950I-1502J169D01*
G01X1652864D01*
G03X1652506Y37373I0J-400D01*
G02X1650282Y37764I-1256J-623D01*
G03X1650276Y38348I-276J289D01*
G02X1651297Y40974I1022J1114D01*
G37*
G36*
G01X1847503Y35441D02*
G03X1848058Y35439I279J287D01*
G02X1848051Y33420I969J-1013D01*
G03X1847496Y33422I-279J-287D01*
G02X1847503Y35441I-969J1013D01*
G37*
G36*
G01X655725Y30405D02*
G03X655151Y30327I-250J-312D01*
G02X652986Y30199I-1135J823D01*
G03X652415Y30215I-293J-272D01*
G02X650428Y30257I-973J1010D01*
G03X649856Y30264I-289J-276D01*
G02X649881Y32226I-989J994D01*
G03X650453Y32219I289J276D01*
G02X652472Y32176I989J-994D01*
G03X653043Y32160I293J272D01*
G02X654891Y32245I972J-1010D01*
G03X655465Y32323I250J312D01*
G02X655725Y30405I1135J-823D01*
G37*
G36*
G01X934593Y32378D02*
G03X934598Y31790I274J-292D01*
G02X932697Y31771I-940J-1040D01*
G03X932692Y32359I-274J292D01*
G02X934593Y32378I940J1040D01*
G37*
G36*
G01X897782D02*
G03X897787Y31790I274J-292D01*
G02X895886Y31771I-940J-1040D01*
G03X895881Y32359I-274J292D01*
G02X897782Y32378I940J1040D01*
G37*
G36*
G01X860971D02*
G03X860976Y31790I274J-292D01*
G02X859075Y31771I-940J-1040D01*
G03X859070Y32359I-274J292D01*
G02X860971Y32378I940J1040D01*
G37*
G36*
G01X824160D02*
G03X824165Y31790I274J-292D01*
G02X822264Y31771I-940J-1040D01*
G03X822259Y32359I-274J292D01*
G02X824160Y32378I940J1040D01*
G37*
G36*
G01X787349D02*
G03X787354Y31790I274J-292D01*
G02X785453Y31771I-940J-1040D01*
G03X785448Y32359I-274J292D01*
G02X787349Y32378I940J1040D01*
G37*
G36*
G01X576127D02*
G03X576132Y31790I274J-292D01*
G02X574231Y31771I-940J-1040D01*
G03X574226Y32359I-274J292D01*
G02X576127Y32378I940J1040D01*
G37*
G36*
G01X539316D02*
G03X539321Y31790I274J-292D01*
G02X537420Y31771I-940J-1040D01*
G03X537415Y32359I-274J292D01*
G02X539316Y32378I940J1040D01*
G37*
G36*
G01X502504D02*
G03X502509Y31790I274J-292D01*
G02X500608Y31771I-940J-1040D01*
G03X500603Y32359I-274J292D01*
G02X502504Y32378I940J1040D01*
G37*
G36*
G01X465693D02*
G03X465698Y31790I274J-292D01*
G02X463797Y31771I-940J-1040D01*
G03X463792Y32359I-274J292D01*
G02X465693Y32378I940J1040D01*
G37*
G36*
G01X939699Y32134D02*
G03Y31555I276J-289D01*
G02X937765I-967J-1015D01*
G03Y32134I-276J289D01*
G02X939699I967J1015D01*
G37*
G36*
G01X902888D02*
G03Y31555I276J-289D01*
G02X900954I-967J-1015D01*
G03Y32134I-276J289D01*
G02X902888I967J1015D01*
G37*
G36*
G01X866077D02*
G03Y31555I276J-289D01*
G02X864143I-967J-1015D01*
G03Y32134I-276J289D01*
G02X866077I967J1015D01*
G37*
G36*
G01X829266D02*
G03Y31555I276J-289D01*
G02X827332I-967J-1015D01*
G03Y32134I-276J289D01*
G02X829266I967J1015D01*
G37*
G36*
G01X792455D02*
G03Y31555I276J-289D01*
G02X790521I-967J-1015D01*
G03Y32134I-276J289D01*
G02X792455I967J1015D01*
G37*
G36*
G01X581233D02*
G03Y31555I276J-289D01*
G02X579299I-967J-1015D01*
G03Y32134I-276J289D01*
G02X581233I967J1015D01*
G37*
G36*
G01X544422D02*
G03Y31555I276J-289D01*
G02X542488I-967J-1015D01*
G03Y32134I-276J289D01*
G02X544422I967J1015D01*
G37*
G36*
G01X507610D02*
G03Y31555I276J-289D01*
G02X505676I-967J-1015D01*
G03Y32134I-276J289D01*
G02X507610I967J1015D01*
G37*
G36*
G01X470799D02*
G03Y31555I276J-289D01*
G02X468865I-967J-1015D01*
G03Y32134I-276J289D01*
G02X470799I967J1015D01*
G37*
G36*
G01X1758406Y34262D02*
Y30367D01*
X1758397Y30283D01*
G02X1755384Y30452I-1502J169D01*
G01Y34252D01*
G02X1758406Y34262I1511J0D01*
G37*
G36*
G01X683076Y27208D02*
G03X682476I-300J-265D01*
G02Y29066I-1050J929D01*
G03X683076I300J265D01*
G02Y27208I1050J-929D01*
G37*
G36*
G01X1523780Y27567D02*
G03X1523280Y27252I-106J-386D01*
G02X1522274Y28851I-1380J248D01*
G03X1522774Y29166I106J386D01*
G02X1523780Y27567I1380J-248D01*
G37*
G36*
G01X1509078Y30563D02*
G03X1508559Y30154I-120J-381D01*
G02X1507596Y32459I-3893J-273D01*
G03X1508253Y32540I301J264D01*
G02X1509078Y30563I1247J-640D01*
G37*
G36*
G01X1808288Y27703D02*
G03X1808887Y27629I332J224D01*
G02X1808661Y25800I935J-1044D01*
G03X1808062Y25874I-332J-224D01*
G02X1808288Y27703I-935J1044D01*
G37*
G36*
G01X1380536Y27426D02*
G03X1381078Y27181I381J121D01*
G02X1380306Y25472I564J-1284D01*
G03X1379764Y25717I-381J-121D01*
G02X1380536Y27426I-564J1284D01*
G37*
G36*
G01X14801Y25749D02*
G03X15397Y25723I310J253D01*
G02X15315Y23856I1003J-979D01*
G03X14719Y23882I-310J-253D01*
G02X14801Y25749I-1003J979D01*
G37*
G36*
G01X1767069Y22498D02*
X1763360D01*
G02Y25522I0J1512D01*
G01X1767069D01*
G02X1768580Y24020I-1J-1512D01*
G01Y23925D01*
X1768571Y23841D01*
G02X1767069Y22498I-1502J169D01*
G37*
G36*
G01X1550861Y22846D02*
G03X1550307I-277J-288D01*
G02Y24866I-973J1010D01*
G03X1550861I277J288D01*
G02X1552845Y24827I973J-1010D01*
G03X1553423I289J277D01*
G02Y22885I1011J-971D01*
G03X1552845I-289J-277D01*
G02X1550861Y22846I-1011J971D01*
G37*
G36*
G01X1748152Y21686D02*
X1743152D01*
G02Y24708I0J1511D01*
G01X1748153D01*
G02X1749664Y23207I0J-1512D01*
G01Y23112D01*
X1749654Y23028D01*
G02X1748152Y21686I-1502J169D01*
G37*
G36*
G01X655327Y21790D02*
G03X654773I-277J-288D01*
G02Y23810I-973J1010D01*
G03X655327I277J288D01*
G02Y21790I973J-1010D01*
G37*
G36*
G01X1738168Y20800D02*
X1733168D01*
G02Y23824I0J1512D01*
G01X1738169D01*
G02X1739680Y22322I-1J-1512D01*
G01Y22227D01*
X1739670Y22143D01*
G02X1738168Y20800I-1502J169D01*
G37*
G36*
G01X1532430Y23307D02*
G02Y24629I3693J661D01*
G02Y23307I3693J-661D01*
G37*
G36*
G01X1824343Y22637D02*
G03X1824913Y22612I297J267D01*
G02X1824827Y20650I957J-1025D01*
G03X1824257Y20675I-297J-267D01*
G02X1824343Y22637I-957J1025D01*
G37*
G36*
G01X691427Y19790D02*
G03X690873I-277J-288D01*
G02Y21810I-973J1010D01*
G03X691427I277J288D01*
G02Y19790I973J-1010D01*
G37*
G36*
G01X1760709Y18534D02*
X1757009Y18496D01*
G02X1756976Y21518I-16J1511D01*
G01X1760677Y21556D01*
G02X1762198Y20189I16J-1511D01*
G01X1762204Y20130D01*
X1762205Y20071D01*
G02Y20019I-1512J-26D01*
G01X1762204Y20017D01*
Y20007D01*
G02X1760709Y18534I-1511J38D01*
G37*
G36*
G01X1375911Y14137D02*
G03X1375375Y14134I-266J-299D01*
G02X1373356Y14269I-945J1036D01*
G03X1372795Y14321I-307J-256D01*
G02X1370854Y16334I-895J1079D01*
G03Y16866I-298J266D01*
G02X1370874Y18755I1046J934D01*
G03X1370885Y19288I-293J273D01*
G02X1370907Y21136I1065J911D01*
G03X1370905Y21673I-298J267D01*
G02X1372984Y21681I1036J944D01*
G03X1372986Y21144I298J-267D01*
G02X1372976Y19245I-1036J-944D01*
G03X1372965Y18712I293J-273D01*
G02X1372946Y16866I-1065J-912D01*
G03Y16334I298J-266D01*
G02X1372975Y16301I-1039J-942D01*
G03X1373536Y16249I307J256D01*
G02X1375362Y16218I895J-1079D01*
G03X1375898Y16221I266J299D01*
G02X1375911Y14137I944J-1036D01*
G37*
G36*
G01X1577048Y10994D02*
X1573048D01*
G02Y14018I0J1512D01*
G01X1577049D01*
G02X1578560Y12516I-1J-1512D01*
G01Y12421D01*
X1578550Y12337D01*
G02X1577048Y10994I-1502J169D01*
G37*
G36*
G01X1567498D02*
X1563498D01*
G02Y14018I0J1512D01*
G01X1567499D01*
G02X1569010Y12516I-1J-1512D01*
G01Y12421D01*
X1569000Y12337D01*
G02X1567498Y10994I-1502J169D01*
G37*
G36*
G01X1548698D02*
X1544698D01*
G02Y14018I0J1512D01*
G01X1548699D01*
G02X1550210Y12516I-1J-1512D01*
G01Y12421D01*
X1550200Y12337D01*
G02X1548698Y10994I-1502J169D01*
G37*
G36*
G01X1554148Y13818D02*
X1558148D01*
G02X1559660Y12316I0J-1512D01*
G01Y12221D01*
X1559650Y12137D01*
G02X1558148Y10794I-1502J169D01*
G01X1554148D01*
G02Y13818I0J1512D01*
G37*
G36*
G01X939703Y13503D02*
G03Y12925I277J-289D01*
G02X937761I-971J-1011D01*
G03Y13503I-277J289D01*
G02X939703I971J1011D01*
G37*
G36*
G01X902892D02*
G03Y12925I277J-289D01*
G02X900950I-971J-1011D01*
G03Y13503I-277J289D01*
G02X902892I971J1011D01*
G37*
G36*
G01X866081D02*
G03Y12925I277J-289D01*
G02X864139I-971J-1011D01*
G03Y13503I-277J289D01*
G02X866081I971J1011D01*
G37*
G36*
G01X829270D02*
G03Y12925I277J-289D01*
G02X827328I-971J-1011D01*
G03Y13503I-277J289D01*
G02X829270I971J1011D01*
G37*
G36*
G01X792459D02*
G03Y12925I277J-289D01*
G02X790517I-971J-1011D01*
G03Y13503I-277J289D01*
G02X792459I971J1011D01*
G37*
G36*
G01X581237D02*
G03Y12925I277J-289D01*
G02X579295I-971J-1011D01*
G03Y13503I-277J289D01*
G02X581237I971J1011D01*
G37*
G36*
G01X544426D02*
G03Y12925I277J-289D01*
G02X542484I-971J-1011D01*
G03Y13503I-277J289D01*
G02X544426I971J1011D01*
G37*
G36*
G01X507615D02*
G03Y12925I277J-289D01*
G02X505673I-971J-1011D01*
G03Y13503I-277J289D01*
G02X507615I971J1011D01*
G37*
G36*
G01X470803D02*
G03Y12925I277J-289D01*
G02X468861I-971J-1011D01*
G03Y13503I-277J289D01*
G02X470803I971J1011D01*
G37*
G36*
G01X934603Y13289D02*
G03Y12711I277J-289D01*
G02X932661I-971J-1011D01*
G03Y13289I-277J289D01*
G02X934603I971J1011D01*
G37*
G36*
G01X897792D02*
G03Y12711I277J-289D01*
G02X895850I-971J-1011D01*
G03Y13289I-277J289D01*
G02X897792I971J1011D01*
G37*
G36*
G01X860981D02*
G03Y12711I277J-289D01*
G02X859039I-971J-1011D01*
G03Y13289I-277J289D01*
G02X860981I971J1011D01*
G37*
G36*
G01X824170D02*
G03Y12711I277J-289D01*
G02X822228I-971J-1011D01*
G03Y13289I-277J289D01*
G02X824170I971J1011D01*
G37*
G36*
G01X787359D02*
G03Y12711I277J-289D01*
G02X785417I-971J-1011D01*
G03Y13289I-277J289D01*
G02X787359I971J1011D01*
G37*
G36*
G01X576137D02*
G03Y12711I277J-289D01*
G02X574195I-971J-1011D01*
G03Y13289I-277J289D01*
G02X576137I971J1011D01*
G37*
G36*
G01X539326D02*
G03Y12711I277J-289D01*
G02X537384I-971J-1011D01*
G03Y13289I-277J289D01*
G02X539326I971J1011D01*
G37*
G36*
G01X502515D02*
G03Y12711I277J-289D01*
G02X500573I-971J-1011D01*
G03Y13289I-277J289D01*
G02X502515I971J1011D01*
G37*
G36*
G01X465703D02*
G03Y12711I277J-289D01*
G02X463761I-971J-1011D01*
G03Y13289I-277J289D01*
G02X465703I971J1011D01*
G37*
G36*
G01X1484135Y10052D02*
X1479135D01*
G02Y13074I0J1511D01*
G01X1484136D01*
G02X1485646Y11573I-1J-1511D01*
G01Y11478D01*
X1485637Y11394D01*
G02X1484135Y10052I-1502J169D01*
G37*
G36*
G01X1465237D02*
X1460237D01*
G02Y13074I0J1511D01*
G01X1465238D01*
G02X1466748Y11573I-1J-1511D01*
G01Y11478D01*
X1466739Y11394D01*
G02X1465237Y10052I-1502J169D01*
G37*
G36*
G01X1441340Y13074D02*
X1446341D01*
G02X1447852Y11573I0J-1512D01*
G01Y11478D01*
X1447842Y11394D01*
G02X1446340Y10052I-1502J169D01*
G01X1441340D01*
G02Y13074I1J1511D01*
G37*
G36*
G01X1427442Y10052D02*
X1422442D01*
G02Y13074I0J1511D01*
G01X1427443D01*
G02X1428954Y11573I0J-1512D01*
G01Y11478D01*
X1428944Y11394D01*
G02X1427442Y10052I-1502J169D01*
G37*
G36*
G01X1728678Y9870D02*
X1723678D01*
G02Y12892I0J1511D01*
G01X1728679D01*
G02X1730190Y11391I0J-1512D01*
G01Y11296D01*
X1730180Y11212D01*
G02X1728678Y9870I-1502J169D01*
G37*
G36*
G01X1681428D02*
X1676428D01*
G02Y12892I0J1511D01*
G01X1681429D01*
G02X1682940Y11391I0J-1512D01*
G01Y11296D01*
X1682930Y11212D01*
G02X1681428Y9870I-1502J169D01*
G37*
G36*
G01X1605898Y9844D02*
X1600898D01*
G02Y12866I0J1511D01*
G01X1605899D01*
G02X1607410Y11365I0J-1512D01*
G01Y11270D01*
X1607400Y11186D01*
G02X1605898Y9844I-1502J169D01*
G37*
G36*
G01X1586998D02*
X1581998D01*
G02Y12866I0J1511D01*
G01X1586999D01*
G02X1588510Y11365I0J-1512D01*
G01Y11270D01*
X1588500Y11186D01*
G02X1586998Y9844I-1502J169D01*
G37*
G36*
G01X1700200Y9806D02*
X1695200D01*
G02Y12828I0J1511D01*
G01X1700201D01*
G02X1701712Y11327I0J-1512D01*
G01Y11232D01*
X1701702Y11148D01*
G02X1700200Y9806I-1502J170D01*
G37*
G36*
G01X1709771Y9750D02*
X1704771D01*
G02Y12772I0J1511D01*
G01X1709772D01*
G02X1711282Y11271I-1J-1511D01*
G01Y11176D01*
X1711273Y11092D01*
G02X1709771Y9750I-1502J169D01*
G37*
G36*
G01X1719297Y9668D02*
X1714297D01*
G02Y12692I0J1512D01*
G01X1719298D01*
G02X1720808Y11190I-1J-1512D01*
G01Y11095D01*
X1720799Y11011D01*
G02X1719297Y9668I-1502J169D01*
G37*
G36*
G01X1643865Y9594D02*
X1638865D01*
G02Y12616I0J1511D01*
G01X1643866D01*
G02X1645376Y11115I-1J-1511D01*
G01Y11020D01*
X1645367Y10936D01*
G02X1643865Y9594I-1502J169D01*
G37*
G36*
G01X1690948Y9214D02*
X1685948D01*
G02Y12236I0J1511D01*
G01X1690949D01*
G02X1692460Y10735I0J-1512D01*
G01Y10640D01*
X1692450Y10556D01*
G02X1690948Y9214I-1502J169D01*
G37*
G36*
G01X1663884Y10164D02*
Y10069D01*
X1663875Y9985D01*
G02X1662342Y8643I-1502J169D01*
G01X1657338Y8747D01*
G02X1657400Y11769I31J1511D01*
G01X1662403Y11665D01*
G02X1663884Y10164I-30J-1511D01*
G37*
G36*
G01X1401627Y8990D02*
G03X1401073I-277J-288D01*
G02Y11010I-973J1010D01*
G03X1401627I277J288D01*
G02X1403573I973J-1010D01*
G03X1404127I277J288D01*
G02Y8990I973J-1010D01*
G03X1403573I-277J-288D01*
G02X1401627I-973J1010D01*
G37*
G36*
G01X665011Y9117D02*
G03X664389I-311J-252D01*
G02Y10883I-1089J883D01*
G03X665011I311J252D01*
G02Y9117I1089J-883D01*
G37*
G36*
G01X1754065Y10273D02*
G03X1754640Y10183I330J226D01*
G02X1754343Y8284I860J-1107D01*
G03X1753768Y8374I-330J-226D01*
G02X1754065Y10273I-860J1107D01*
G37*
G36*
G01X1591848Y12918D02*
X1595849D01*
G02X1597360Y11416I-1J-1512D01*
G01Y11321D01*
X1597350Y11237D01*
G02X1595848Y9894I-1502J169D01*
G01X1593957D01*
G03X1593623Y9274I0J-400D01*
G02X1591378Y9402I-1170J-772D01*
G03X1591234Y10025I-306J257D01*
G02X1591848Y12918I614J1381D01*
G37*
G36*
G01X1436025Y6244D02*
X1431025D01*
G02Y9268I0J1512D01*
G01X1436026D01*
G02X1437536Y7766I-1J-1512D01*
G01Y7671D01*
X1437527Y7587D01*
G02X1436025Y6244I-1502J169D01*
G37*
G36*
G01X1493770Y5398D02*
X1488770D01*
G02Y8420I0J1511D01*
G01X1493771D01*
G02X1495282Y6919I0J-1512D01*
G01Y6824D01*
X1495272Y6740D01*
G02X1493770Y5398I-1502J169D01*
G37*
G36*
G01X1634148Y5314D02*
X1629148D01*
G02Y8336I0J1511D01*
G01X1634149D01*
G02X1635660Y6835I0J-1512D01*
G01Y6740D01*
X1635650Y6656D01*
G02X1634148Y5314I-1502J169D01*
G37*
G36*
G01X1653748Y4814D02*
X1648748D01*
G02Y7836I0J1511D01*
G01X1653749D01*
G02X1655260Y6335I0J-1512D01*
G01Y6240D01*
X1655250Y6156D01*
G02X1653748Y4814I-1502J169D01*
G37*
G36*
G01X1671979Y4724D02*
X1666979D01*
G02Y7748I0J1512D01*
G01X1671979D01*
G02X1673490Y6246I-1J-1512D01*
G01Y6151D01*
X1673481Y6067D01*
G02X1671979Y4724I-1502J168D01*
G37*
G36*
G01X1368378Y4805D02*
G03X1367800I-289J-277D01*
G02Y6747I-1011J971D01*
G03X1368378I289J277D01*
G02Y4805I1011J-971D01*
G37*
G36*
G01X1474388Y4078D02*
X1469388D01*
G02Y7100I0J1511D01*
G01X1474389D01*
G02X1475900Y5599I0J-1512D01*
G01Y5504D01*
X1475890Y5420D01*
G02X1474388Y4078I-1502J169D01*
G37*
G36*
G01X1454991D02*
X1449991D01*
G02Y7100I0J1511D01*
G01X1454992D01*
G02X1456502Y5599I-1J-1511D01*
G01Y5504D01*
X1456493Y5420D01*
G02X1454991Y4078I-1502J169D01*
G37*
G36*
G01X1614833Y3914D02*
X1609833D01*
G02Y6936I0J1511D01*
G01X1614834D01*
G02X1616344Y5435I-1J-1511D01*
G01Y5340D01*
X1616335Y5256D01*
G02X1614833Y3914I-1502J169D01*
G37*
G36*
G01X665442Y3406D02*
G03X664944Y3216I-143J-374D01*
G02X664199Y5171I-1245J645D01*
G03X664697Y5361I143J374D01*
G02X665442Y3406I1245J-645D01*
G37*
G36*
G01X1381205Y4584D02*
G03X1381223Y3999I282J-284D01*
G02X1379314Y3941I-923J-1055D01*
G03X1379296Y4526I-282J284D01*
G02X1381205Y4584I923J1055D01*
G37*
G36*
G01X1825803Y2785D02*
G03X1825972Y2243I354J-187D01*
G02X1824085Y1656I-648J-1243D01*
G03X1823916Y2198I-354J187D01*
G02X1825803Y2785I648J1243D01*
G37*
G36*
G01X752985Y1288D02*
G03X753584Y1266I309J254D01*
G02X753515Y-588I1016J-966D01*
G03X752916Y-566I-309J-254D01*
G02X752985Y1288I-1016J966D01*
G37*
G36*
G01X1600129Y-1610D02*
G03X1599575I-277J-288D01*
G02Y410I-973J1010D01*
G03X1600129I277J288D01*
G02Y-1610I973J-1010D01*
G37*
G36*
G01X63074Y-533D02*
G03X63194Y-1141I308J-255D01*
G02X61456Y-1484I-659J-1238D01*
G03X61336Y-876I-308J255D01*
G02X63074Y-533I659J1238D01*
G37*
G36*
G01X1381410Y-3782D02*
G03X1381885Y-4168I400J7D01*
G02X1380749Y-5568I266J-1377D01*
G03X1380274Y-5182I-400J-7D01*
G02X1381410Y-3782I-266J1377D01*
G37*
G36*
G01X718771Y-5838D02*
G03X718316Y-6193I-57J-396D01*
G02X717125Y-4661I-1395J145D01*
G03X717580Y-4306I57J396D01*
G02X718771Y-5838I1395J-145D01*
G37*
G36*
G01X934593Y-5422D02*
G03X934598Y-6010I274J-292D01*
G02X932697Y-6029I-940J-1040D01*
G03X932692Y-5441I-274J292D01*
G02X934593Y-5422I940J1040D01*
G37*
G36*
G01X897782D02*
G03X897787Y-6010I274J-292D01*
G02X895886Y-6029I-940J-1040D01*
G03X895881Y-5441I-274J292D01*
G02X897782Y-5422I940J1040D01*
G37*
G36*
G01X860971D02*
G03X860976Y-6010I274J-292D01*
G02X859075Y-6029I-940J-1040D01*
G03X859070Y-5441I-274J292D01*
G02X860971Y-5422I940J1040D01*
G37*
G36*
G01X824160D02*
G03X824165Y-6010I274J-292D01*
G02X822264Y-6029I-940J-1040D01*
G03X822259Y-5441I-274J292D01*
G02X824160Y-5422I940J1040D01*
G37*
G36*
G01X787349D02*
G03X787354Y-6010I274J-292D01*
G02X785453Y-6029I-940J-1040D01*
G03X785448Y-5441I-274J292D01*
G02X787349Y-5422I940J1040D01*
G37*
G36*
G01X576127D02*
G03X576132Y-6010I274J-292D01*
G02X574231Y-6029I-940J-1040D01*
G03X574226Y-5441I-274J292D01*
G02X576127Y-5422I940J1040D01*
G37*
G36*
G01X539316D02*
G03X539321Y-6010I274J-292D01*
G02X537420Y-6029I-940J-1040D01*
G03X537415Y-5441I-274J292D01*
G02X539316Y-5422I940J1040D01*
G37*
G36*
G01X502505D02*
G03X502510Y-6010I274J-292D01*
G02X500609Y-6029I-940J-1040D01*
G03X500604Y-5441I-274J292D01*
G02X502505Y-5422I940J1040D01*
G37*
G36*
G01X465693D02*
G03X465698Y-6010I274J-292D01*
G02X463797Y-6029I-940J-1040D01*
G03X463792Y-5441I-274J292D01*
G02X465693Y-5422I940J1040D01*
G37*
G36*
G01X939699Y-5666D02*
G03Y-6245I276J-290D01*
G02X937765I-967J-1015D01*
G03Y-5666I-276J290D01*
G02X939699I967J1015D01*
G37*
G36*
G01X902888D02*
G03Y-6245I276J-290D01*
G02X900954I-967J-1015D01*
G03Y-5666I-276J290D01*
G02X902888I967J1015D01*
G37*
G36*
G01X866077D02*
G03Y-6245I276J-290D01*
G02X864143I-967J-1015D01*
G03Y-5666I-276J290D01*
G02X866077I967J1015D01*
G37*
G36*
G01X829266D02*
G03Y-6245I276J-290D01*
G02X827332I-967J-1015D01*
G03Y-5666I-276J290D01*
G02X829266I967J1015D01*
G37*
G36*
G01X792455D02*
G03Y-6245I276J-290D01*
G02X790521I-967J-1015D01*
G03Y-5666I-276J290D01*
G02X792455I967J1015D01*
G37*
G36*
G01X581233D02*
G03Y-6245I276J-290D01*
G02X579299I-967J-1015D01*
G03Y-5666I-276J290D01*
G02X581233I967J1015D01*
G37*
G36*
G01X544422D02*
G03Y-6245I276J-290D01*
G02X542488I-967J-1015D01*
G03Y-5666I-276J290D01*
G02X544422I967J1015D01*
G37*
G36*
G01X507611D02*
G03Y-6245I276J-290D01*
G02X505677I-967J-1015D01*
G03Y-5666I-276J290D01*
G02X507611I967J1015D01*
G37*
G36*
G01X470799D02*
G03Y-6245I276J-290D01*
G02X468865I-967J-1015D01*
G03Y-5666I-276J290D01*
G02X470799I967J1015D01*
G37*
G36*
G01X647971Y-10511D02*
G03Y-11089I277J-289D01*
G02X646029I-971J-1011D01*
G03Y-10511I-277J289D01*
G02X646208Y-8343I971J1011D01*
G03X646297Y-7766I-226J330D01*
G02X648192Y-8057I1103J866D01*
G03X648103Y-8634I226J-330D01*
G02X647971Y-10511I-1103J-866D01*
G37*
G36*
G01X64936Y-12238D02*
G03X65464Y-12420I357J180D01*
G02X64808Y-14317I597J-1268D01*
G03X64280Y-14135I-357J-180D01*
G02X64936Y-12238I-597J1268D01*
G37*
G36*
G01X730372Y-16258D02*
G03X729818Y-16331I-240J-320D01*
G02X727466Y-16100I-1102J866D01*
G03X726936Y-15921I-356J-181D01*
G02X725354Y-15668I-609J1263D01*
G03X724800I-277J-288D01*
G02Y-13648I-973J1010D01*
G03X725354I277J288D01*
G02X726891Y-13374I973J-1010D01*
G03X727448Y-12954I161J366D01*
G02X729716Y-13856I1389J191D01*
G03X729689Y-14455I250J-311D01*
G02X729693Y-14460I-1084J-871D01*
G03X730004Y-14418I139J144D01*
G02X730372Y-16258I1206J-716D01*
G37*
G36*
G01X1585527Y-17110D02*
G03X1584973I-277J-288D01*
G02Y-15090I-973J1010D01*
G03X1585527I277J288D01*
G02Y-17110I973J-1010D01*
G37*
G36*
G01X41289Y-16225D02*
G03X41102Y-15669I-351J191D01*
G02X42908Y-15061I575J1279D01*
G03X43095Y-15617I351J-191D01*
G02X41289Y-16225I-575J-1279D01*
G37*
G36*
G01X1375736Y-17802D02*
G03X1375155Y-17824I-280J-285D01*
G02X1373046I-1055J924D01*
G03X1372502Y-17769I-301J-263D01*
G02X1370658Y-15667I-849J1115D01*
G03X1370647Y-15093I-284J282D01*
G02X1370569Y-13124I958J1024D01*
G03X1370568Y-12584I-296J269D01*
G02X1370580Y-10669I1030J951D01*
G03X1370588Y-10127I-290J275D01*
G02X1372650Y-10155I1044J936D01*
G03X1372642Y-10697I290J-275D01*
G02X1372634Y-12578I-1044J-936D01*
G03X1372635Y-13118I296J-269D01*
G02X1372600Y-15056I-1030J-951D01*
G03X1372611Y-15630I284J-282D01*
G02X1372707Y-15730I-962J-1020D01*
G03X1373251Y-15785I301J263D01*
G02X1375083Y-15900I850J-1115D01*
G03X1375664Y-15878I280J285D01*
G02X1375736Y-17802I1055J-924D01*
G37*
G36*
G01X18562Y-92D02*
X18560Y-189D01*
G02Y199I-18560J194D01*
G01X18561Y105D01*
X18562Y10D01*
Y-92D01*
G37*
G36*
G01X1606531Y-18356D02*
G03X1605977I-277J-288D01*
G02Y-16336I-973J1010D01*
G03X1606531I277J288D01*
G02X1608477I973J-1010D01*
G03X1609031I277J288D01*
G02Y-18356I973J-1010D01*
G03X1608477I-277J-288D01*
G02X1606531I-973J1010D01*
G37*
G36*
G01X1596531D02*
G03X1595977I-277J-288D01*
G02Y-16336I-973J1010D01*
G03X1596531I277J288D01*
G02X1598477I973J-1010D01*
G03X1599031I277J288D01*
G02Y-18356I973J-1010D01*
G03X1598477I-277J-288D01*
G02X1596531I-973J1010D01*
G37*
G36*
G01X661185Y-16750D02*
G03X661784Y-16839I338J214D01*
G02X661515Y-18650I916J-1062D01*
G03X660916Y-18561I-338J-214D01*
G02X661185Y-16750I-916J1062D01*
G37*
G36*
G01X21111Y-18129D02*
G03X21683Y-18241I339J213D01*
G02X21312Y-20127I816J-1140D01*
G03X20740Y-20015I-339J-213D01*
G02X21111Y-18129I-816J1140D01*
G37*
G36*
G01X709720Y-17986D02*
G03X710115Y-18437I397J-51D01*
G02X708717Y-19659I-8J-1402D01*
G03X708322Y-19208I-397J51D01*
G02X709720Y-17986I8J1402D01*
G37*
G36*
G01X1902168Y-18425D02*
G02X1901892Y-20014I992J-991D01*
G03X1901248Y-19902I-361J-171D01*
G02X1901524Y-18313I-992J991D01*
G03X1902168Y-18425I361J171D01*
G37*
G36*
G01X954372Y10313D02*
G03X953964Y10712I-400J-1D01*
G02Y13516I-28J1402D01*
G03X954372Y13915I8J400D01*
G01Y29659D01*
X954419Y29818D01*
G03Y30080I-483J131D01*
G01X954372Y30239D01*
Y32299D01*
G03X953964Y32698I-400J-1D01*
G02Y35502I-28J1402D01*
G03X954372Y35901I8J400D01*
G01Y48113D01*
G03X953964Y48512I-400J-1D01*
G02Y51316I-28J1402D01*
G03X954372Y51715I8J400D01*
G01Y52324D01*
X954419Y52483D01*
G03Y52745I-483J131D01*
G01X954372Y52904D01*
Y67459D01*
X954419Y67618D01*
G03Y67880I-483J131D01*
G01X954372Y68039D01*
Y69452D01*
X957433D01*
X957484Y69575D01*
G02X957862Y70097I1294J-539D01*
G03X957756Y70769I-262J303D01*
G01X957144Y71027D01*
Y73206D01*
X957470Y73504D01*
G03X957369Y74163I-270J296D01*
G01X957368Y74164D01*
X956676Y74489D01*
Y85796D01*
G02X957800Y86994I1201J-1D01*
G03Y87794I-26J400D01*
G02X956676Y88992I77J1199D01*
G01Y91393D01*
G02Y93921I607J1264D01*
G01Y99118D01*
X962265Y104707D01*
X962152Y104847D01*
G02X962348Y106803I1093J878D01*
G01Y116265D01*
X982998Y136915D01*
Y156666D01*
G03X982331Y156963I-400J0D01*
G02Y170201I-5953J6619D01*
G03X982998Y170498I267J297D01*
G01Y195715D01*
X984048Y196765D01*
Y198415D01*
X984398Y198765D01*
Y199485D01*
X984048Y199835D01*
Y201396D01*
X983960Y201485D01*
Y213585D01*
X983198Y214346D01*
Y215169D01*
G02X984962Y216522I1402J-1D01*
G03X985060Y217310I103J387D01*
G02X983991Y219643I-23J1401D01*
G03X983994Y219905I-149J133D01*
G02X984107Y221832I1072J904D01*
G02X983960Y222407I1054J576D01*
G01Y223111D01*
G02X985089Y224309I1201J-1D01*
G03X985465Y224733I-24J400D01*
G01Y224736D01*
X985435Y225276D01*
X987664Y227504D01*
Y229397D01*
G02X987851Y231830I782J1164D01*
G01X987966Y231884D01*
Y233772D01*
X988628Y234103D01*
G03Y234817I-182J357D01*
G01X987966Y235148D01*
Y237672D01*
X988628Y238003D01*
G03Y238717I-182J357D01*
G01X987966Y239048D01*
Y241572D01*
X988628Y241903D01*
G03Y242617I-182J357D01*
G01X987966Y242948D01*
Y244983D01*
X989885Y246902D01*
X990216D01*
G03X990573Y247481I-1J400D01*
G02X993079I1253J628D01*
G03X993436Y246902I358J-179D01*
G01X994016D01*
G02X996396I1190J-742D01*
G01X1000775D01*
G02X1003155I1190J-742D01*
G01X1007535D01*
G02X1009915I1190J-742D01*
G01X1010495D01*
G03X1010852Y247481I-1J400D01*
G02X1013358I1253J628D01*
G03X1013715Y246902I358J-179D01*
G01X1014295D01*
G02X1016675I1190J-742D01*
G01X1017255D01*
G03X1017612Y247481I-1J400D01*
G02X1019822Y249134I1253J628D01*
G03X1020377Y249144I272J293D01*
G01X1021306Y250072D01*
X1022073Y249698D01*
G03X1022607Y250232I172J362D01*
G01X1022233Y250999D01*
X1023176Y251942D01*
G02X1024265Y252349I991J-991D01*
G02X1025285Y253369I1360J-340D01*
G02X1025692Y254458I1398J98D01*
G01X1027628Y256395D01*
G03X1027463Y257060I-283J283D01*
G02X1029248Y258117I412J1340D01*
G03X1029600Y257638I392J-81D01*
G02X1029810Y257601I-137J-1394D01*
G03X1030054Y257845I51J193D01*
G02X1030420Y259186I1357J350D01*
G01X1038668Y267434D01*
X1050700D01*
X1050712Y267424D01*
X1077323D01*
X1078804Y265942D01*
X1078945Y266063D01*
G02X1078810Y264070I914J-1063D01*
G03X1078228Y264087I-299J-266D01*
G01X1071704Y257563D01*
G03X1071784Y256936I283J-282D01*
G02X1069864Y255016I-712J-1208D01*
G03X1069237Y255096I-345J-203D01*
G01X1068888Y254746D01*
X1068951Y254618D01*
G02X1067074Y252741I-1259J-618D01*
G01X1066946Y252804D01*
X1062376Y248234D01*
Y225585D01*
X1061002Y224211D01*
Y204789D01*
X1062376Y203415D01*
Y197377D01*
X1064944Y194808D01*
Y132772D01*
X1099056Y98660D01*
Y90538D01*
X1098190Y90285D01*
X1098189D01*
G03Y89515I111J-385D01*
G01X1098190D01*
X1099056Y89262D01*
Y85902D01*
X1098127Y85687D01*
G03Y84905I91J-391D01*
G01X1099056Y84690D01*
Y74190D01*
X1098119Y73980D01*
G03X1097947Y73284I88J-391D01*
G02X1097987Y71191I-911J-1064D01*
G03X1098005Y70587I272J-294D01*
G02X1097987Y68404I-888J-1084D01*
G03X1098139Y67701I248J-314D01*
G01X1099056Y67479D01*
Y60503D01*
X1099558Y60002D01*
X1317060D01*
X1318147Y58914D01*
X1319049D01*
X1320136Y60002D01*
X1324415D01*
X1327468Y56948D01*
X1327544Y56943D01*
G02X1328791Y55128I-92J-1399D01*
G03X1328897Y54887I191J-60D01*
G02X1329702Y53619I-597J-1268D01*
G01Y53402D01*
G02X1328949Y52160I-1402J0D01*
G03X1328849Y51928I93J-177D01*
G02X1328827Y51095I-1349J-381D01*
G03X1328927Y50851I189J-65D01*
G02X1329702Y49598I-627J-1254D01*
G01Y3731D01*
G02Y1319I-715J-1206D01*
G01Y-11626D01*
G02Y-13774I-902J-1074D01*
G01Y-14215D01*
X1328999Y-14918D01*
X1328990Y-14985D01*
G02X1328036Y-16133I-1390J185D01*
G03X1327769Y-16599I124J-380D01*
G02X1325884Y-18203I-1369J-301D01*
G01X1325761Y-18155D01*
X1324415Y-19502D01*
X1308585D01*
X1307199Y-18115D01*
X1307086Y-18148D01*
G02X1305352Y-16414I-386J1348D01*
G01X1305385Y-16301D01*
X1303605Y-14522D01*
X1301003D01*
G03X1300641Y-15090I1J-400D01*
G02X1300366Y-16666I-1272J-590D01*
G03X1300430Y-17281I284J-281D01*
G02X1298511Y-17399I-881J-1338D01*
G03X1298500Y-16780I-259J305D01*
G02X1298097Y-15090I869J1100D01*
G03X1297735Y-14522I-363J168D01*
G01X1294810D01*
G02X1292822I-994J989D01*
G01X1286272D01*
X1286250Y-14697D01*
G02X1283927Y-15571I-1391J173D01*
G03X1283348Y-15621I-266J-299D01*
G02X1281047Y-15464I-1096J874D01*
G03X1280343Y-15495I-344J-205D01*
G02X1280321Y-14060I-1443J696D01*
G03X1281025Y-14068I354J186D01*
G02X1281840Y-13407I1227J-679D01*
G03X1282005Y-12742I-118J382D01*
G01X1279094Y-9830D01*
X1278148D01*
G03X1277748Y-10235I0J-400D01*
G02X1275090Y-10873I-1402J-15D01*
G03X1274449Y-10768I-358J-178D01*
G01X1271715Y-13502D01*
X1031184D01*
G02X1030139Y-11167I0J1402D01*
G03X1029548Y-10625I-299J267D01*
G02X1028603Y-11063I-1020J961D01*
G02X1025803Y-11098I-1401J57D01*
G02X1024798Y-10633I38J1401D01*
G03X1024201Y-11167I-298J-267D01*
G02X1023156Y-13502I-1045J-933D01*
G01X954372D01*
Y-8141D01*
X954419Y-7982D01*
G03Y-7720I-483J131D01*
G01X954372Y-7561D01*
Y-5501D01*
G03X953964Y-5102I-400J-1D01*
G02Y-2298I-28J1402D01*
G03X954372Y-1899I8J400D01*
G01Y10313D01*
G37*
G36*
G01X714334Y-17027D02*
G02X712514Y-17832I-510J-1306D01*
G03X712286Y-17317I-373J143D01*
G02X711398Y-16115I510J1306D01*
G03X710836Y-15780I-399J-30D01*
G02X709291Y-13490I-573J1280D01*
G03X709305Y-12928I-277J288D01*
G02X711299Y-12978I1022J960D01*
G03X711285Y-13540I277J-288D01*
G02X711661Y-14396I-1022J-960D01*
G03X712223Y-14731I399J30D01*
G02X714106Y-16512I573J-1280D01*
G03X714334Y-17027I373J-143D01*
G37*
G36*
G01X1674935Y-17561D02*
G02X1674904Y-16078I-1435J712D01*
G03X1675602Y-16084I351J193D01*
G02X1675632Y-17526I1217J-696D01*
G03X1674935Y-17561I-339J-213D01*
G37*
G36*
G01X1498611Y-11287D02*
G02X1497445Y-12317I189J-1389D01*
G03X1496979Y-11822I-387J103D01*
G02X1498178Y-10763I-319J1570D01*
G03X1498611Y-11287I379J-127D01*
G37*
G36*
G01X735454Y-7525D02*
G02X734182Y-7734I-434J-1333D01*
G03X734066Y-7033I-239J320D01*
G02X733101Y-5790I434J1333D01*
G03X732588Y-5432I-399J-25D01*
G02X731232Y-3064I-397J1345D01*
G03X731260Y-2509I-273J292D01*
G02X733327Y-616I1056J922D01*
G03X733905I289J277D01*
G02Y-2558I1011J-971D01*
G03X733327I-289J-277D01*
G02X733275Y-2610I-1017J965D01*
G03X733247Y-3165I273J-292D01*
G02X733590Y-3997I-1056J-922D01*
G03X734103Y-4355I399J25D01*
G02X735338Y-6824I397J-1345D01*
G03X735454Y-7525I239J-320D01*
G37*
G36*
G01X1606667Y-4377D02*
G02Y-2823I-1167J777D01*
G03X1607333I333J222D01*
G02Y-4377I1167J-777D01*
G03X1606667I-333J-222D01*
G37*
G36*
G01X1837406Y-2254D02*
G02X1836404Y-3467I394J-1346D01*
G03X1835894Y-3046I-398J37D01*
G02X1836896Y-1833I-394J1346D01*
G03X1837406Y-2254I398J-37D01*
G37*
G36*
G01X624333Y-2565D02*
G02X623044Y-1599I-1333J-435D01*
G03X623437Y-1075I13J400D01*
G02X624726Y-2041I1333J435D01*
G03X624333Y-2565I-13J-400D01*
G37*
G36*
G01X1689167Y2223D02*
G02Y3777I-1167J777D01*
G03X1689833I333J222D01*
G02Y2223I1167J-777D01*
G03X1689167I-333J-222D01*
G37*
G36*
G01X1547967Y2623D02*
G02Y4177I-1167J777D01*
G03X1548633I333J222D01*
G02X1550773Y4410I1167J-777D01*
G03X1551327I277J288D01*
G02X1553273I973J-1010D01*
G03X1553827I277J288D01*
G02X1556045Y4045I973J-1010D01*
G03X1556755I355J184D01*
G02X1558973Y4410I1245J-645D01*
G03X1559527I277J288D01*
G02X1561550Y4329I973J-1010D01*
G03X1562150I300J265D01*
G02X1564289Y4283I1050J-929D01*
G03X1564911I311J252D01*
G02X1567167Y4177I1089J-883D01*
G03X1567833I333J222D01*
G02Y2623I1167J-777D01*
G03X1567167I-333J-222D01*
G02X1564911Y2517I-1167J777D01*
G03X1564289I-311J-252D01*
G02X1562150Y2471I-1089J883D01*
G03X1561550I-300J-265D01*
G02X1559527Y2390I-1050J929D01*
G03X1558973I-277J-288D01*
G02X1556755Y2755I-973J1010D01*
G03X1556045I-355J-184D01*
G02X1553827Y2390I-1245J645D01*
G03X1553273I-277J-288D01*
G02X1551327I-973J1010D01*
G03X1550773I-277J-288D01*
G02X1548633Y2623I-973J1010D01*
G03X1547967I-333J-222D01*
G37*
G36*
G01X1510373Y2490D02*
G02Y4510I-973J1010D01*
G03X1510927I277J288D01*
G02X1512873I973J-1010D01*
G03X1513427I277J288D01*
G02X1515373I973J-1010D01*
G03X1515927I277J288D01*
G02X1518145Y4145I973J-1010D01*
G03X1518855I355J184D01*
G02Y2855I1245J-645D01*
G03X1518145I-355J-184D01*
G02X1515927Y2490I-1245J645D01*
G03X1515373I-277J-288D01*
G02X1513427I-973J1010D01*
G03X1512873I-277J-288D01*
G02X1510927I-973J1010D01*
G03X1510373I-277J-288D01*
G37*
G36*
G01X1525889Y2617D02*
G02Y4383I-1089J883D01*
G03X1526511I311J252D01*
G02X1528845Y4145I1089J-883D01*
G03X1529555I355J184D01*
G02X1532045I1245J-645D01*
G03X1532755I355J184D01*
G02Y2855I1245J-645D01*
G03X1532045I-355J-184D01*
G02X1529555I-1245J645D01*
G03X1528845I-355J-184D01*
G02X1526511Y2617I-1245J645D01*
G03X1525889I-311J-252D01*
G37*
G36*
G01X1786560Y7365D02*
G02X1786549Y8852I-1194J735D01*
G03X1787227Y8857I337J215D01*
G02X1787238Y7370I1194J-735D01*
G03X1786560Y7365I-337J-215D01*
G37*
G36*
G01X649581Y7600D02*
G02X647784Y9724I-1031J950D01*
G03X647773Y10401I-218J335D01*
G02X649474Y12608I727J1199D01*
G03X650051Y12630I278J288D01*
G02X651847Y10513I1049J-931D01*
G03Y9837I213J-338D01*
G02X650147Y7622I-747J-1186D01*
G03X649581Y7600I-272J-293D01*
G37*
G36*
G01X1809523Y10358D02*
G02X1807832Y10471I-920J-1058D01*
G03X1807875Y11107I-220J334D01*
G02X1809566Y10994I920J1058D01*
G03X1809523Y10358I220J-334D01*
G37*
G36*
G01X1619797Y12266D02*
X1624799D01*
G02X1626310Y10765I0J-1512D01*
G01Y10670D01*
X1626300Y10586D01*
G02X1624798Y9244I-1502J169D01*
G01X1619796D01*
G02X1618983Y9482I1J1511D01*
G03X1618375Y9224I-216J-336D01*
G02X1617708Y10710I-1375J276D01*
G03X1618305Y10992I202J345D01*
G02X1619797Y12266I1493J-237D01*
G37*
G36*
G01X1842292Y10352D02*
G02X1842206Y8838I1134J-824D01*
G03X1841534Y8876I-348J-197D01*
G02X1839427Y8690I-1134J824D01*
G03X1838873I-277J-288D01*
G02Y10710I-973J1010D01*
G03X1839427I277J288D01*
G02X1841620Y10390I972J-1010D01*
G03X1842292Y10352I348J197D01*
G37*
G36*
G01X1833522Y11557D02*
G02X1831621Y9726I-622J-1257D01*
G03X1830952Y9822I-365J-164D01*
G02X1831167Y11309I-1064J913D01*
G03X1831836Y11213I365J164D01*
G02X1832233Y11533I1064J-913D01*
G03X1832220Y12243I-190J352D01*
G02X1833509Y12267I621J1257D01*
G03X1833522Y11557I190J-352D01*
G37*
G36*
G01X63880Y12677D02*
G02X62764Y11443I279J-1374D01*
G03X62287Y11875I-398J40D01*
G02X63403Y13109I-279J1374D01*
G03X63880Y12677I398J-40D01*
G37*
G36*
G01X1847352Y13735D02*
G02X1847035Y12168I970J-1012D01*
G03X1846390Y12298I-368J-158D01*
G02X1846707Y13865I-970J1012D01*
G03X1847352Y13735I368J158D01*
G37*
G36*
G01X1869503Y12151D02*
G02X1869308Y13808I-1217J697D01*
G03X1869946Y13883I291J274D01*
G02X1870141Y12226I1217J-697D01*
G03X1869503Y12151I-291J-274D01*
G37*
G36*
G01X1414946Y12458D02*
G02Y13820I-1225J681D01*
G03X1415646I350J194D01*
G02Y12458I1225J-681D01*
G03X1414946I-350J-194D01*
G37*
G36*
G01X25301Y17595D02*
G02X23782Y16791I-241J-1381D01*
G03X23487Y17350I-364J165D01*
G02X25006Y18154I241J1381D01*
G03X25301Y17595I364J-165D01*
G37*
G36*
G01X63377Y18524D02*
G02X62881Y16915I823J-1135D01*
G03X62269Y17103I-376J-135D01*
G02X62765Y18712I-823J1135D01*
G03X63377Y18524I376J135D01*
G37*
G36*
G01X35905Y18708D02*
G02X35882Y20238I-1186J747D01*
G03X36553Y20248I332J223D01*
G02X38615Y20596I1186J-747D01*
G03X39234Y20755I250J312D01*
G02X39654Y19125I1296J-535D01*
G03X39035Y18966I-250J-312D01*
G02X36576Y18718I-1296J535D01*
G03X35905Y18708I-332J-223D01*
G37*
G36*
G01X702306Y18872D02*
G02X700071Y18689I-1186J747D01*
G03X699483Y18700I-299J-266D01*
G02X699519Y20599I-1013J969D01*
G03X700107Y20588I299J266D01*
G02X702291Y20390I1013J-969D01*
G03X702964Y20397I334J220D01*
G02X702979Y18879I1186J-747D01*
G03X702306Y18872I-334J-220D01*
G37*
G36*
G01X1853568Y21812D02*
G02X1851033Y22017I-1332J-694D01*
G03X1850781Y22650I-321J239D01*
G02X1850430Y25502I259J1479D01*
G03X1850618Y26060I-163J366D01*
G02X1852351Y25337I1318J720D01*
G03X1852246Y25025I56J-192D01*
G02X1852325Y24907I-1207J-894D01*
G03X1852647Y24879I171J104D01*
G02X1853803Y25396I1134J-985D01*
G03X1854151Y26003I6J400D01*
G02X1855414Y25278I1285J777D01*
G03X1855066Y24671I-6J-400D01*
G02X1853893Y22396I-1285J-777D01*
G03X1853568Y21812I29J-399D01*
G37*
G36*
G01X1857168D02*
G02X1855724Y22616I-1332J-694D01*
G03X1856049Y23200I-29J399D01*
G02X1857403Y25396I1332J694D01*
G03X1857751Y26003I6J400D01*
G02X1859014Y25278I1285J777D01*
G03X1858666Y24671I-6J-400D01*
G02X1857493Y22396I-1285J-777D01*
G03X1857168Y21812I29J-399D01*
G37*
G36*
G01X1860768D02*
G02X1859324Y22616I-1332J-694D01*
G03X1859649Y23200I-29J399D01*
G02X1861003Y25396I1332J694D01*
G03X1861351Y26003I6J400D01*
G02X1864093Y26413I1285J777D01*
G03X1864384Y25927I388J-98D01*
G02X1865444Y23992I-364J-1457D01*
G03X1865745Y23473I379J-127D01*
G02X1864812Y20640I-296J-1473D01*
G03X1864284Y20455I-170J-362D01*
G02X1861610Y21824I-1348J663D01*
G03X1861199Y22408I-353J188D01*
G02X1861093Y22396I-222J1486D01*
G03X1860768Y21812I29J-399D01*
G37*
G36*
G01X1839435Y20812D02*
G02X1836914Y20579I-1335J688D01*
G03X1836287Y20585I-316J-245D01*
G02X1833917Y20634I-1166J947D01*
G03X1833275I-321J-239D01*
G02Y22430I-1204J898D01*
G03X1833917I321J239D01*
G02X1836307Y22453I1204J-898D01*
G03X1836934Y22447I316J245D01*
G02X1839375Y22295I1166J-947D01*
G03X1840064Y22312I339J211D01*
G02X1840124Y20852I1225J-681D01*
G03X1839435Y20812I-333J-222D01*
G37*
G36*
G01X1878304Y23696D02*
G02X1878951Y21990I3291J272D01*
G03X1878242Y21846I-320J-240D01*
G02X1877678Y23334I-1361J335D01*
G03X1878304Y23696I227J329D01*
G37*
G36*
G01X755559Y23924D02*
G02X755505Y22420I1155J-794D01*
G03X754830Y22445I-345J-202D01*
G02X754884Y23949I-1155J794D01*
G03X755559Y23924I345J202D01*
G37*
G36*
G01X713670Y24408D02*
G02X713617Y22895I1153J-798D01*
G03X712944Y22918I-344J-204D01*
G02X712997Y24431I-1153J798D01*
G03X713670Y24408I344J204D01*
G37*
G36*
G01X1871884Y25563D02*
G02X1869964Y26249I-1284J-563D01*
G03X1870029Y26921I-181J357D01*
G02X1872259Y26123I2314J2953D01*
G03X1871884Y25563I-8J-400D01*
G37*
G36*
G01X1837669Y27730D02*
G02X1837537Y25688I1031J-1092D01*
G03X1836952Y25726I-310J-253D01*
G02X1834677Y25976I-1031J1092D01*
G03X1834015I-331J-224D01*
G02X1831521Y25986I-1244J842D01*
G03X1830843Y25967I-333J-222D01*
G02X1830776Y27496I-1207J713D01*
G03X1831452Y27537I325J233D01*
G02X1834015Y27660I1319J-719D01*
G03X1834677I331J224D01*
G02X1837084Y27768I1244J-842D01*
G03X1837669Y27730I310J253D01*
G37*
G36*
G01X643566Y30162D02*
G02X643831Y32385I-5773J1815D01*
G03X644497Y32113I399J26D01*
G02X644277Y30270I933J-1046D01*
G03X643566Y30162I-329J-228D01*
G37*
G36*
G01X1855356Y35523D02*
G02X1855081Y33888I977J-1005D01*
G03X1854444Y33995I-358J-180D01*
G02X1854719Y35630I-977J1005D01*
G03X1855356Y35523I358J180D01*
G37*
G36*
G01X702098Y36889D02*
G02X700469Y36532I-573J-1279D01*
G03X700331Y37160I-302J263D01*
G02X701960Y37517I573J1279D01*
G03X702098Y36889I302J-263D01*
G37*
G36*
G01X3401Y37588D02*
G02X2221Y36451I199J-1388D01*
G03X1771Y36919I-393J72D01*
G02X2951Y38056I-199J1388D01*
G03X3401Y37588I393J-72D01*
G37*
G36*
G01X1818049Y38126D02*
G02X1816526Y38042I-697J-1217D01*
G03X1816489Y38712I-236J323D01*
G02X1818012Y38796I697J1217D01*
G03X1818049Y38126I236J-323D01*
G37*
G36*
G01X1879863Y38648D02*
G02X1877978Y38508I-866J-1102D01*
G03X1877934Y39098I-291J275D01*
G02X1878027Y41370I866J1102D01*
G03Y42037I-220J334D01*
G02X1879573I773J1170D01*
G03Y41370I220J-333D01*
G02X1879819Y39238I-773J-1169D01*
G03X1879863Y38648I291J-275D01*
G37*
G36*
G01X717821Y39557D02*
G02X715736Y37718I-921J-1057D01*
G03X715097Y37752I-332J-223D01*
G02X712873Y37851I-1074J901D01*
G03X712224Y37862I-328J-228D01*
G02X710054Y39634I-1123J839D01*
G03Y40166I-298J266D01*
G02X712250Y41902I1046J933D01*
G03X712899Y41891I328J228D01*
G02X713154Y42154I1126J-836D01*
G03X713149Y42786I-247J314D01*
G02X713067Y44947I851J1114D01*
G03X712995Y45595I-266J298D01*
G02X714647Y47831I679J1227D01*
G03X715203I278J288D01*
G02X717077Y47896I973J-1009D01*
G03X717615Y47918I257J307D01*
G02X718193Y48263I987J-996D01*
G03X718471Y48718I-115J383D01*
G02X720796Y50005I1379J252D01*
G03X721342Y50011I270J295D01*
G02X723690Y48740I970J-1012D01*
G03X723976Y48280I393J-75D01*
G02X722657Y45894I-373J-1351D01*
G03X722111Y45888I-270J-295D01*
G02X720144Y45914I-970J1012D01*
G03X719580Y45919I-285J-281D01*
G02X717699Y45847I-980J1002D01*
G03X717161Y45825I-257J-307D01*
G02X717105Y45772I-991J991D01*
G03X717222Y45101I265J-299D01*
G02X717628Y42749I-522J-1301D01*
G03X717637Y42141I264J-300D01*
G02X717786Y40126I-895J-1079D01*
G03X717821Y39557I298J-267D01*
G37*
G36*
G01X1825416Y39145D02*
G02X1824999Y40803I-1286J558D01*
G03X1825614Y40958I248J314D01*
G02X1826031Y39300I1286J-558D01*
G03X1825416Y39145I-248J-314D01*
G37*
G36*
G01X1637398Y38350D02*
X1632398D01*
G02X1630896Y39694I0J1512D01*
G03X1630473Y40049I-398J-44D01*
G02X1629531Y40337I-87J1399D01*
G03X1629211Y40150I-122J-159D01*
G02X1629219Y40082I-1497J-211D01*
G01X1629226Y40019D01*
X1629227Y39956D01*
G02Y39911I-1512J-23D01*
G01X1629226Y39910D01*
Y39900D01*
G02X1627725Y38423I-1511J34D01*
G01X1622645Y38389D01*
G02X1622625Y41411I-10J1511D01*
G01X1627704Y41445D01*
G02X1628410Y41277I13J-1512D01*
G03X1628991Y41591I183J355D01*
G02X1631767Y41690I1395J-143D01*
G03X1632211Y41362I394J69D01*
G02X1632398Y41374I190J-1500D01*
G01X1637399D01*
G02X1638910Y39872I-1J-1512D01*
G01Y39777D01*
X1638900Y39693D01*
G02X1637398Y38350I-1502J169D01*
G37*
G36*
G01X1868660Y40718D02*
G02X1867396Y41163I-1041J-939D01*
G03X1867629Y41826I-64J395D01*
G02X1868893Y41381I1041J939D01*
G03X1868660Y40718I64J-395D01*
G37*
G36*
G01X685717Y41085D02*
G02X684243Y41179I-813J-1142D01*
G03X684287Y41858I-188J353D01*
G02X685761Y41764I813J1142D01*
G03X685717Y41085I188J-353D01*
G37*
G36*
G01X1350135Y39522D02*
G02X1350061Y41113I-1190J742D01*
G03X1350718Y41144I318J243D01*
G02X1350792Y39553I1190J-742D01*
G03X1350135Y39522I-318J-243D01*
G37*
G36*
G01X1856584Y40050D02*
G02X1856393Y41790I-1184J751D01*
G03X1857014Y41858I283J282D01*
G02X1859170Y42118I1184J-750D01*
G03X1859745Y42139I277J288D01*
G02X1859814Y40190I1041J-939D01*
G03X1859239Y40169I-277J-288D01*
G02X1857205Y40118I-1041J939D01*
G03X1856584Y40050I-283J-282D01*
G37*
G36*
G01X657040Y43629D02*
G02X655290Y45806I-972J1010D01*
G03Y46472I-222J333D01*
G02X657040Y48649I778J1167D01*
G03X657594I277J288D01*
G02X659344Y46472I972J-1010D01*
G03Y45806I222J-333D01*
G02X657594Y43629I-778J-1167D01*
G03X657040I-277J-288D01*
G37*
G36*
G01X1378856Y46412D02*
G02X1377714Y45162I254J-1379D01*
G03X1377243Y45592I-398J37D01*
G02X1378385Y46842I-254J1379D01*
G03X1378856Y46412I398J-37D01*
G37*
G36*
G01X12409Y48226D02*
G02X10405Y47952I-870J-1099D01*
G03X10330Y48501I-323J235D01*
G02X10187Y48631I869J1100D01*
G03X9632Y48653I-289J-277D01*
G02X9713Y50669I-932J1047D01*
G03X10268Y50647I289J277D01*
G02X12303Y50466I932J-1047D01*
G03X12926Y50459I314J247D01*
G02X12773Y48910I1084J-889D01*
G03X12422Y48913I-176J-94D01*
G02X12334Y48775I-1224J684D01*
G03X12409Y48226I323J-235D01*
G37*
G36*
G01X-8844Y50087D02*
G02X-8845Y51712I-1143J812D01*
G03X-8193I326J232D01*
G02X-8192Y50087I1143J-812D01*
G03X-8844I-326J-232D01*
G37*
G36*
G01X1393023Y54549D02*
G02X1391273Y56726I-972J1010D01*
G03Y57392I-222J333D01*
G02X1393023Y59569I778J1167D01*
G03X1393577I277J288D01*
G02X1395523I973J-1010D01*
G03X1396077I277J288D01*
G02X1397827Y57392I972J-1010D01*
G03Y56726I222J-333D01*
G02X1396077Y54549I-778J-1167D01*
G03X1395523I-277J-288D01*
G02X1393577I-973J1010D01*
G03X1393023I-277J-288D01*
G37*
G36*
G01X2629Y57596D02*
G02X1052Y57616I-803J-1149D01*
G03X1060Y58277I-221J333D01*
G02X2637Y58257I803J1149D01*
G03X2629Y57596I221J-333D01*
G37*
G36*
G01X-7239Y59518D02*
G02X-9396Y60971I-1371J292D01*
G03X-9343Y61590I-224J331D01*
G02X-9771Y62657I973J1010D01*
G03X-10237Y63068I-400J16D01*
G02X-11672Y63728I-234J1382D01*
G03X-12369Y63708I-343J-206D01*
G02X-12408Y65082I-1241J652D01*
G03X-11711Y65102I343J206D01*
G02X-10689Y65835I1241J-652D01*
G03X-10449Y66492I-62J395D01*
G02X-9171Y66025I1060J918D01*
G03X-9411Y65368I62J-395D01*
G02X-9069Y64393I-1059J-919D01*
G03X-8603Y63982I400J-16D01*
G02X-6972Y62710I233J-1382D01*
G03X-6449Y62362I398J32D01*
G02X-6662Y59789I439J-1332D01*
G03X-7239Y59518I-186J-354D01*
G37*
G36*
G01X1875282Y59842D02*
G02X1875079Y61138I-1326J456D01*
G03X1875777Y61248I320J240D01*
G02X1875980Y59952I1326J-456D01*
G03X1875282Y59842I-320J-240D01*
G37*
G36*
G01X1393350Y64127D02*
G02X1391442Y66175I-1011J971D01*
G03X1391400Y66821I-256J308D01*
G02X1393262Y68858I749J1185D01*
G03X1393906Y68870I318J243D01*
G02X1396023Y69069I1144J-811D01*
G03X1396577I277J288D01*
G02X1398345Y66904I972J-1011D01*
G03X1398342Y66247I227J-330D01*
G02X1396528Y64127I-802J-1149D01*
G03X1395950I-289J-277D01*
G02X1393928I-1011J971D01*
G03X1393350I-289J-277D01*
G37*
G36*
G01X656573Y65090D02*
G02X654823Y67267I-972J1010D01*
G03Y67933I-222J333D01*
G02X656573Y70110I778J1167D01*
G03X657127I277J288D01*
G02X658877Y67933I972J-1010D01*
G03Y67267I222J-333D01*
G02X657127Y65090I-778J-1167D01*
G03X656573I-277J-288D01*
G37*
G36*
G01X1845071Y66284D02*
G02X1842659Y67986I-1046J1078D01*
G03X1842341Y68550I-364J167D01*
G02X1841469Y68964I174J1492D01*
G03X1840911I-279J-286D01*
G02X1838843Y68942I-1046J1078D01*
G03X1838274Y68917I-272J-293D01*
G02X1835783Y69328I-1113J1009D01*
G03X1835131Y69449I-367J-159D01*
G02X1832991Y69445I-1072J1052D01*
G03X1832445Y69466I-284J-281D01*
G02X1830402Y71666I-985J1134D01*
G03Y72234I-282J284D01*
G02X1832518I1058J1066D01*
G03Y71666I282J-284D01*
G02X1832528Y71656I-1057J-1067D01*
G03X1833074Y71635I284J281D01*
G02X1835531Y70802I985J-1134D01*
G03X1835895Y70734I196J40D01*
G02X1836052Y70939I1267J-807D01*
G03X1836045Y71486I-295J270D01*
G02X1835714Y73030I1084J1040D01*
G03X1835417Y73557I-377J135D01*
G02X1835353Y76487I297J1472D01*
G03X1835640Y76992I-96J388D01*
G02X1838194Y78433I1437J437D01*
G03X1838806Y78452I298J267D01*
G02X1841062Y78569I1179J-930D01*
G03X1841650Y78585I287J279D01*
G02X1844210Y77131I1133J-986D01*
G03X1844476Y76624I380J-124D01*
G02X1845115Y76242I-427J-1440D01*
G03X1845665Y76225I284J281D01*
G02X1846921Y73626I1002J-1119D01*
G03X1846605Y73118I68J-394D01*
G02X1846243Y71646I-1440J-426D01*
G03Y71088I286J-279D01*
G02X1846531Y69418I-1078J-1046D01*
G03X1846849Y68854I364J-167D01*
G02X1847721Y68440I-174J-1492D01*
G03X1848279I279J286D01*
G02Y66284I1046J-1078D01*
G03X1847721I-279J-286D01*
G02X1845629I-1046J1078D01*
G03X1845071I-279J-286D01*
G37*
G36*
G01X1665360Y70935D02*
G02X1663340I-1010J-973D01*
G03Y71489I-288J277D01*
G02X1663233Y71615I1013J969D01*
G03X1662885Y71561I-159J-121D01*
G02X1661123Y70697I-1322J467D01*
G03X1660598Y70311I-125J-380D01*
G02X1659636Y71622I-1402J-20D01*
G03X1660161Y72008I125J380D01*
G02X1660178Y72245I1402J19D01*
G03X1659870Y72443I-198J31D01*
G02X1658127Y72604I-771J1171D01*
G03X1657573I-277J-288D01*
G02Y74624I-973J1010D01*
G03X1658127I277J288D01*
G02X1660500Y73684I973J-1010D01*
G03X1661047Y73332I399J20D01*
G02X1662513Y73059I516J-1304D01*
G03X1663132Y73155I271J294D01*
G02X1665360Y71489I1219J-693D01*
G03Y70935I288J-277D01*
G37*
G36*
G01X1767991Y71341D02*
G02X1767899Y69490I1259J-990D01*
G03X1767268Y69547I-338J-215D01*
G02X1767358Y71346I-1028J953D01*
G03X1767991Y71341I318J242D01*
G37*
G36*
G01X1931256Y69430D02*
G02X1929064Y71484I-1106J1017D01*
G03X1929024Y72073I-289J276D01*
G02X1928738Y72375I937J1174D01*
G03X1928075Y72356I-325J-233D01*
G02X1928001Y73961I-1185J750D01*
G03X1928663Y74004I317J244D01*
G02X1931031Y74301I1298J-757D01*
G03X1931613Y74314I285J281D01*
G02X1933791Y74373I1117J-1004D01*
G03X1934342Y74360I282J284D01*
G02X1935084Y74725I1008J-1113D01*
G03X1935370Y75302I-70J394D01*
G02X1937793Y77024I1337J685D01*
G03X1938374Y77027I289J276D01*
G02X1940610Y76978I1096J-1027D01*
G03X1941224Y76987I303J261D01*
G02X1943420Y77133I1166J-947D01*
G03X1943973Y77137I274J291D01*
G02X1946398Y75462I1047J-1077D01*
G03X1946678Y74913I367J-159D01*
G02X1947377Y74543I-328J-1466D01*
G03X1947924Y74544I273J292D01*
G02Y72352I1027J-1096D01*
G03X1947377Y72351I-273J-292D01*
G02X1945281Y72392I-1027J1096D01*
G03X1944692Y72371I-285J-281D01*
G02X1944640Y72314I-1135J983D01*
G03X1944682Y71725I290J-275D01*
G02X1942644Y69530I-933J-1177D01*
G03X1942056I-294J-270D01*
G02X1939881Y69492I-1106J1017D01*
G03X1939292Y69471I-285J-281D01*
G02X1937123Y69351I-1142J976D01*
G03X1936577I-273J-292D01*
G02X1934523I-1027J1096D01*
G03X1933977I-273J-292D01*
G02X1931844Y69430I-1027J1096D01*
G03X1931256I-294J-270D01*
G37*
G36*
G01X1613948Y71562D02*
G02X1613859Y70164I1167J-776D01*
G03X1613167Y70208I-359J-178D01*
G02X1613256Y71606I-1167J776D01*
G03X1613948Y71562I359J178D01*
G37*
G36*
G01X1585945Y70110D02*
G02X1585874Y71675I-1197J730D01*
G03X1586537Y71704I322J238D01*
G02X1586608Y70139I1197J-730D01*
G03X1585945Y70110I-322J-238D01*
G37*
G36*
G01X650973Y71290D02*
G02X649223Y73467I-972J1010D01*
G03Y74133I-222J333D01*
G02X650973Y76310I778J1167D01*
G03X651527I277J288D01*
G02X653277Y74133I972J-1010D01*
G03Y73467I222J-333D01*
G02X651527Y71290I-778J-1167D01*
G03X650973I-277J-288D01*
G37*
G36*
G01X657473D02*
G02X655723Y73467I-972J1010D01*
G03Y74133I-222J333D01*
G02X657473Y76310I778J1167D01*
G03X658027I277J288D01*
G02X659777Y74133I972J-1010D01*
G03Y73467I222J-333D01*
G02X658027Y71290I-778J-1167D01*
G03X657473I-277J-288D01*
G37*
G36*
G01X1592905Y76213D02*
G02X1590493Y74840I-1305J-513D01*
G03X1589907Y74890I-316J-245D01*
G02X1590069Y76786I-945J1036D01*
G03X1590655Y76736I316J245D01*
G02X1591385Y77085I944J-1037D01*
G03X1591695Y77627I-62J395D01*
G02X1593215Y76755I1305J513D01*
G03X1592905Y76213I62J-395D01*
G37*
G36*
G01X1408457Y76508D02*
G02X1406582Y78504I-1157J792D01*
G03X1406729Y79037I-205J343D01*
G02X1406651Y79208I1234J666D01*
G03X1406277I-187J-70D01*
G02X1403617Y80088I-1313J492D01*
G03X1403239Y80598I-385J110D01*
G02X1404431Y82777I25J1402D01*
G03X1405097I333J222D01*
G02X1407431I1167J-777D01*
G03X1408097I333J222D01*
G02X1409588Y80636I1167J-777D01*
G03X1409300Y80126I93J-389D01*
G02X1408682Y78496I-1336J-426D01*
G03X1408535Y77963I205J-343D01*
G02X1408549Y77938I-1216J-697D01*
G03X1408911Y77950I178J91D01*
G02X1409100Y76530I1289J-551D01*
G03X1408457Y76508I-313J-248D01*
G37*
G36*
G01X6314Y78585D02*
G02X4763Y78637I-815J-1141D01*
G03X4786Y79303I-210J341D01*
G02X6337Y79251I815J1141D01*
G03X6314Y78585I210J-341D01*
G37*
G36*
G01X764202Y79450D02*
G02X762559Y79422I-802J-1150D01*
G03X762548Y80070I-240J320D01*
G02X764191Y80098I802J1150D01*
G03X764202Y79450I240J-320D01*
G37*
G36*
G01X12658Y79649D02*
G02X10884Y79496I-794J-1155D01*
G03X10831Y80112I-280J286D01*
G02X10652Y80257I790J1158D01*
G03X10098I-277J-288D01*
G02X8520Y82532I-972J1010D01*
G03X8543Y83242I-172J361D01*
G02X8187Y83524I681J1226D01*
G03X7583Y83509I-296J-269D01*
G02X7538Y85343I-1083J891D01*
G03X8142Y85358I296J269D01*
G02X10198Y85477I1083J-891D01*
G03X10752I277J288D01*
G02X12330Y83202I972J-1010D01*
G03X12307Y82492I172J-361D01*
G02X12605Y80265I-682J-1225D01*
G03X12658Y79649I280J-286D01*
G37*
G36*
G01X1518409Y78143D02*
G02X1518368Y79500I-1247J641D01*
G03X1519067Y79521I344J204D01*
G02X1519077Y79539I1230J-672D01*
G03X1518914Y80079I-353J188D01*
G02X1520817Y80654I666J1234D01*
G03X1520980Y80114I353J-188D01*
G02X1519108Y78164I-666J-1234D01*
G03X1518409Y78143I-344J-204D01*
G37*
G36*
G01X-10313Y78490D02*
G02X-12501Y78378I-1139J818D01*
G03X-13089Y78389I-299J-266D01*
G02X-15075Y78348I-1013J969D01*
G03X-15629I-277J-288D01*
G02X-17612Y80331I-973J1010D01*
G03Y80885I-288J277D01*
G02X-15629Y82868I1010J973D01*
G03X-15075I277J288D01*
G02X-13053Y82788I973J-1010D01*
G03X-12465Y82777I299J266D01*
G02X-10342Y82665I1013J-969D01*
G03X-9701Y82676I316J244D01*
G02X-9678Y82707I1137J-820D01*
G03X-9733Y83251I-318J243D01*
G02X-7669Y85121I922J1057D01*
G03X-7026Y85109I326J232D01*
G02X-4846Y83347I1114J-852D01*
G03X-4835Y82814I304J-260D01*
G02X-4878Y80857I-1025J-956D01*
G03X-4894Y80302I280J-286D01*
G02X-6954Y78400I-1036J-944D01*
G03X-7538I-292J-273D01*
G02X-9672Y78501I-1024J958D01*
G03X-10313Y78490I-316J-244D01*
G37*
G36*
G01X733908Y81859D02*
G02X733868Y83450I-1174J766D01*
G03X734526Y83467I323J236D01*
G02X734566Y81876I1174J-766D01*
G03X733908Y81859I-323J-236D01*
G37*
G36*
G01X1574210Y83318D02*
G02X1574165Y84982I-1150J802D01*
G03X1574809Y85000I315J246D01*
G02X1574854Y83336I1150J-802D01*
G03X1574210Y83318I-315J-246D01*
G37*
G36*
G01X648982Y84439D02*
G02X646223Y84462I-1382J-239D01*
G03X645912Y84928I-393J74D01*
G02X645190Y87273I288J1372D01*
G03Y87827I-288J277D01*
G02X647367Y89577I1010J972D01*
G03X648033I333J222D01*
G02X648721Y90117I1166J-778D01*
G03X648943Y90668I-137J376D01*
G02X648914Y90733I1266J604D01*
G03X648270Y90866I-368J-157D01*
G02X646161Y91070I-966J1016D01*
G03X645628Y91181I-326J-231D01*
G02X646047Y93194I-724J1201D01*
G03X646580Y93083I326J231D01*
G02X648594Y92431I724J-1201D01*
G03X649238Y92298I368J157D01*
G02X651486Y91850I966J-1016D01*
G03X652063Y91672I366J162D01*
G02X651522Y89914I741J-1190D01*
G03X650945Y90092I-366J-162D01*
G02X650683Y89965I-739J1191D01*
G03X650461Y89414I137J-376D01*
G02X650210Y87827I-1261J-614D01*
G03Y87273I288J-277D01*
G02X649337Y84905I-1010J-973D01*
G03X648982Y84439I39J-398D01*
G37*
G36*
G01X1318622Y84134D02*
G02X1316250Y85529I-1322J466D01*
G03X1316227Y86084I-299J266D01*
G02X1316228Y88114I968J1015D01*
G03X1316252Y88669I-275J290D01*
G02X1318267Y88584I1049J931D01*
G03X1318243Y88029I275J-290D01*
G02X1318245Y86169I-1048J-931D01*
G03X1318268Y85614I299J-266D01*
G02X1318278Y85605I-933J-1047D01*
G03X1318615Y85717I140J143D01*
G02X1319222Y84334I1385J-217D01*
G03X1318622Y84134I-222J-333D01*
G37*
G36*
G01X768798Y85914D02*
G02X768120Y84453I702J-1214D01*
G03X767526Y84729I-394J-70D01*
G02X765913Y84877I-702J1214D01*
G03X765271Y84690I-260J-304D01*
G02X764841Y86166I-1341J410D01*
G03X765483Y86353I260J304D01*
G02X768204Y86190I1341J-410D01*
G03X768798Y85914I394J70D01*
G37*
G36*
G01X1758640Y84149D02*
G02X1758460Y85705I-1245J644D01*
G03X1759119Y85781I304J260D01*
G02X1759299Y84225I1245J-644D01*
G03X1758640Y84149I-304J-260D01*
G37*
G36*
G01X714182Y87090D02*
G02X712274Y86956I-882J-1090D01*
G03X712233Y87539I-293J272D01*
G02X714330Y89329I882J1090D01*
G03X715030Y89341I347J199D01*
G02X715053Y87983I1238J-658D01*
G03X714353Y87971I-347J-199D01*
G02X714141Y87673I-1239J657D01*
G03X714182Y87090I293J-272D01*
G37*
G36*
G01X707312Y87073D02*
G02X704606Y86976I-1340J-413D01*
G03X704134Y87458I-389J91D01*
G02X705211Y88514I-289J1372D01*
G03X705683Y88032I389J-91D01*
G02X705688Y88033I277J-1374D01*
G03X705989Y88542I-81J392D01*
G02X707613Y87582I1340J413D01*
G03X707312Y87073I81J-392D01*
G37*
G36*
G01X1676511Y87846D02*
G02X1676437Y86108I1062J-916D01*
G03X1675811Y86134I-323J-235D01*
G02X1675885Y87872I-1062J916D01*
G03X1676511Y87846I323J235D01*
G37*
G36*
G01X7750Y87098D02*
G02X7648Y88832I-1150J802D01*
G03X8275Y88869I299J265D01*
G02X10398Y89077I1150J-802D01*
G03X10952I277J288D01*
G02Y87057I973J-1010D01*
G03X10398I-277J-288D01*
G02X8377Y87135I-973J1010D01*
G03X7750Y87098I-299J-265D01*
G37*
G36*
G01X1312558Y92415D02*
G02X1310554Y92409I-999J-984D01*
G03X1310552Y92968I-287J278D01*
G02X1310472Y93057I1002J981D01*
G03X1310152Y93039I-153J-128D01*
G02X1308161Y94950I-1168J775D01*
G03X1308159Y95600I-234J324D01*
G02X1309794Y95606I813J1142D01*
G03X1309796Y94956I234J-324D01*
G02X1309929Y94848I-815J-1140D01*
G03X1310499Y94879I270J295D01*
G02X1312556Y92974I1052J-927D01*
G03X1312558Y92415I287J-278D01*
G37*
G36*
G01X1377332Y92806D02*
G02X1377230Y91313I1132J-827D01*
G03X1376554Y91358I-352J-190D01*
G02X1376656Y92853I-1142J829D01*
G03X1377332Y92806I353J189D01*
G37*
G36*
G01X1455416Y93465D02*
G02X1454081Y92667I-69J-1400D01*
G03X1453740Y93239I-361J172D01*
G02X1455075Y94037I69J1400D01*
G03X1455416Y93465I361J-172D01*
G37*
G36*
G01X692056Y93537D02*
G02X691687Y92008I944J-1037D01*
G03X691044Y92163I-374J-141D01*
G02X691413Y93692I-944J1037D01*
G03X692056Y93537I374J141D01*
G37*
G36*
G01X110302Y92129D02*
G02X110107Y93703I-1245J645D01*
G03X110762Y93784I300J265D01*
G02X110957Y92210I1245J-645D01*
G03X110302Y92129I-300J-265D01*
G37*
G36*
G01X733219Y93291D02*
G02X732024Y94187I-1309J-501D01*
G03X732431Y94729I33J399D01*
G02X733626Y93833I1309J501D01*
G03X733219Y93291I-33J-399D01*
G37*
G36*
G01X1919149Y94521D02*
G02X1917153Y94597I-1035J-945D01*
G03X1917174Y95158I-274J291D01*
G02X1917252Y97127I1036J945D01*
G03X1917206Y97748I-273J292D01*
G02X1918960Y97878I796J1154D01*
G03X1919006Y97257I273J-292D01*
G02X1919170Y95082I-796J-1154D01*
G03X1919149Y94521I274J-291D01*
G37*
G36*
G01X1296358Y95487D02*
G02X1294804I-777J-1167D01*
G03Y96153I-222J333D01*
G02X1296358I777J1167D01*
G03Y95487I222J-333D01*
G37*
G36*
G01X1693483Y93884D02*
G02X1693432Y95418I-1198J728D01*
G03X1694102Y95440I328J229D01*
G02X1696313Y95681I1198J-728D01*
G03X1696868Y95659I289J277D01*
G02X1696787Y93643I932J-1047D01*
G03X1696232Y93665I-289J-277D01*
G02X1694153Y93906I-932J1047D01*
G03X1693483Y93884I-328J-229D01*
G37*
G36*
G01X1363012Y95261D02*
G02X1360588Y96453I-1378J258D01*
G03Y96985I-298J266D01*
G02X1362680I1046J934D01*
G03Y96453I298J-266D01*
G02X1362959Y95976I-1047J-932D01*
G03X1363342Y96091I189J64D01*
G02X1363693Y95465I1358J350D01*
G03X1363012Y95261I-288J-278D01*
G37*
G36*
G01X1573433Y96756D02*
G02X1571776Y96784I-848J-1117D01*
G03X1571787Y97429I-231J327D01*
G02X1573444Y97401I848J1117D01*
G03X1573433Y96756I231J-327D01*
G37*
G36*
G01X1745442Y96580D02*
G02X1745127Y95325I1049J-930D01*
G03X1744447Y95507I-389J-93D01*
G02X1743673Y97690I-947J893D01*
G03X1744111Y98196I53J397D01*
G02X1745191Y97260I1253J354D01*
G03X1744753Y96754I-53J-397D01*
G02X1744757Y96741I-1242J-389D01*
G03X1745442Y96580I386J104D01*
G37*
G36*
G01X1289548Y96543D02*
G02Y98097I-1167J777D01*
G03X1290214I333J222D01*
G02Y96543I1167J-777D01*
G03X1289548I-333J-222D01*
G37*
G36*
G01X1945567Y98870D02*
G02X1945553Y97453I1203J-720D01*
G03X1944863Y97460I-347J-199D01*
G02X1944877Y98877I-1203J720D01*
G03X1945567Y98870I347J199D01*
G37*
G36*
G01X1269667Y101323D02*
G02X1267570Y103149I-1167J777D01*
G03X1267592Y103726I-266J299D01*
G02X1269724Y105538I1008J975D01*
G03X1270366I321J239D01*
G02X1272465Y103692I1124J-839D01*
G03X1272467Y103115I278J-288D01*
G02X1270333Y101323I-967J-1015D01*
G03X1269667I-333J-222D01*
G37*
G36*
G01X1875618Y103538D02*
G02X1874255Y104598I-1360J-342D01*
G03X1874641Y105096I-2J400D01*
G02X1876004Y104036I1360J342D01*
G03X1875618Y103538I2J-400D01*
G37*
G36*
G01X74915Y103760D02*
G02Y106240I-2115J1240D01*
G03X75606I346J202D01*
G02X79837Y106239I2115J-1240D01*
G03X80527I345J202D01*
G02X84758Y106240I2116J-1239D01*
G03X85449I345J202D01*
G02X89679I2115J-1240D01*
G03X90370I346J202D01*
G02X94600I2115J-1240D01*
G03X95291I345J202D01*
G02X99522Y106239I2115J-1240D01*
G03X100212I345J202D01*
G02X104443Y106240I2116J-1239D01*
G03X105134I345J202D01*
G02Y103760I2115J-1240D01*
G03X104443I-345J-202D01*
G02X100212Y103761I-2115J1240D01*
G03X99522I-345J-202D01*
G02X95291Y103760I-2116J1239D01*
G03X94600I-345J-202D01*
G02X90370I-2115J1240D01*
G03X89679I-345J-202D01*
G02X85449I-2115J1240D01*
G03X84758I-345J-202D01*
G02X80527Y103761I-2115J1240D01*
G03X79837I-345J-202D01*
G02X75606Y103760I-2116J1239D01*
G03X74915I-345J-202D01*
G37*
G36*
G01X1345919Y105559D02*
G02X1344470Y105798I-919J-1059D01*
G03X1344581Y106470I-151J370D01*
G02X1346030Y106231I919J1059D01*
G03X1345919Y105559I151J-370D01*
G37*
G36*
G01X121118Y107644D02*
G02X119537Y107824I-921J-1057D01*
G03X119612Y108478I-188J353D01*
G02X121193Y108298I921J1057D01*
G03X121118Y107644I188J-353D01*
G37*
G36*
G01X1392517Y107705D02*
G02X1392488Y109327I-1158J791D01*
G03X1393140Y109339I322J237D01*
G02X1393502Y109702I1157J-792D01*
G03X1393504Y110359I-227J329D01*
G02X1395106Y110352I806J1147D01*
G03X1395104Y109695I227J-329D01*
G02X1393169Y107717I-806J-1147D01*
G03X1392517Y107705I-322J-237D01*
G37*
G36*
G01X1452447Y110885D02*
G02X1451038Y110235I-215J-1385D01*
G03X1450758Y110840I-341J210D01*
G02X1452167Y111490I215J1385D01*
G03X1452447Y110885I341J-210D01*
G37*
G36*
G01X1512424Y120143D02*
G02X1515446Y120153I1511J0D01*
G01Y116258D01*
X1515437Y116174D01*
G02X1514779Y115089I-1502J169D01*
G03X1514753Y114445I224J-332D01*
G02X1513046Y114477I-874J-1096D01*
G03X1513044Y115122I-237J322D01*
G02X1512424Y116343I892J1221D01*
G01Y120143D01*
G37*
G36*
G01X1258565Y115056D02*
G02X1257135I-715J-1206D01*
G03Y115744I-204J344D01*
G02X1258565I715J1206D01*
G03Y115056I204J-344D01*
G37*
G36*
G01X619388Y115330D02*
G02X618655Y114188I666J-1234D01*
G03X618066Y114566I-399J26D01*
G02X618799Y115708I-666J1234D01*
G03X619388Y115330I399J-26D01*
G37*
G36*
G01X1286893Y117099D02*
G02X1285339I-777J-1167D01*
G03Y117765I-222J333D01*
G02X1286893I777J1167D01*
G03Y117099I222J-333D01*
G37*
G36*
G01X1398444Y117893D02*
G02X1397340Y117114I156J-1393D01*
G03X1396936Y117687I-360J175D01*
G02X1398040Y118466I-156J1393D01*
G03X1398444Y117893I360J-175D01*
G37*
G36*
G01X1554838Y121420D02*
G02X1554273Y122169I-1337J-421D01*
G03X1554545Y122454I111J167D01*
G02X1554398Y122705I1130J830D01*
G03X1553883Y122911I-364J-164D01*
G02X1554631Y124787I-530J1298D01*
G03X1555146Y124581I364J164D01*
G02X1556219Y124576I530J-1298D01*
G03X1556757Y124830I155J369D01*
G02X1557557Y123134I1343J-403D01*
G03X1557019Y122880I-155J-369D01*
G02X1555321Y121927I-1343J403D01*
G03X1554838Y121420I-102J-387D01*
G37*
G36*
G01X1928184Y121747D02*
G02X1926314Y122480I-1292J-544D01*
G03X1926518Y123000I-165J365D01*
G02X1926888Y124600I1292J544D01*
G03X1926912Y125180I-263J301D01*
G02X1927962Y127557I1006J976D01*
G03X1928366Y128041I13J400D01*
G02X1928815Y129394I1370J296D01*
G03X1928820Y129994I-262J302D01*
G02X1930677Y129980I936J1043D01*
G03X1930672Y129380I262J-302D01*
G02X1929692Y126936I-936J-1043D01*
G03X1929288Y126452I-13J-400D01*
G02X1928840Y125100I-1370J-296D01*
G03X1928816Y124520I263J-301D01*
G02X1928388Y122267I-1006J-976D01*
G03X1928184Y121747I165J-365D01*
G37*
G36*
G01X1401422Y122341D02*
G02X1399879Y122837I-1122J-841D01*
G03X1400078Y123459I-121J381D01*
G02X1399817Y124532I1122J841D01*
G03X1399418Y124998I-394J66D01*
G02X1400783Y126168I-18J1402D01*
G03X1401182Y125702I394J-66D01*
G02X1401621Y122963I18J-1402D01*
G03X1401422Y122341I121J-381D01*
G37*
G36*
G01X1392867Y122173D02*
G02X1390923Y124117I-1167J777D01*
G03Y124783I-222J333D01*
G02Y127117I777J1167D01*
G03Y127783I-222J333D01*
G02X1392867Y129727I777J1167D01*
G03X1393533I333J222D01*
G02X1395477Y127783I1167J-777D01*
G03Y127117I222J-333D01*
G02Y124783I-777J-1167D01*
G03Y124117I222J-333D01*
G02X1393533Y122173I-777J-1167D01*
G03X1392867I-333J-222D01*
G37*
G36*
G01X1525319Y122826D02*
G02X1524803Y124449I-1319J474D01*
G03X1525409Y124642I229J328D01*
G02X1525925Y123019I1319J-474D01*
G03X1525319Y122826I-229J-328D01*
G37*
G36*
G01X3938Y126754D02*
G03X5205Y127157I-2J2199D01*
G02X9264Y125823I1488J-2314D01*
G03X10004Y125805I374J143D01*
G02Y123881I2201J-962D01*
G03X9264Y123863I-366J-161D01*
G02X5221Y122519I-2571J980D01*
G03X3967Y122932I-1283J-1786D01*
G01X3936D01*
G03X2669Y122529I2J-2199D01*
G02X2653Y127167I-1488J2314D01*
G03X3907Y126754I1283J1786D01*
G01X3938D01*
G37*
G36*
G01X1864351Y125131D02*
G02X1864331Y123808I1226J-680D01*
G03X1863626Y123819I-355J-183D01*
G02X1863646Y125142I-1226J680D01*
G03X1864351Y125131I355J183D01*
G37*
G36*
G01X1857797Y127786D02*
G02X1856243I-777J-1167D01*
G03Y128452I-222J333D01*
G02X1857797I777J1167D01*
G03Y127786I222J-333D01*
G37*
G36*
G01X1513634Y127666D02*
G02X1513388Y125945I966J-1016D01*
G03X1512766Y126034I-346J-201D01*
G02X1513012Y127755I-966J1016D01*
G03X1513634Y127666I346J201D01*
G37*
G36*
G01X1473905Y130098D02*
G02X1472295I-805J-1148D01*
G03Y130752I-230J327D01*
G02X1473905I805J1148D01*
G03Y130098I230J-327D01*
G37*
G36*
G01X1861800Y131977D02*
G02X1860194Y131952I-785J-1162D01*
G03X1860184Y132607I-234J324D01*
G02X1859998Y134780I785J1162D01*
G03Y135358I-277J289D01*
G02X1861940I971J1011D01*
G03Y134780I277J-289D01*
G02X1861790Y132632I-971J-1011D01*
G03X1861800Y131977I234J-324D01*
G37*
G36*
G01X1531353Y133302D02*
G02X1530076Y134073I-1252J-631D01*
G03X1530426Y134653I-7J400D01*
G02X1530308Y135583I1252J631D01*
G03X1529813Y136054I-391J85D01*
G02X1530819Y137109I-364J1354D01*
G03X1531314Y136638I391J-85D01*
G02X1531703Y133882I364J-1354D01*
G03X1531353Y133302I7J-400D01*
G37*
G36*
G01X1324193Y132546D02*
G02Y134100I-1167J777D01*
G03X1324859I333J222D01*
G02Y132546I1167J-777D01*
G03X1324193I-333J-222D01*
G37*
G36*
G01X1262697Y134362D02*
G02X1262517Y132923I1101J-868D01*
G03X1261838Y133008I-365J-163D01*
G02X1262018Y134447I-1101J868D01*
G03X1262697Y134362I365J163D01*
G37*
G36*
G01X1590927Y135783D02*
G02X1588569Y134355I-1047J-932D01*
G03X1588067Y134592I-374J-142D01*
G02X1588931Y136417I-447J1329D01*
G03X1589433Y136180I374J142D01*
G02X1589549Y136213I441J-1331D01*
G03X1589753Y136868I-95J389D01*
G02X1591850Y138729I1047J932D01*
G03X1592450I300J265D01*
G02Y136871I1050J-929D01*
G03X1591850I-300J-265D01*
G02X1591131Y136438I-1050J929D01*
G03X1590927Y135783I95J-389D01*
G37*
G36*
G01X1568792Y137816D02*
G02X1567154Y137824I-825J-1134D01*
G03X1567157Y138473I-232J326D01*
G02X1568795Y138465I825J1134D01*
G03X1568792Y137816I232J-326D01*
G37*
G36*
G01X1513514Y139046D02*
G02X1513185Y137327I911J-1065D01*
G03X1512571Y137444I-354J-187D01*
G02X1512900Y139163I-911J1065D01*
G03X1513514Y139046I354J187D01*
G37*
G36*
G01X1952235Y142296D02*
G02X1950569Y141828I-535J-1296D01*
G03X1950399Y142434I-323J236D01*
G02X1952065Y142902I535J1296D01*
G03X1952235Y142296I323J-236D01*
G37*
G36*
G01X1240805Y142936D02*
G02X1239229Y142929I-783J-1163D01*
G03X1239227Y143591I-226J330D01*
G02X1240803Y143598I783J1163D01*
G03X1240805Y142936I226J-330D01*
G37*
G36*
G01X1822623Y142854D02*
G02X1822532Y144188I-1275J583D01*
G03X1823234Y144236I338J214D01*
G02X1823325Y142902I1275J-583D01*
G03X1822623Y142854I-338J-214D01*
G37*
G36*
G01X1937319Y144841D02*
G02X1935737Y145341I-1132J-828D01*
G03X1935922Y145968I-128J379D01*
G02X1935778Y146188I1180J929D01*
G03X1935109Y146242I-352J-190D01*
G02X1935210Y147808I-1109J858D01*
G03X1935880Y147776I345J202D01*
G02X1937528Y145460I1220J-876D01*
G03X1937319Y144841I114J-383D01*
G37*
G36*
G01X1542460Y150283D02*
G02X1540828Y150010I-629J-1253D01*
G03X1540722Y150647I-286J280D01*
G02X1542354Y150920I629J1253D01*
G03X1542460Y150283I286J-280D01*
G37*
G36*
G01X1715223Y148268D02*
G02Y149632I-1109J682D01*
G03X1715905I341J209D01*
G02Y148268I1109J-682D01*
G03X1715223I-341J-209D01*
G37*
G36*
G01X1914609Y148685D02*
G02X1914445Y150306I-1217J696D01*
G03X1915093Y150372I300J264D01*
G02X1917581Y150267I1217J-696D01*
G03X1918286Y150228I363J169D01*
G02X1918213Y148909I1198J-728D01*
G03X1917508Y148948I-363J-169D01*
G02X1915257Y148751I-1198J728D01*
G03X1914609Y148685I-300J-264D01*
G37*
G36*
G01X1578563Y150675D02*
G02X1577117Y150760I-793J-1156D01*
G03X1577157Y151444I-186J354D01*
G02X1576957Y153590I793J1156D01*
G03X1576901Y154201I-283J282D01*
G02X1578693Y154363I799J1152D01*
G03X1578749Y153752I283J-282D01*
G02X1578603Y151359I-799J-1152D01*
G03X1578563Y150675I186J-354D01*
G37*
G36*
G01X1829274Y151006D02*
G02X1827889Y151287I-933J-1046D01*
G03X1828026Y151964I-129J379D01*
G02X1829411Y151683I933J1046D01*
G03X1829274Y151006I129J-379D01*
G37*
G36*
G01X1906106Y151138D02*
G02X1904426Y151404I-1014J-968D01*
G03X1904526Y152032I-190J352D01*
G02X1906206Y151766I1014J968D01*
G03X1906106Y151138I190J-352D01*
G37*
G36*
G01X1493400Y154196D02*
G02X1491916Y153632I-331J-1362D01*
G03X1491682Y154248I-329J227D01*
G02X1493166Y154812I331J1362D01*
G03X1493400Y154196I329J-227D01*
G37*
G36*
G01X1263621Y155695D02*
G02X1263522Y154039I1079J-895D01*
G03X1262879Y154078I-336J-217D01*
G02X1262978Y155734I-1079J895D01*
G03X1263621Y155695I336J217D01*
G37*
G36*
G01X1808218Y163430D02*
G02X1806662I-778J-1400D01*
G03Y164130I-194J350D01*
G02Y166930I778J1400D01*
G03Y167630I-194J350D01*
G02X1808218I778J1400D01*
G03Y166930I194J-350D01*
G02Y164130I-778J-1400D01*
G03Y163430I194J-350D01*
G37*
G36*
G01X-14373Y161787D02*
G02X-14902Y163024I-1395J135D01*
G03X-14256Y163300I248J315D01*
G02X-13727Y162063I1395J-135D01*
G03X-14373Y161787I-248J-315D01*
G37*
G36*
G01X1455114Y164296D02*
G02X1453485Y164634I-1044J-936D01*
G03X1453616Y165264I-167J363D01*
G02X1455245Y164926I1044J936D01*
G03X1455114Y164296I167J-363D01*
G37*
G36*
G01X1929290Y171119D02*
G02X1929132Y169372I1010J-972D01*
G03X1928510Y169428I-333J-221D01*
G02X1928668Y171175I-1010J972D01*
G03X1929290Y171119I333J221D01*
G37*
G36*
G01X1452032Y171551D02*
G02X1450714Y171560I-667J-1233D01*
G03X1450719Y172266I-185J354D01*
G02X1450374Y174469I667J1233D01*
G03X1450369Y175027I-289J276D01*
G02X1450089Y176595I996J987D01*
G03X1449904Y177118I-364J165D01*
G02X1451808Y177791I628J1254D01*
G03X1451993Y177268I364J-165D01*
G02X1452377Y175044I-628J-1254D01*
G03X1452382Y174486I289J-276D01*
G02X1452037Y172257I-996J-987D01*
G03X1452032Y171551I185J-354D01*
G37*
G36*
G01X1675688Y171990D02*
G02X1675669Y173359I-1233J668D01*
G03X1676367Y173368I346J200D01*
G02X1676386Y171999I1233J-668D01*
G03X1675688Y171990I-346J-200D01*
G37*
G36*
G01X1929349Y174614D02*
G02X1927318Y176518I-1131J829D01*
G03X1927325Y177125I-257J307D01*
G02X1929149Y177104I924J1054D01*
G03X1929142Y176497I257J-307D01*
G02X1929302Y176332I-923J-1055D01*
G03X1929934Y176349I309J253D01*
G02X1930489Y176798I1130J-830D01*
G03X1930617Y177437I-164J365D01*
G02X1932215Y177118I1022J959D01*
G03X1932087Y176479I164J-365D01*
G02X1929981Y174631I-1022J-959D01*
G03X1929349Y174614I-309J-253D01*
G37*
G36*
G01X1720013Y177316D02*
G02X1718316Y177397I-913J-1316D01*
G03X1718371Y178058I-195J349D01*
G02X1720021Y177979I879J1092D01*
G03X1720013Y177316I220J-334D01*
G37*
G36*
G01X1752390Y178036D02*
X1757391D01*
G02X1758902Y176535I0J-1512D01*
G01Y176440D01*
X1758892Y176356D01*
G02X1757390Y175014I-1502J169D01*
G01X1752390D01*
G02X1751337Y175442I1J1511D01*
G03X1750706Y175345I-279J-287D01*
G02X1750451Y177213I-1411J759D01*
G03X1751086Y177288I289J276D01*
G02X1752390Y178036I1304J-763D01*
G37*
G36*
G01X1884675Y177325D02*
G02X1883084Y177255I-745J-1188D01*
G03X1883055Y177912I-242J318D01*
G02X1884957Y179892I745J1188D01*
G03X1885534Y179803I330J226D01*
G02X1885243Y177908I866J-1103D01*
G03X1884666Y177997I-330J-226D01*
G02X1884646Y177982I-851J1114D01*
G03X1884675Y177325I242J-318D01*
G37*
G36*
G01X63421Y177506D02*
G02X62786Y176279I766J-1174D01*
G03X62168Y176599I-400J-15D01*
G02X62803Y177826I-766J1174D01*
G03X63421Y177506I400J15D01*
G37*
G36*
G01X1489739Y177922D02*
G02X1488381Y177890I-650J-1242D01*
G03X1488364Y178590I-202J345D01*
G02X1489722Y178622I650J1242D01*
G03X1489739Y177922I202J-345D01*
G37*
G36*
G01X1227947Y178203D02*
G02X1226003Y180147I-1167J777D01*
G03Y180813I-222J333D01*
G02X1225919Y183086I777J1167D01*
G03X1225948Y183692I-246J315D01*
G02X1227775Y183602I966J1016D01*
G03X1227746Y182996I246J-315D01*
G02X1227947Y182757I-966J-1016D01*
G03X1228613I333J222D01*
G02X1230947I1167J-777D01*
G03X1231613I333J222D01*
G02X1233557Y180813I1167J-777D01*
G03Y180147I222J-333D01*
G02X1231613Y178203I-777J-1167D01*
G03X1230947I-333J-222D01*
G02X1228613I-1167J777D01*
G03X1227947I-333J-222D01*
G37*
G36*
G01X1597025Y179619D02*
G02Y180981I-1225J681D01*
G03X1597725I350J194D01*
G02Y179619I1225J-681D01*
G03X1597025I-350J-194D01*
G37*
G36*
G01X1855682Y182846D02*
G02X1854144Y182808I-740J-1191D01*
G03X1854128Y183476I-228J329D01*
G02X1855666Y183514I740J1191D01*
G03X1855682Y182846I228J-329D01*
G37*
G36*
G01X87704Y182904D02*
G02X86355Y182989I-752J-1183D01*
G03X86399Y183689I-170J362D01*
G02X87748Y183604I752J1183D01*
G03X87704Y182904I170J-362D01*
G37*
G36*
G01X767754Y183850D02*
G02X765216Y182837I-1386J-214D01*
G03X764664Y182940I-328J-229D01*
G02X762508Y184389I-783J1163D01*
G03X762239Y184851I-391J81D01*
G02X761777Y185103I428J1335D01*
G03X761242Y185079I-254J-309D01*
G02X759160Y186949I-984J999D01*
G03X759122Y187489I-313J249D01*
G02X759037Y187575I954J1028D01*
G03X758734Y187570I-149J-133D01*
G02X756760Y187384I-1080J894D01*
G03X756226Y187363I-255J-308D01*
G02X754226Y187408I-978J1005D01*
G03X753662Y187428I-292J-273D01*
G02X751706Y187475I-954J1027D01*
G03X751142Y187482I-286J-280D01*
G02X749159Y187515I-975J1008D01*
G03X748561Y187488I-287J-278D01*
G02X746453Y187402I-1092J880D01*
G03X745889Y187417I-290J-276D01*
G02X743856Y187534I-961J1021D01*
G03X743227Y187511I-305J-258D01*
G02X741097Y187344I-1136J822D01*
G03X740491Y187298I-283J-282D01*
G02X737962Y188013I-1132J827D01*
G03X737509Y188377I-399J-32D01*
G02X737404Y188367I-185J1389D01*
G03X737028Y187967I24J-399D01*
G02X734269Y187614I-1402J-2D01*
G03X733811Y187908I-387J-100D01*
G02X732641Y188233I-247J1380D01*
G03X732106Y188226I-264J-301D01*
G02X732078Y190311I-951J1030D01*
G03X732613Y190318I264J301D01*
G02X734921Y189639I951J-1030D01*
G03X735379Y189345I387J100D01*
G02X735541Y189364I244J-1380D01*
G03X735917Y189764I-24J399D01*
G02X736450Y190866I1402J2D01*
G03X736498Y191449I-248J314D01*
G02X738938Y192406I1038J943D01*
G03X739405Y192016I400J4D01*
G02X740525Y189546I236J-1382D01*
G03X740463Y188989I253J-310D01*
G02X740499Y188941I-1103J-865D01*
G03X740840Y188967I163J116D01*
G02X743163Y189237I1251J-634D01*
G03X743792Y189260I305J258D01*
G02X745944Y189404I1136J-822D01*
G03X746508Y189389I290J276D01*
G02X748477Y189343I961J-1021D01*
G03X749075Y189370I287J278D01*
G02X751169Y189470I1091J-880D01*
G03X751733Y189463I286J280D01*
G02X753730Y189415I975J-1008D01*
G03X754294Y189395I292J273D01*
G02X756142Y189448I954J-1027D01*
G03X756676Y189469I255J308D01*
G02X758581Y189516I978J-1005D01*
G03X759120Y189526I264J300D01*
G02X760987Y189580I964J-1018D01*
G03X761531Y189606I258J306D01*
G02X763513Y189628I1002J-980D01*
G03X764062Y189619I279J286D01*
G02X766074Y189493I945J-1036D01*
G03X766622Y189435I304J259D01*
G02X768495Y187360I854J-1112D01*
G03X768543Y186768I291J-274D01*
G02X768047Y184298I-851J-1114D01*
G03X767754Y183850I102J-387D01*
G37*
G36*
G01X1643138Y183981D02*
G02X1640433Y184087I-1338J419D01*
G03X1639869Y184358I-390J-89D01*
G02X1640658Y185686I-611J1262D01*
G03X1640976Y185534I200J10D01*
G02X1641128Y185630I823J-1135D01*
G03X1641274Y186196I-192J351D01*
G02X1643844Y187149I1183J752D01*
G03X1644283Y186809I396J58D01*
G02X1643722Y184206I150J-1394D01*
G03X1643138Y183981I-203J-345D01*
G37*
G36*
G01X1703257Y188180D02*
G02X1701704Y188154I-757J-1180D01*
G03X1701693Y188820I-227J329D01*
G02X1703246Y188846I757J1180D01*
G03X1703257Y188180I227J-329D01*
G37*
G36*
G01X1709077Y188435D02*
G02X1708544Y186943I823J-1135D01*
G03X1707923Y187165I-387J-102D01*
G02X1708456Y188657I-823J1135D01*
G03X1709077Y188435I387J102D01*
G37*
G36*
G01X726687Y189694D02*
G02X726618Y188021I1089J-883D01*
G03X725977Y188047I-330J-226D01*
G02X726046Y189720I-1089J883D01*
G03X726687Y189694I330J226D01*
G37*
G36*
G01X1945242Y191496D02*
G02X1943626Y191653I-942J-1296D01*
G03X1943713Y192323I-169J363D01*
G02X1945285Y192170I898J1077D01*
G03X1945242Y191496I192J-351D01*
G37*
G36*
G01X1264031Y192350D02*
G02X1261842Y190662I-951J-1030D01*
G03X1261189Y190740I-354J-187D01*
G02X1258828Y191177I-1049J930D01*
G03X1258177Y191325I-374J-141D01*
G02X1255826Y192116I-967J1015D01*
G03X1255404Y192451I-395J-64D01*
G02X1254628Y192625I-94J1399D01*
G03X1254099Y192497I-196J-349D01*
G02X1251543Y193067I-1169J773D01*
G03X1251134Y193409I-396J-58D01*
G02X1249691Y194909I-45J1401D01*
G03X1249354Y195333I-399J29D01*
G02X1248169Y196692I217J1385D01*
G03X1247777Y197084I-400J-8D01*
G02X1246401Y198520I26J1402D01*
G03X1246021Y198930I-400J11D01*
G02X1244688Y200354I69J1400D01*
G03X1244309Y200760I-400J7D01*
G02X1242987Y202316I71J1400D01*
G03X1242636Y202758I-398J45D01*
G02X1242119Y205375I164J1392D01*
G03X1242207Y206008I-194J350D01*
G02X1241812Y206781I990J993D01*
G03X1241202Y207056I-395J-63D01*
G02X1239442Y209213I-750J1184D01*
G03Y209767I-288J277D01*
G02Y211713I1010J973D01*
G03Y212267I-288J277D01*
G02Y214213I1010J973D01*
G03Y214767I-288J277D01*
G02X1239446Y216717I1010J973D01*
G03X1239457Y217263I-287J279D01*
G02X1241506Y217223I1043J937D01*
G03X1241495Y216677I287J-279D01*
G02X1241462Y214767I-1043J-937D01*
G03Y214213I288J-277D01*
G02Y212267I-1010J-973D01*
G03Y211713I288J-277D01*
G02Y209767I-1010J-973D01*
G03Y209213I288J-277D01*
G02X1241836Y208461I-1011J-972D01*
G03X1242446Y208186I395J63D01*
G02X1244589Y207161I750J-1184D01*
G03X1244992Y206807I397J46D01*
G02X1246416Y205371I22J-1402D01*
G03X1246772Y204964I400J-10D01*
G02X1248021Y203529I-152J-1394D01*
G03X1248392Y203118I400J-12D01*
G02X1248785Y203032I-100J-1398D01*
G03X1249304Y203272I142J374D01*
G02X1252027Y202824I1321J-468D01*
G03X1252405Y202430I400J5D01*
G02X1252469Y202425I-77J-1400D01*
G03X1252908Y202827I39J398D01*
G02X1255088Y204006I1402J13D01*
G03X1255643Y204117I222J333D01*
G02X1256982Y204731I1167J-777D01*
G03X1257426Y205064I49J397D01*
G02X1258739Y206240I1384J-224D01*
G03X1259117Y206684I-20J400D01*
G02X1260386Y208236I1393J156D01*
G03X1260734Y208747I-36J398D01*
G02X1262016Y210541I1346J393D01*
G03X1262382Y211052I-18J399D01*
G02X1265099Y211149I1346J392D01*
G03X1265481Y210665I391J-84D01*
G02X1266852Y209289I-31J-1402D01*
G03X1267244Y208897I400J8D01*
G02X1268620Y207521I-26J-1402D01*
G03X1269012Y207129I400J8D01*
G02X1270388Y205753I-26J-1402D01*
G03X1270780Y205361I400J8D01*
G02X1272156Y203985I-26J-1402D01*
G03X1272548Y203593I400J8D01*
G02X1272678Y200798I-26J-1402D01*
G03X1272325Y200360I45J-398D01*
G02X1270974Y198819I-1395J-140D01*
G03X1270602Y198309I13J-400D01*
G02X1269325Y196523I-1348J-386D01*
G03X1268947Y196079I20J-400D01*
G02X1267382Y194532I-1393J-156D01*
G03X1266941Y194218I-50J-397D01*
G02X1264803Y193336I-1371J292D01*
G03X1264242Y193208I-219J-335D01*
G02X1264022Y192929I-1202J722D01*
G03X1264031Y192350I280J-285D01*
G37*
G36*
G01X706309Y191605D02*
G02X705545Y192886I-1402J32D01*
G03X706127Y193233I182J356D01*
G02X707720Y194589I1402J-33D01*
G03X708135Y195158I54J396D01*
G02X710728Y196211I1264J605D01*
G03X711280Y195978I379J128D01*
G02X712356Y196035I606J-1264D01*
G03X712855Y196250I133J377D01*
G02X715433Y196217I1282J-568D01*
G03X715953Y195999I370J153D01*
G02X715184Y194165I527J-1299D01*
G03X714664Y194383I-370J-153D01*
G02X713667Y194361I-527J1299D01*
G03X713168Y194146I-133J-377D01*
G02X710558Y194266I-1282J568D01*
G03X710006Y194499I-379J-128D01*
G02X709209Y194374I-607J1264D01*
G03X708794Y193805I-54J-396D01*
G02X706891Y191952I-1265J-605D01*
G03X706309Y191605I-182J-356D01*
G37*
G36*
G01X698454Y194415D02*
G02X696900Y194323I-708J-1210D01*
G03X696860Y194987I-242J319D01*
G02X698414Y195079I708J1210D01*
G03X698454Y194415I242J-319D01*
G37*
G36*
G01X98575Y195729D02*
G02X97147Y195683I-675J-1229D01*
G03X97125Y196371I-214J337D01*
G02X97155Y198845I675J1229D01*
G03Y199555I-184J355D01*
G02X98445I645J1245D01*
G03Y198845I184J-355D01*
G02X98553Y196417I-645J-1245D01*
G03X98575Y195729I214J-337D01*
G37*
G36*
G01X1630836Y196158D02*
G02X1630732Y196162I2J1402D01*
G03X1630314Y195670I-29J-399D01*
G02X1629054Y196742I-1364J-326D01*
G03X1629472Y197234I29J399D01*
G02X1632121Y197000I1364J326D01*
G03X1632340Y196724I184J-79D01*
G02X1632363Y196727I193J-1387D01*
G03X1632691Y197196I-65J395D01*
G02X1634296Y196071I1378J258D01*
G03X1633968Y195602I65J-395D01*
G02X1631226Y195666I-1378J-258D01*
G03X1630837Y196158I-389J92D01*
G01X1630836D01*
G37*
G36*
G01X105535Y196906D02*
G02X104105I-715J-1206D01*
G03Y197594I-204J344D01*
G02X105535I715J1206D01*
G03Y196906I204J-344D01*
G37*
G36*
G01X1731771Y195558D02*
G02X1731397Y196835I-1371J292D01*
G03X1732076Y197045I285J281D01*
G02X1733563Y198288I1487J-268D01*
G01X1738564D01*
G02X1740074Y196786I-1J-1512D01*
G01Y196691D01*
X1740065Y196607D01*
G02X1738563Y195264I-1502J168D01*
G01X1733563D01*
G02X1732456Y195747I1J1512D01*
G03X1731771Y195558I-294J-272D01*
G37*
G36*
G01X607489Y199401D02*
G02X605767Y199172I-716J-1205D01*
G03X605684Y199795I-287J279D01*
G02X605006Y201146I716J1205D01*
G03X604573Y201586I-398J41D01*
G02X605847Y202837I-120J1397D01*
G03X606280Y202397I398J-41D01*
G02X607406Y200024I120J-1397D01*
G03X607489Y199401I287J-279D01*
G37*
G36*
G01X799325Y200502D02*
G02X798088Y199804I-24J-1402D01*
G03X797737Y200405I-346J201D01*
G02X798992Y201113I-20J1502D01*
G03X799325Y200502I340J-211D01*
G37*
G36*
G01X1894193Y200047D02*
G02X1893186Y201414I-1402J22D01*
G03X1893698Y201792I112J384D01*
G02X1894569Y203068I1402J-22D01*
G03X1894683Y203737I-152J370D01*
G02X1896145Y203487I932J1048D01*
G03X1896031Y202818I152J-370D01*
G02X1894705Y200425I-931J-1048D01*
G03X1894193Y200047I-112J-384D01*
G37*
G36*
G01X579220Y203377D02*
G02X578123Y202280I277J-1374D01*
G03X577652Y202751I-392J79D01*
G02X578749Y203848I-277J1374D01*
G03X579220Y203377I392J-79D01*
G37*
G36*
G01X1403833Y206100D02*
G02X1402555Y205885I-433J-1334D01*
G03X1402437Y206584I-241J319D01*
G02X1403715Y206799I433J1334D01*
G03X1403833Y206100I241J-319D01*
G37*
G36*
G01X562584Y206877D02*
G02X561487Y205780I277J-1374D01*
G03X561016Y206251I-392J79D01*
G02X562113Y207348I-277J1374D01*
G03X562584Y206877I392J-79D01*
G37*
G36*
G01X1955487Y214076D02*
G03X1955651Y214607I-193J350D01*
G02X1956220Y216466I1250J634D01*
G03Y217166I-194J350D01*
G02X1957582I681J1225D01*
G03Y216466I194J-350D01*
G02X1958147Y214599I-681J-1225D01*
G03X1958308Y214067I356J-183D01*
G02X1959541Y212715I-1418J-2532D01*
G03X1960200Y212606I365J163D01*
G02X1959928Y209839I1690J-1563D01*
G03X1959260Y209861I-341J-209D01*
G02X1957697Y208747I-2371J1673D01*
G01X1957552Y208706D01*
Y204492D01*
X1946598D01*
Y213346D01*
X1954623D01*
G02X1955487Y214076I2269J-1809D01*
G37*
G36*
G01X1330337Y207982D02*
G02X1330256Y209998I-1013J969D01*
G03X1330811Y210020I266J299D01*
G02X1332952Y209883I1013J-969D01*
G03X1333596I322J238D01*
G02Y208219I1128J-832D01*
G03X1332952I-322J-238D01*
G02X1330892Y208004I-1128J832D01*
G03X1330337Y207982I-266J-299D01*
G37*
G36*
G01X1884653Y211688D02*
G02X1882947I-853J-1113D01*
G03Y212323I-243J317D01*
G02X1885092Y213981I853J1113D01*
G03X1885791Y213912I368J155D01*
G02X1885660Y212580I1161J-787D01*
G03X1884961Y212649I-368J-155D01*
G02X1884653Y212323I-1160J788D01*
G03Y211688I243J-318D01*
G37*
G36*
G01X565773Y212929D02*
G02X564656Y211694I278J-1374D01*
G03X564178Y212126I-398J40D01*
G02X565295Y213361I-278J1374D01*
G03X565773Y212929I398J-40D01*
G37*
G36*
G01X174485Y210977D02*
G02X172328Y213045I-1185J923D01*
G03Y213655I-259J305D01*
G02Y215945I972J1145D01*
G03Y216555I-259J305D01*
G02X174603Y218448I972J1145D01*
G03X175233Y218366I346J199D01*
G02X177779Y217570I1067J-1058D01*
G03X178410Y217318I394J70D01*
G02X180485Y217031I890J-1210D01*
G03X181115I315J246D01*
G02Y215185I1185J-923D01*
G03X180485I-315J-246D01*
G02X180272Y214963I-1185J923D01*
G03Y214353I259J-305D01*
G02X178421Y211990I-972J-1145D01*
G03X177791Y211715I-233J-325D01*
G02X175115Y210977I-1491J185D01*
G03X174485I-315J-246D01*
G37*
G36*
G01X1848935Y212284D02*
G02Y213608I-1236J662D01*
G03X1849640I353J189D01*
G02Y212284I1236J-662D01*
G03X1848935I-352J-189D01*
G37*
G36*
G01X116300Y214684D02*
G02X114751Y214669I-763J-1176D01*
G03X114744Y215336I-224J331D01*
G02X116293Y215351I763J1176D01*
G03X116300Y214684I224J-331D01*
G37*
G36*
G01X765908D02*
G02X764359Y214669I-763J-1176D01*
G03X764352Y215336I-224J331D01*
G02X765901Y215351I763J1176D01*
G03X765908Y214684I224J-331D01*
G37*
G36*
G01X1220270Y214898D02*
G02X1218893Y216271I-1402J-29D01*
G03X1219300Y216679I7J400D01*
G02X1219317Y216923I1402J25D01*
G03X1218979Y217097I-198J31D01*
G02X1219396Y218228I-979J1003D01*
G03X1219996Y217919I398J37D01*
G02X1220677Y215306I706J-1211D01*
G03X1220270Y214898I-7J-400D01*
G37*
G36*
G01X1331241Y215723D02*
G02Y217277I-1167J777D01*
G03X1331907I333J222D01*
G02X1334241I1167J-777D01*
G03X1334907I333J222D01*
G02Y215723I1167J-777D01*
G03X1334241I-333J-222D01*
G02X1331907I-1167J777D01*
G03X1331241I-333J-222D01*
G37*
G36*
G01X580354Y218161D02*
G02X579257Y219258I-1374J-277D01*
G03X579728Y219729I79J392D01*
G02X580825Y218632I1374J277D01*
G03X580354Y218161I-79J-392D01*
G37*
G36*
G01X743908Y222185D02*
G02X741579Y220827I-971J-1011D01*
G03X741024Y221091I-388J-99D01*
G02X739426Y221393I-587J1273D01*
G03X738848I-289J-277D01*
G02X736866Y223375I-1011J971D01*
G03Y223953I-277J289D01*
G02X738848Y225935I971J1011D01*
G03X739426I289J277D01*
G02X739696Y226154I1011J-971D01*
G03X739665Y226850I-212J339D01*
G02X741685Y228317I635J1250D01*
G03X742262Y228023I395J62D01*
G02X743690Y225617I635J-1250D01*
G03X743699Y224951I226J-330D01*
G02X743908Y222763I-762J-1177D01*
G03Y222185I277J-289D01*
G37*
G36*
G01X642696Y222427D02*
G02X640504I-1096J-1027D01*
G03Y222973I-292J273D01*
G02Y225027I1096J1027D01*
G03Y225573I-292J273D01*
G02Y227627I1096J1027D01*
G03Y228173I-292J273D01*
G02Y230227I1096J1027D01*
G03Y230773I-292J273D01*
G02X642745Y232772I1096J1027D01*
G03X643355I305J259D01*
G02X645724Y232670I1145J-972D01*
G03X646376I326J232D01*
G02X648824I1224J-870D01*
G03X649476I326J232D01*
G02X651796Y230773I1225J-869D01*
G03Y230227I292J-273D01*
G02Y228173I-1096J-1027D01*
G03Y227627I292J-273D01*
G02X652171Y226905I-1096J-1027D01*
G03X652812Y226673I392J81D01*
G02X652843Y224303I938J-1173D01*
G03X652202Y223987I-241J-319D01*
G02X649476Y223130I-1502J13D01*
G03X648824I-326J-232D01*
G02X646376I-1224J870D01*
G03X645724I-326J-232D01*
G02X643355Y223028I-1224J870D01*
G03X642745I-305J-259D01*
G02X642696Y222973I-1146J971D01*
G03Y222427I292J-273D01*
G37*
G36*
G01X1903999Y226780D02*
G02X1902051Y226789I-979J-1004D01*
G03X1902053Y227364I-277J288D01*
G02X1902167Y229471I979J1004D01*
G03X1902139Y230121I-247J315D01*
G02X1903772Y230191I768J1173D01*
G03X1903800Y229541I247J-315D01*
G02X1904001Y227355I-768J-1173D01*
G03X1903999Y226780I277J-288D01*
G37*
G36*
G01X1398440Y226716D02*
G02X1395924Y225485I-1229J-675D01*
G03X1395407Y225697I-367J-159D01*
G02X1396168Y227553I-526J1300D01*
G03X1396685Y227341I367J159D01*
G02X1397063Y227435I524J-1300D01*
G03X1397371Y228025I-43J398D01*
G02X1399574Y229708I1229J675D01*
G03X1400233Y229871I279J287D01*
G02X1400591Y228427I1332J-436D01*
G03X1399932Y228264I-279J-287D01*
G02X1398748Y227306I-1332J436D01*
G03X1398440Y226716I43J-398D01*
G37*
G36*
G01X602200Y227570D02*
G02X602143Y225908I1100J-870D01*
G03X601500Y225930I-330J-226D01*
G02X601557Y227592I-1100J870D01*
G03X602200Y227570I330J226D01*
G37*
G36*
G01X1279850Y230736D02*
G02X1278675Y229922I99J-1398D01*
G03X1278283Y230488I-363J167D01*
G02X1276858Y232344I-100J1398D01*
G03X1276513Y232873I-378J130D01*
G02X1275240Y234465I115J1397D01*
G03X1274912Y234915I-396J56D01*
G02X1276542Y236101I242J1381D01*
G03X1276870Y235651I396J-56D01*
G02X1277953Y233812I-242J-1381D01*
G03X1278298Y233283I378J-130D01*
G02X1279458Y231302I-115J-1397D01*
G03X1279850Y230736I363J-167D01*
G37*
G36*
G01X1967564Y228788D02*
G02Y230412I-1264J812D01*
G03X1968236I336J216D01*
G02Y228788I1264J-812D01*
G03X1967564I-336J-216D01*
G37*
G36*
G01X1398802Y232142D02*
G02X1398004Y233383I-1402J-24D01*
G03X1398576Y233751I172J361D01*
G02X1399003Y234783I1402J24D01*
G03X1399023Y235337I-278J287D01*
G02X1398664Y236309I1043J937D01*
G03X1398073Y236670I-400J10D01*
G02X1398802Y237865I-673J1230D01*
G03X1399393Y237504I400J-10D01*
G02X1401041Y235266I674J-1230D01*
G03X1401021Y234712I278J-287D01*
G02X1399374Y232510I-1043J-937D01*
G03X1398802Y232142I-172J-361D01*
G37*
G36*
G01X1837228Y234063D02*
G02X1835822Y233596I-328J-1363D01*
G03X1835608Y234241I-307J256D01*
G02X1837014Y234708I328J1363D01*
G03X1837228Y234063I307J-256D01*
G37*
G36*
G01X1735168Y232256D02*
G02X1734900Y233771I-1288J553D01*
G03X1735559Y233888I291J274D01*
G02X1738014Y234111I1288J-554D01*
G03X1738680I333J222D01*
G02X1740447Y234601I1167J-777D01*
G03X1741013Y234900I171J362D01*
G02X1741191Y235395I1385J-219D01*
G03X1741020Y235959I-344J204D01*
G02X1740644Y236215I648J1355D01*
G03X1740093Y236209I-272J-293D01*
G02X1737939Y236267I-1049J1075D01*
G03X1737368Y236286I-295J-270D01*
G02X1735427Y236290I-968J1014D01*
G03X1734873I-277J-288D01*
G02Y238310I-973J1010D01*
G03X1735427I277J288D01*
G02X1737380Y238302I972J-1010D01*
G03X1737951Y238314I280J286D01*
G02X1740068Y238383I1093J-1030D01*
G03X1740619Y238389I272J293D01*
G02X1742718Y238388I1049J-1075D01*
G03X1743273Y238384I280J286D01*
G02X1745454Y238266I1035J-1089D01*
G03X1746068Y238270I305J258D01*
G02X1746081Y236343I1159J-956D01*
G03X1745467Y236339I-305J-258D01*
G02X1744101Y235807I-1159J956D01*
G03X1743680Y235249I-56J-396D01*
G02X1741798Y233414I-1282J-568D01*
G03X1741232Y233115I-171J-362D01*
G02X1738680Y232557I-1385J219D01*
G03X1738014I-333J-222D01*
G02X1735827Y232373I-1167J777D01*
G03X1735168Y232256I-291J-274D01*
G37*
G36*
G01X123238Y235830D02*
G02X121540Y236050I-1008J-1114D01*
G03X121625Y236702I-183J355D01*
G02X123790Y238773I1007J1114D01*
G03X124406I308J255D01*
G02Y236859I1158J-957D01*
G03X123790I-308J-255D01*
G02X123323Y236482I-1158J957D01*
G03X123238Y235830I183J-355D01*
G37*
G36*
G01X1608415Y241546D02*
G02X1607183Y242777I-1566J-336D01*
G03X1607662Y243223I83J391D01*
G02X1608861Y242026I1389J192D01*
G03X1608415Y241546I-55J-396D01*
G37*
G36*
G01X1667018Y243217D02*
G02X1665659Y243210I-673J-1230D01*
G03X1665656Y243909I-196J349D01*
G02X1667015Y243916I673J1230D01*
G03X1667018Y243217I196J-349D01*
G37*
G36*
G01X1682647Y243237D02*
G02X1682508Y241656I1082J-892D01*
G03X1681851Y241714I-348J-196D01*
G02X1680454Y243971I-1082J891D01*
G03X1680674Y244614I-90J390D01*
G02X1682786Y246455I1086J886D01*
G03X1683397Y246484I293J272D01*
G02X1683483Y244676I1112J-853D01*
G03X1682872Y244647I-293J-272D01*
G02X1682075Y244134I-1113J853D01*
G03X1681855Y243491I90J-390D01*
G02X1681990Y243295I-1083J-890D01*
G03X1682647Y243237I348J196D01*
G37*
G36*
G01X128755Y242876D02*
G02X128442Y244539I-1255J625D01*
G03X129069Y244657I269J296D01*
G02X129382Y242994I1255J-625D01*
G03X128755Y242876I-269J-296D01*
G37*
G36*
G01X778282Y242932D02*
G02X778000Y244483I-1282J568D01*
G03X778650Y244601I285J281D01*
G02X778932Y243050I1282J-568D01*
G03X778282Y242932I-285J-281D01*
G37*
G36*
G01X1437365Y245552D02*
G02X1436078Y244616I35J-1402D01*
G03X1435690Y245148I-377J132D01*
G02X1436977Y246084I-35J1402D01*
G03X1437365Y245552I377J-132D01*
G37*
G36*
G01X116289Y246548D02*
G02X114740Y246533I-763J-1176D01*
G03X114733Y247200I-224J331D01*
G02X116282Y247215I763J1176D01*
G03X116289Y246548I224J-331D01*
G37*
G36*
G01X765908Y246684D02*
G02X764359Y246669I-763J-1176D01*
G03X764352Y247336I-224J331D01*
G02X765901Y247351I763J1176D01*
G03X765908Y246684I224J-331D01*
G37*
G36*
G01X849467Y245504D02*
G02X847186Y247454I-1185J923D01*
G03Y248000I-292J273D01*
G02X847224Y250093I1096J1027D01*
G03Y250661I-282J284D01*
G02X846884Y251179I1059J1065D01*
G03X846204Y251289I-373J-146D01*
G02X846448Y252798I-1154J961D01*
G03X847128Y252688I373J146D01*
G02X847186Y252754I1157J-958D01*
G03Y253300I-292J273D01*
G02X849467Y255250I1096J1027D01*
G03X850097I315J246D01*
G02X852467I1185J-923D01*
G03X853097I315J246D01*
G02X855467I1185J-923D01*
G03X856097I315J246D01*
G02X858378Y253300I1185J-923D01*
G03Y252754I292J-273D01*
G02X858340Y250661I-1096J-1027D01*
G03Y250093I282J-284D01*
G02X858378Y248000I-1058J-1066D01*
G03Y247454I292J-273D01*
G02X856097Y245504I-1096J-1027D01*
G03X855467I-315J-246D01*
G02X853097I-1185J923D01*
G03X852467I-315J-246D01*
G02X850097I-1185J923D01*
G03X849467I-315J-246D01*
G37*
G36*
G01X199345Y245528D02*
G02X197277Y247685I-1145J972D01*
G03Y248315I-246J315D01*
G02Y250685I923J1185D01*
G03Y251315I-246J315D01*
G02X197111Y251466I925J1183D01*
G03X196459Y251360I-290J-276D01*
G02X196189Y253034I-1359J640D01*
G03X196841Y253140I290J276D01*
G02X199385Y253423I1359J-640D01*
G03X200015I315J246D01*
G02X202385I1185J-923D01*
G03X203015I315J246D01*
G02X205385I1185J-923D01*
G03X206015I315J246D01*
G02X208123Y251315I1185J-923D01*
G03Y250685I246J-315D01*
G02X207871Y248156I-923J-1185D01*
G03X207772Y247510I179J-358D01*
G02X205722Y245604I-972J-1010D01*
G03X205096Y245591I-308J-255D01*
G02X202794Y245483I-1196J909D01*
G03X202206I-294J-270D01*
G02X199955Y245528I-1106J1017D01*
G03X199345I-305J-259D01*
G37*
G36*
G01X1663900Y249338D02*
G02X1662940Y248226I424J-1336D01*
G03X1662424Y248672I-395J65D01*
G02X1663384Y249784I-424J1336D01*
G03X1663900Y249338I395J-65D01*
G37*
G36*
G01X718606Y249173D02*
G02X718591Y250691I-1186J747D01*
G03X719264Y250697I335J219D01*
G02X721584Y250774I1186J-747D01*
G03X722239Y250786I323J236D01*
G02X724545Y250809I1161J-786D01*
G03X725195Y250805I326J231D01*
G02X725183Y249170I1133J-826D01*
G03X724533Y249174I-326J-231D01*
G02X722266Y249176I-1133J826D01*
G03X721611Y249164I-323J-236D01*
G02X719279Y249179I-1161J786D01*
G03X718606Y249173I-335J-219D01*
G37*
G36*
G01X658864Y249391D02*
G02X658783Y251062I-1164J781D01*
G03X659424Y251093I309J254D01*
G02X659505Y249422I1164J-781D01*
G03X658864Y249391I-309J-254D01*
G37*
G36*
G01X1500777Y249858D02*
G02X1500262Y251528I-1305J512D01*
G03X1500860Y251712I226J330D01*
G02X1501375Y250042I1305J-512D01*
G03X1500777Y249858I-226J-330D01*
G37*
G36*
G01X1588322Y250980D02*
G02X1587633Y252491I-1372J287D01*
G03X1588220Y252759I195J349D01*
G02X1588909Y251248I1372J-287D01*
G03X1588322Y250980I-195J-349D01*
G37*
G36*
G01X1440096Y254445D02*
G02X1438370Y253545I-396J-1345D01*
G03X1438104Y254055I-379J127D01*
G02X1437463Y256344I396J1345D01*
G03X1437308Y256987I-296J269D01*
G02X1438837Y257356I492J1313D01*
G03X1438992Y256713I296J-269D01*
G02X1439830Y254955I-492J-1313D01*
G03X1440096Y254445I379J-127D01*
G37*
G36*
G01X1859705Y253139D02*
G02X1859613Y254436I-1285J561D01*
G03X1860320Y254486I340J210D01*
G02X1862690Y254813I1285J-561D01*
G03X1863289Y254791I309J254D01*
G02X1863220Y252937I1016J-966D01*
G03X1862621Y252959I-309J-254D01*
G02X1860412Y253189I-1016J966D01*
G03X1859705Y253139I-340J-210D01*
G37*
G36*
G01X749809Y253142D02*
G02X749663Y255019I-1109J858D01*
G03X750254Y255065I275J291D01*
G02X752491Y255039I1109J-858D01*
G03X753135I322J238D01*
G02Y253375I1128J-832D01*
G03X752491I-322J-238D01*
G02X750400Y253188I-1128J832D01*
G03X749809Y253142I-275J-291D01*
G37*
G36*
G01X1671347Y255991D02*
G02X1669766Y255613I-525J-1300D01*
G03X1669615Y256247I-301J263D01*
G02X1669027Y256694I525J1300D01*
G03X1668478Y256777I-318J-243D01*
G02X1666532Y258743I-811J1144D01*
G03X1666377Y259340I-324J234D01*
G02X1668103Y259788I591J1271D01*
G03X1668258Y259191I324J-234D01*
G02X1668780Y258773I-590J-1272D01*
G03X1669329Y258690I318J243D01*
G02X1671196Y256625I810J-1144D01*
G03X1671347Y255991I301J-263D01*
G37*
G36*
G01X1621068Y255879D02*
G02X1619424Y255874I-819J-1138D01*
G03X1619422Y256522I-236J323D01*
G02X1621066Y256527I819J1138D01*
G03X1621068Y255879I236J-323D01*
G37*
G36*
G01X1309929Y256611D02*
G02X1309831Y254805I1021J-961D01*
G03X1309221Y254839I-319J-241D01*
G02X1306892Y256305I-1021J961D01*
G03X1306534Y256849I-373J144D01*
G02X1307893Y257745I51J1401D01*
G03X1308251Y257201I373J-144D01*
G02X1309319Y256645I-51J-1401D01*
G03X1309929Y256611I319J241D01*
G37*
G36*
G01X1592584Y258161D02*
G02X1590540Y255962I-985J-1133D01*
G03X1589993Y255978I-282J-284D01*
G02X1587974Y256006I-994J1126D01*
G03X1587428Y256005I-272J-293D01*
G02X1585060Y256418I-1029J1094D01*
G03X1584355Y256433I-357J-181D01*
G02X1582112Y258346I-1308J738D01*
G03X1582118Y258967I-249J313D01*
G02X1584464Y260702I960J1155D01*
G03X1585168Y260639I369J155D01*
G02X1587464Y260914I1262J-815D01*
G03X1588011Y260910I276J290D01*
G02X1590007Y260948I1019J-1103D01*
G03X1590553Y260973I260J304D01*
G02X1592590Y258770I1074J-1050D01*
G03X1592584Y258161I256J-307D01*
G37*
G36*
G01X1884646Y261214D02*
G02X1882480Y259185I-924J-1185D01*
G03X1881830Y259202I-331J-224D01*
G02X1879710Y261294I-1197J907D01*
G03Y261924I-246J315D01*
G02X1881876Y263953I924J1185D01*
G03X1882526Y263936I331J224D01*
G02X1884646Y261844I1197J-907D01*
G03Y261214I246J-315D01*
G37*
G36*
G01X643632Y262228D02*
G02X641968I-832J-1128D01*
G03Y262872I-238J322D01*
G02X642408Y265346I832J1128D01*
G03X642583Y266008I-112J384D01*
G02X642443Y267787I1008J974D01*
G03X642279Y268382I-328J230D01*
G02X644003Y268856I576J1278D01*
G03X644167Y268261I328J-230D01*
G02X643983Y265637I-576J-1278D01*
G03X643808Y264975I112J-384D01*
G02X643632Y262872I-1008J-975D01*
G03Y262228I238J-322D01*
G37*
G36*
G01X445821Y262562D02*
G02X444136Y262342I-698J-1216D01*
G03X444054Y262972I-282J284D01*
G02X443931Y265325I698J1216D01*
G03X443855Y266017I-234J325D01*
G02X445229Y266168I554J1288D01*
G03X445305Y265476I234J-325D01*
G02X445739Y263192I-553J-1288D01*
G03X445821Y262562I282J-284D01*
G37*
G36*
G01X1087133Y263352D02*
G02X1084941Y263301I-1072J-1052D01*
G03X1084928Y263848I-298J267D01*
G02X1087371Y265514I1072J1052D01*
G03X1088039Y265416I365J163D01*
G02X1088053Y265432I1062J-915D01*
G03X1088031Y265987I-299J266D01*
G02X1090047Y266068I969J1013D01*
G03X1090069Y265513I299J-266D01*
G02X1090267Y265277I-969J-1014D01*
G03X1090933I333J222D01*
G02X1091255Y265619I1167J-777D01*
G03X1091299Y266218I-241J319D01*
G02X1093145Y266081I1001J982D01*
G03X1093101Y265482I241J-319D01*
G02X1090933Y263723I-1001J-982D01*
G03X1090267I-333J-222D01*
G02X1087841Y263883I-1167J777D01*
G03X1087170Y263958I-359J-176D01*
G02X1087120Y263899I-1171J941D01*
G03X1087133Y263352I298J-267D01*
G37*
G36*
G01X440857Y264577D02*
G02X439243Y265001I-1093J-878D01*
G03X439407Y265622I-148J371D01*
G02X441021Y265198I1093J878D01*
G03X440857Y264577I148J-371D01*
G37*
G36*
G01X451230Y266487D02*
G02X450517Y264930I653J-1241D01*
G03X449941Y265194I-390J-90D01*
G02X450654Y266751I-653J1241D01*
G03X451230Y266487I390J90D01*
G37*
G36*
G01X1096538Y267024D02*
G02X1094862I-838J-1124D01*
G03Y267666I-239J321D01*
G02X1096538I838J1124D01*
G03Y267024I239J-321D01*
G37*
G36*
G01X123208Y267857D02*
G02X121491Y268023I-977J-1141D01*
G03X121554Y268675I-197J348D01*
G02X123689Y270773I978J1140D01*
G03X124305I308J255D01*
G02Y268859I1158J-957D01*
G03X123689I-308J-255D01*
G02X123271Y268509I-1157J958D01*
G03X123208Y267857I197J-348D01*
G37*
G36*
G01X186837Y269010D02*
G02X184675Y271095I-1069J1055D01*
G03X184672Y271647I-291J274D01*
G02X184782Y273834I1082J1042D01*
G03X184778Y274447I-259J305D01*
G02X184629Y274587I952J1162D01*
G03X184041I-294J-270D01*
G02X181820Y274597I-1106J1017D01*
G03X181169Y274513I-296J-268D01*
G02X178650Y274281I-1334J691D01*
G03X178020I-315J-246D01*
G02X175650I-1185J923D01*
G03X175020I-315J-246D01*
G02X172739Y276231I-1185J923D01*
G03Y276777I-292J273D01*
G02X175020Y278727I1096J1027D01*
G03X175650I315J246D01*
G02X178020I1185J-923D01*
G03X178650I315J246D01*
G02X180950Y278811I1185J-923D01*
G03X181601Y278895I296J268D01*
G02X184041Y279221I1334J-691D01*
G03X184629I294J270D01*
G02X186833Y279229I1106J-1017D01*
G03X187436Y279249I293J273D01*
G02X189669Y279355I1164J-949D01*
G03X190258Y279376I285J281D01*
G02X190331Y277345I1142J-976D01*
G03X189742Y277324I-285J-281D01*
G02X189633Y277210I-1139J980D01*
G03X189620Y276643I276J-290D01*
G02X189479Y274436I-1085J-1039D01*
G03X189474Y273818I251J-311D01*
G02X189592Y271624I-964J-1152D01*
G03X189585Y271077I288J-277D01*
G02X187406Y269010I-1110J-1012D01*
G03X186837I-285J-281D01*
G37*
G36*
G01X653393Y271818D02*
G02X651851Y271716I-694J-1218D01*
G03X651807Y272382I-242J318D01*
G02X653349Y272484I694J1218D01*
G03X653393Y271818I242J-318D01*
G37*
G36*
G01X710700Y273831D02*
G02X709004Y273683I-751J-1184D01*
G03X708949Y274316I-269J295D01*
G02X708692Y276474I751J1184D01*
G03X708670Y277051I-288J278D01*
G02X708511Y277217I930J1049D01*
G03X707889I-311J-252D01*
G02Y278983I-1089J883D01*
G03X708511I311J252D01*
G02X710608Y277126I1090J-882D01*
G03X710630Y276549I288J-278D01*
G02X710645Y274464I-930J-1049D01*
G03X710700Y273831I269J-295D01*
G37*
G36*
G01X1624564Y272426D02*
G02X1624542Y274148I-1117J847D01*
G03X1625174Y274156I313J249D01*
G02X1625196Y272434I1117J-847D01*
G03X1624564Y272426I-313J-249D01*
G37*
G36*
G01X755577Y274494D02*
G02X754007Y274540I-819J-1138D01*
G03X754027Y275202I-214J338D01*
G02X755597Y275156I819J1138D01*
G03X755577Y274494I214J-338D01*
G37*
G36*
G01X202032Y274010D02*
G02X199964Y276148I-1185J923D01*
G03X199985Y276779I-235J324D01*
G02X199794Y276970I962J1153D01*
G03X199192Y276983I-307J-257D01*
G02X197199Y279210I-1110J1012D01*
G03X197220Y279841I-235J324D01*
G02X199297Y282001I962J1154D01*
G03X199878Y281988I297J268D01*
G02X202180Y281790I1069J-1055D01*
G03X202828Y281778I328J229D01*
G02X204792Y279814I1119J-845D01*
G03X204804Y279166I241J-320D01*
G02X204830Y276718I-857J-1233D01*
G03X204809Y276087I235J-324D01*
G02X202662Y274010I-962J-1153D01*
G03X202032I-315J-246D01*
G37*
G36*
G01X128755Y274876D02*
G02X128442Y276539I-1255J625D01*
G03X129069Y276657I269J296D01*
G02X129382Y274994I1255J-625D01*
G03X128755Y274876I-269J-296D01*
G37*
G36*
G01X116300Y278684D02*
G02X114751Y278669I-763J-1176D01*
G03X114744Y279336I-224J331D01*
G02X116293Y279351I763J1176D01*
G03X116300Y278684I224J-331D01*
G37*
G36*
G01X765908D02*
G02X764359Y278669I-763J-1176D01*
G03X764352Y279336I-224J331D01*
G02X765901Y279351I763J1176D01*
G03X765908Y278684I224J-331D01*
G37*
G36*
G01X750187Y280386D02*
G02X748558Y280793I-1087J-886D01*
G03X748713Y281414I-155J369D01*
G02X750342Y281007I1087J886D01*
G03X750187Y280386I155J-369D01*
G37*
G36*
G01X690825Y282220D02*
G02X689271I-777J-1167D01*
G03Y282886I-222J333D01*
G02X690825I777J1167D01*
G03Y282220I222J-333D01*
G37*
G36*
G01X1495494Y282261D02*
G02X1495450Y280598I1106J-861D01*
G03X1494806Y280615I-328J-229D01*
G02X1494850Y282278I-1106J861D01*
G03X1495494Y282261I328J229D01*
G37*
G36*
G01X1405610Y282190D02*
G02X1402952Y282162I-1324J-461D01*
G03X1402465Y282671I-380J124D01*
G02X1403191Y283152I-373J1351D01*
G03X1403465Y282866I157J-124D01*
G02X1403822Y283052I820J-1138D01*
G03X1404068Y283561I-132J378D01*
G02X1405856Y282699I1324J461D01*
G03X1405610Y282190I132J-378D01*
G37*
G36*
G01X684678Y281366D02*
G02X684620Y282940I-1188J744D01*
G03X685282Y282964I323J236D01*
G02X685340Y281390I1188J-744D01*
G03X684678Y281366I-323J-236D01*
G37*
G36*
G01X59894Y282265D02*
G02X59782Y283892I-1194J735D01*
G03X60431Y283936I309J254D01*
G02X60965Y284438I1194J-735D01*
G03X61026Y285104I-188J353D01*
G02X62560Y284963I874J1096D01*
G03X62499Y284297I188J-353D01*
G02X60543Y282309I-874J-1096D01*
G03X59894Y282265I-309J-254D01*
G37*
G36*
G01X766364Y284716D02*
G02X765442Y285696I-1357J-353D01*
G03X765953Y286177I124J380D01*
G02X765923Y286323I1357J355D01*
G03X765406Y286644I-395J-60D01*
G02X766367Y288187I-426J1336D01*
G03X766884Y287866I395J60D01*
G02X766875Y285197I426J-1336D01*
G03X766364Y284716I-124J-380D01*
G37*
G36*
G01X656121Y285442D02*
G02X654689Y285967I-1121J-842D01*
G03X654921Y286597I-88J390D01*
G02X656353Y286072I1121J842D01*
G03X656121Y285442I88J-390D01*
G37*
G36*
G01X1357775Y285582D02*
G02X1357735Y284295I1225J-682D01*
G03X1357025Y284318I-361J-172D01*
G02X1357065Y285605I-1225J682D01*
G03X1357775Y285582I361J172D01*
G37*
G36*
G01X1116937Y288227D02*
G02X1115684Y287313I62J-1401D01*
G03X1115292Y287851I-375J139D01*
G02X1116545Y288765I-62J1401D01*
G03X1116937Y288227I375J-139D01*
G37*
G36*
G01X465845Y293836D02*
G02X464680Y292661I221J-1384D01*
G03X464221Y293116I-396J60D01*
G02X465386Y294291I-221J1384D01*
G03X465845Y293836I396J-60D01*
G37*
G36*
G01X1455422Y293767D02*
G02X1454196Y293829I-671J-1116D01*
G03X1454231Y294533I-171J361D01*
G02X1455457Y294471I671J1116D01*
G03X1455422Y293767I171J-361D01*
G37*
G36*
G01X391445Y293739D02*
G02X391442Y292074I1249J-835D01*
G03X390777Y292075I-333J-221D01*
G02X390780Y293740I-1249J835D01*
G03X391445Y293739I333J221D01*
G37*
G36*
G01X1019491Y293792D02*
G02X1019487Y292021I1211J-888D01*
G03X1018841Y292022I-323J-236D01*
G02X1018845Y293793I-1211J888D01*
G03X1019491Y293792I323J236D01*
G37*
G36*
G01X1033860Y293749D02*
G02X1033857Y292064I1242J-845D01*
G03X1033195Y292065I-331J-224D01*
G02X1033198Y293750I-1242J845D01*
G03X1033860Y293749I331J224D01*
G37*
G36*
G01X1041074Y293769D02*
G02X1041066Y292051I1228J-865D01*
G03X1040410Y292054I-329J-227D01*
G02X1040418Y293772I-1228J865D01*
G03X1041074Y293769I329J227D01*
G37*
G36*
G01X1048230Y293702D02*
G02X1048227Y292110I1272J-798D01*
G03X1047548Y292112I-340J-211D01*
G02X1047551Y293704I-1272J798D01*
G03X1048230Y293702I340J211D01*
G37*
G36*
G01X1055512Y293821D02*
G02X1055509Y291992I1190J-916D01*
G03X1054874Y291993I-318J-243D01*
G02X1054877Y293822I-1190J916D01*
G03X1055512Y293821I318J243D01*
G37*
G36*
G01X412461Y292127D02*
G02Y293681I-1167J777D01*
G03X413127I333J222D01*
G02Y292127I1167J-777D01*
G03X412461I-333J-222D01*
G37*
G36*
G01X419661D02*
G02Y293681I-1167J777D01*
G03X420327I333J222D01*
G02Y292127I1167J-777D01*
G03X419661I-333J-222D01*
G37*
G36*
G01X426861D02*
G02Y293681I-1167J777D01*
G03X427527I333J222D01*
G02Y292127I1167J-777D01*
G03X426861I-333J-222D01*
G37*
G36*
G01X434061D02*
G02Y293681I-1167J777D01*
G03X434727I333J222D01*
G02Y292127I1167J-777D01*
G03X434061I-333J-222D01*
G37*
G36*
G01X441261D02*
G02Y293681I-1167J777D01*
G03X441927I333J222D01*
G02Y292127I1167J-777D01*
G03X441261I-333J-222D01*
G37*
G36*
G01X1062069D02*
G02Y293681I-1167J777D01*
G03X1062735I333J222D01*
G02Y292127I1167J-777D01*
G03X1062069I-333J-222D01*
G37*
G36*
G01X1069269D02*
G02Y293681I-1167J777D01*
G03X1069935I333J222D01*
G02Y292127I1167J-777D01*
G03X1069269I-333J-222D01*
G37*
G36*
G01X1076469D02*
G02Y293681I-1167J777D01*
G03X1077135I333J222D01*
G02Y292127I1167J-777D01*
G03X1076469I-333J-222D01*
G37*
G36*
G01X1083669D02*
G02Y293681I-1167J777D01*
G03X1084335I333J222D01*
G02Y292127I1167J-777D01*
G03X1083669I-333J-222D01*
G37*
G36*
G01X1090869D02*
G02Y293681I-1167J777D01*
G03X1091535I333J222D01*
G02Y292127I1167J-777D01*
G03X1090869I-333J-222D01*
G37*
G36*
G01X1321162Y296032D02*
G02X1320246Y295063I438J-1332D01*
G03X1319735Y295546I-387J103D01*
G02X1320651Y296515I-438J1332D01*
G03X1321162Y296032I387J-103D01*
G37*
G36*
G01X173985Y294577D02*
G02X171828Y296645I-1185J923D01*
G03Y297255I-259J305D01*
G02X171742Y299466I972J1145D01*
G03Y300034I-282J284D01*
G02X171828Y302245I1058J1066D01*
G03Y302855I-259J305D01*
G02X173985Y304923I972J1145D01*
G03X174615I315J246D01*
G02X176985I1185J-923D01*
G03X177615I315J246D01*
G02X179985I1185J-923D01*
G03X180615I315J246D01*
G02X182985I1185J-923D01*
G03X183615I315J246D01*
G02X185985I1185J-923D01*
G03X186615I315J246D01*
G02X186869Y305179I1186J-922D01*
G03X186890Y305788I-248J313D01*
G02X189000Y307922I1009J1113D01*
G03X189582Y307918I293J273D01*
G02X189689Y308018I1078J-1046D01*
G03X189677Y308331I-130J152D01*
G02X191679Y308526I893J1208D01*
G03X191699Y307966I295J-270D01*
G02X189565Y305855I-1034J-1089D01*
G03X188983Y305859I-293J-273D01*
G02X188831Y305721I-1083J1041D01*
G03X188810Y305112I248J-313D01*
G02X188772Y302855I-1010J-1112D01*
G03Y302245I259J-305D01*
G02X188858Y300034I-972J-1145D01*
G03Y299466I282J-284D01*
G02X188868Y297343I-1058J-1067D01*
G03X188900Y296751I284J-282D01*
G02X189108Y296547I-943J-1169D01*
G03X189706Y296529I307J256D01*
G02X191985Y296423I1094J-1029D01*
G03X192615I315J246D01*
G02X195024Y296370I1185J-923D01*
G03X195688Y296388I326J232D01*
G02X195732Y294713I1268J-805D01*
G03X195068Y294695I-326J-232D01*
G02X192615Y294577I-1268J805D01*
G03X191985I-315J-246D01*
G02X189648Y294536I-1185J923D01*
G03X189050Y294554I-307J-256D01*
G02X186732Y294713I-1094J1029D01*
G03X186068Y294695I-326J-232D01*
G02X183615Y294577I-1268J805D01*
G03X182985I-315J-246D01*
G02X180648Y294536I-1185J923D01*
G03X180050Y294554I-307J-256D01*
G02X177732Y294713I-1094J1029D01*
G03X177068Y294695I-326J-232D01*
G02X174615Y294577I-1268J805D01*
G03X173985I-315J-246D01*
G37*
G36*
G01X823867Y294604D02*
G02X821759Y296712I-1185J923D01*
G03Y297342I-246J315D01*
G02X821624Y299593I923J1185D01*
G03Y300161I-282J284D01*
G02Y302293I1058J1066D01*
G03Y302861I-282J284D01*
G02X823867Y304850I1058J1066D01*
G03X824497I315J246D01*
G02X826867I1185J-923D01*
G03X827497I315J246D01*
G02X829867I1185J-923D01*
G03X830497I315J246D01*
G02X832867I1185J-923D01*
G03X833497I315J246D01*
G02X835906Y304797I1185J-923D01*
G03X836558I326J232D01*
G02X838754Y302782I1224J-870D01*
G03Y302172I259J-305D01*
G02Y299882I-972J-1145D01*
G03Y299272I259J-305D01*
G02X836448Y297436I-972J-1145D01*
G03X835797Y297520I-355J-184D01*
G02X833497Y297604I-1115J1007D01*
G03X832867I-315J-246D01*
G02X830497I-1185J923D01*
G03X829867I-315J-246D01*
G02X827497I-1185J923D01*
G03X826867I-315J-246D01*
G02X826605Y297342I-1185J923D01*
G03Y296712I246J-315D01*
G02X824497Y294604I-923J-1185D01*
G03X823867I-315J-246D01*
G37*
G36*
G01X1115777Y297174D02*
G02X1114706Y295993I319J-1365D01*
G03X1114219Y296435I-397J52D01*
G02X1115290Y297616I-319J1365D01*
G03X1115777Y297174I397J-52D01*
G37*
G36*
G01X59608Y298174D02*
G02X57670Y298249I-1008J-974D01*
G03X57692Y298826I-266J299D01*
G02X57830Y300900I1008J975D01*
G03X57808Y301543I-248J313D01*
G02X59470Y301600I792J1157D01*
G03X59492Y300957I248J-313D01*
G02X59630Y298751I-792J-1157D01*
G03X59608Y298174I266J-299D01*
G37*
G36*
G01X672778Y298889D02*
G02X672637Y297518I1144J-810D01*
G03X671944Y297589I-367J-160D01*
G02X669711Y297517I-1144J811D01*
G03X669089I-311J-252D01*
G02Y299283I-1089J883D01*
G03X669711I311J252D01*
G02X672085Y298960I1089J-883D01*
G03X672778Y298889I367J160D01*
G37*
G36*
G01X776085Y299379D02*
G02X773826Y297921I-914J-1063D01*
G03X773223Y298143I-384J-112D01*
G02X771430Y298253I-823J1257D01*
G03X770807Y298114I-259J-305D01*
G02X768259Y299663I-1368J620D01*
G03X768017Y300303I-315J247D01*
G02X769312Y302881I273J1477D01*
G03X769861Y302885I272J293D01*
G02X772343Y301384I1039J-1085D01*
G03X772659Y300880I384J-110D01*
G02X773112Y300722I-262J-1479D01*
G03X773701Y301101I190J352D01*
G02X776105Y300001I1499J99D01*
G03X776085Y299379I241J-319D01*
G37*
G36*
G01X123318Y299752D02*
G02X121539Y300049I-1087J-1036D01*
G03X121644Y300680I-185J355D01*
G02X123889Y302673I1087J1037D01*
G03X124505I308J255D01*
G02Y300759I1158J-957D01*
G03X123889I-308J-255D01*
G02X123423Y300383I-1157J958D01*
G03X123318Y299752I185J-355D01*
G37*
G36*
G01X4973Y301570D02*
G02Y303124I-1167J777D01*
G03X5639I333J222D01*
G02Y301570I1167J-777D01*
G03X4973I-333J-222D01*
G37*
G36*
G01X1459331Y305344D02*
G02X1458118Y306398I-1279J-246D01*
G03X1458533Y306735I20J399D01*
G02X1458534Y306739I387J-95D01*
G03X1458299Y306969I-197J33D01*
G02X1458117Y309547I-248J1278D01*
G03X1458532Y309884I20J400D01*
G02X1458533Y309889I393J-76D01*
G03X1458298Y310118I-197J33D01*
G02X1459352Y311332I-246J1278D01*
G03X1459689Y310917I400J-20D01*
G02X1459694Y310916I-76J-393D01*
G03X1459923Y311151I33J197D01*
G02X1462502Y311331I1279J246D01*
G03X1462839Y310916I399J-20D01*
G02X1462843Y310915I-95J-387D01*
G03X1463073Y311150I33J197D01*
G02X1464285Y310097I1278J247D01*
G03X1463870Y309760I-20J-399D01*
G02X1463869Y309755I-392J76D01*
G03X1464104Y309526I197J-33D01*
G02X1464285Y306947I246J-1279D01*
G03X1463869Y306610I-21J-400D01*
G01Y306606D01*
G03X1464104Y306376I197J-34D01*
G02X1463051Y305164I247J-1278D01*
G03X1462714Y305579I-399J20D01*
G02X1462710Y305580I95J387D01*
G03X1462480Y305345I-33J-197D01*
G02X1459902Y305163I-1278J-248D01*
G03X1459565Y305578I-400J20D01*
G02X1459560Y305579I76J393D01*
G03X1459331Y305344I-33J-197D01*
G37*
G36*
G01X1506795Y307781D02*
G02X1505065Y307774I-861J-1107D01*
G03X1505063Y308403I-248J314D01*
G02X1506793Y308410I861J1107D01*
G03X1506795Y307781I248J-314D01*
G37*
G36*
G01X777591Y306631D02*
G02X777150Y308191I-1321J469D01*
G03X777779Y308369I252J311D01*
G02X778220Y306809I1321J-469D01*
G03X777591Y306631I-252J-311D01*
G37*
G36*
G01X128755Y306876D02*
G02X128442Y308539I-1255J625D01*
G03X129069Y308657I269J296D01*
G02X129382Y306994I1255J-625D01*
G03X128755Y306876I-269J-296D01*
G37*
G36*
G01X1104766Y308814D02*
G02X1102437Y307365I-1010J-972D01*
G03X1101882Y307587I-376J-136D01*
G02X1099937Y308365I-626J1254D01*
G03X1099382Y308587I-376J-136D01*
G02X1097553Y309122I-626J1254D01*
G03X1096875Y309136I-343J-205D01*
G02X1094573Y309072I-1173J768D01*
G03X1093919Y309058I-322J-237D01*
G02X1091553Y309122I-1163J783D01*
G03X1090875Y309136I-343J-205D01*
G02X1090905Y310623I-1173J767D01*
G03X1091583Y310609I343J205D01*
G02X1093885Y310673I1173J-768D01*
G03X1094539Y310687I322J237D01*
G02X1096905Y310623I1163J-783D01*
G03X1097583Y310609I343J205D01*
G02X1100075Y310317I1173J-768D01*
G03X1100630Y310095I376J136D01*
G02X1101805Y310131I626J-1254D01*
G03X1102359Y310464I156J368D01*
G02X1104766Y309368I1397J-123D01*
G03Y308814I288J-277D01*
G37*
G36*
G01X116300Y310684D02*
G02X114751Y310669I-763J-1176D01*
G03X114744Y311336I-224J331D01*
G02X116293Y311351I763J1176D01*
G03X116300Y310684I224J-331D01*
G37*
G36*
G01X765908D02*
G02X764359Y310669I-763J-1176D01*
G03X764352Y311336I-224J331D01*
G02X765901Y311351I763J1176D01*
G03X765908Y310684I224J-331D01*
G37*
G36*
G01X1022322Y308938D02*
G02X1022236Y310700I-1257J822D01*
G03X1022883Y310731I312J250D01*
G02X1022969Y308969I1257J-822D01*
G03X1022322Y308938I-312J-250D01*
G37*
G36*
G01X369939Y310602D02*
G02X369911Y309141I1298J-756D01*
G03X369212Y309154I-353J-188D01*
G02X369240Y310615I-1298J756D01*
G03X369939Y310602I353J188D01*
G37*
G36*
G01X391435Y310723D02*
G02X391432Y309089I1259J-819D01*
G03X390761Y309091I-336J-217D01*
G02X390764Y310725I-1259J819D01*
G03X391435Y310723I336J217D01*
G37*
G36*
G01X398638Y310728D02*
G02X398635Y309085I1256J-824D01*
G03X397965Y309086I-335J-218D01*
G02X397968Y310729I-1256J824D01*
G03X398638Y310728I335J218D01*
G37*
G36*
G01X1033923Y310774D02*
G02X1033919Y309039I1224J-870D01*
G03X1033266Y309040I-327J-231D01*
G02X1033270Y310775I-1224J870D01*
G03X1033923Y310774I327J231D01*
G37*
G36*
G01X1055504Y310747D02*
G02X1055500Y309066I1243J-843D01*
G03X1054837Y309067I-332J-223D01*
G02X1054841Y310748I-1243J843D01*
G03X1055504Y310747I332J223D01*
G37*
G36*
G01X441282Y309097D02*
G02Y310585I-1188J744D01*
G03X441960I339J213D01*
G02Y309097I1188J-744D01*
G03X441282I-339J-213D01*
G37*
G36*
G01X412461Y309127D02*
G02Y310681I-1167J777D01*
G03X413127I333J222D01*
G02Y309127I1167J-777D01*
G03X412461I-333J-222D01*
G37*
G36*
G01X419661D02*
G02Y310681I-1167J777D01*
G03X420327I333J222D01*
G02Y309127I1167J-777D01*
G03X419661I-333J-222D01*
G37*
G36*
G01X426861D02*
G02Y310681I-1167J777D01*
G03X427527I333J222D01*
G02Y309127I1167J-777D01*
G03X426861I-333J-222D01*
G37*
G36*
G01X434061D02*
G02Y310681I-1167J777D01*
G03X434727I333J222D01*
G02Y309127I1167J-777D01*
G03X434061I-333J-222D01*
G37*
G36*
G01X1062069D02*
G02Y310681I-1167J777D01*
G03X1062735I333J222D01*
G02Y309127I1167J-777D01*
G03X1062069I-333J-222D01*
G37*
G36*
G01X1069269D02*
G02Y310681I-1167J777D01*
G03X1069935I333J222D01*
G02Y309127I1167J-777D01*
G03X1069269I-333J-222D01*
G37*
G36*
G01X1076469D02*
G02Y310681I-1167J777D01*
G03X1077135I333J222D01*
G02Y309127I1167J-777D01*
G03X1076469I-333J-222D01*
G37*
G36*
G01X1083669D02*
G02Y310681I-1167J777D01*
G03X1084335I333J222D01*
G02Y309127I1167J-777D01*
G03X1083669I-333J-222D01*
G37*
G36*
G01X77011Y310638D02*
G02X74355Y309826I-1385J-221D01*
G03X73684Y309910I-362J-170D01*
G02X73871Y311392I-1084J890D01*
G03X74542Y311308I362J170D01*
G02X75699Y311818I1083J-890D01*
G03X76115Y312280I21J399D01*
G02X76713Y313660I1385J220D01*
G03X76668Y314348I-225J331D01*
G02X78087Y314440I631J1252D01*
G03X78132Y313752I225J-331D01*
G02X77427Y311100I-632J-1252D01*
G03X77011Y310638I-21J-399D01*
G37*
G36*
G01X1494528Y312009D02*
G02X1494517Y310711I1123J-659D01*
G03X1493823Y310717I-349J-196D01*
G02X1493834Y312015I-1123J659D01*
G03X1494528Y312009I349J196D01*
G37*
G36*
G01X1493845Y313933D02*
G02Y315159I-1149J613D01*
G03X1494550I352J188D01*
G02Y313933I1149J-613D01*
G03X1493845I-352J-188D01*
G37*
G36*
G01X766382Y316635D02*
G02X765182Y317754I-1375J-272D01*
G03X765625Y318228I50J397D01*
G02X765973Y319454I1375J272D01*
G03X765913Y320051I-293J272D01*
G02X767759Y320235I819J1138D01*
G03X767819Y319638I293J-272D01*
G02X766825Y317109I-819J-1138D01*
G03X766382Y316635I-50J-397D01*
G37*
G36*
G01X76830Y321972D02*
G02X76259Y320391I770J-1172D01*
G03X75657Y320608I-382J-117D01*
G02X73796Y320899I-770J1172D01*
G03X73178Y320903I-311J-252D01*
G02X73191Y322681I-1078J897D01*
G03X73809Y322677I311J252D01*
G02X76228Y322189I1078J-897D01*
G03X76830Y321972I382J117D01*
G37*
G36*
G01X94042Y324546D02*
G02X93615Y323004I896J-1078D01*
G03X92982Y323179I-377J-132D01*
G02X93409Y324721I-896J1078D01*
G03X94042Y324546I377J132D01*
G37*
G36*
G01X688114Y326341D02*
G02X686563Y326393I-815J-1141D01*
G03X686586Y327059I-210J341D01*
G02X688137Y327007I815J1141D01*
G03X688114Y326341I210J-341D01*
G37*
G36*
G01X637472Y328363D02*
G02X636003Y327816I-329J-1363D01*
G03X635771Y328437I-326J232D01*
G02X636069Y331202I328J1363D01*
G03X636420Y331777I-8J400D01*
G02X637712Y330988I1261J613D01*
G03X637361Y330413I8J-400D01*
G02X637240Y328984I-1261J-613D01*
G03X637472Y328363I326J-232D01*
G37*
G36*
G01X1514594Y328782D02*
G02X1513308Y328680I-545J-1292D01*
G03X1513252Y329388I-211J340D01*
G02X1514538Y329490I545J1292D01*
G03X1514594Y328782I211J-340D01*
G37*
G36*
G01X195977Y326720D02*
G02X193577Y326760I-1185J923D01*
G03X192946Y326781I-324J-235D01*
G02X190491Y326992I-1154J962D01*
G03X189831Y327040I-346J-200D01*
G02X187731Y329158I-1177J933D01*
G03Y329788I-246J315D01*
G02X187696Y332130I923J1185D01*
G03X187691Y332750I-255J308D01*
G02X187445Y333000I940J1171D01*
G03X186815I-315J-246D01*
G02X184579Y334996I-1185J923D01*
G03X184510Y335623I-279J287D01*
G02X184085Y336017I789J1278D01*
G03X183454Y336038I-324J-235D01*
G02X181115Y336077I-1154J962D01*
G03X180485I-315J-246D01*
G02X178115I-1185J923D01*
G03X177485I-315J-246D01*
G02X175115I-1185J923D01*
G03X174485I-315J-246D01*
G02X172328Y338145I-1185J923D01*
G03Y338755I-259J305D01*
G02X174485Y340823I972J1145D01*
G03X175115I315J246D01*
G02X177485I1185J-923D01*
G03X178115I315J246D01*
G02X180485I1185J-923D01*
G03X181115I315J246D01*
G02X183485I1185J-923D01*
G03X184115I315J246D01*
G02X186485I1185J-923D01*
G03X187115I315J246D01*
G02X189515Y340783I1185J-923D01*
G03X190146Y340762I324J235D01*
G02X190085Y338917I1154J-962D01*
G03X189454Y338938I-324J-235D01*
G02X189223Y338715I-1153J963D01*
G03Y338085I246J-315D01*
G02X189351Y335827I-923J-1185D01*
G03X189420Y335200I279J-287D01*
G02X189588Y332766I-790J-1277D01*
G03X189593Y332146I255J-308D01*
G02X189577Y329788I-939J-1173D01*
G03Y329158I246J-315D01*
G02X189955Y328724I-923J-1185D01*
G03X190615Y328676I346J200D01*
G02X193007Y328626I1177J-933D01*
G03X193638Y328605I324J235D01*
G02X195977Y328566I1154J-962D01*
G03X196607I315J246D01*
G02Y326720I1185J-923D01*
G03X195977I-315J-246D01*
G37*
G36*
G01X126275Y331524D02*
G02X124804Y331495I-712J-1208D01*
G03X124779Y332182I-217J336D01*
G02X124256Y332659I722J1317D01*
G03X123673Y332746I-331J-224D01*
G02X123312Y332531I-942J1170D01*
G03X123207Y331858I155J-369D01*
G02X121650Y332101I-976J-1142D01*
G03X121755Y332774I-155J369D01*
G02X123975Y334757I976J1142D01*
G03X124558Y334670I331J224D01*
G02X126272Y332212I942J-1169D01*
G03X126275Y331524I206J-343D01*
G37*
G36*
G01X202100Y331913D02*
G02X200254I-923J-1185D01*
G03Y332543I-246J315D01*
G02Y334913I923J1185D01*
G03Y335543I-246J315D01*
G02X200133Y337808I923J1185D01*
G03X200130Y338386I-278J288D01*
G02X199892Y338675I1031J1092D01*
G03X199252Y338724I-338J-213D01*
G02X197112Y340824I-1134J985D01*
G03X197133Y341396I-269J296D01*
G02X197289Y343607I1090J1034D01*
G03X197292Y344232I-248J314D01*
G02X197048Y344479I939J1172D01*
G03X196418I-315J-246D01*
G02X194376Y346635I-1185J923D01*
G03X194388Y347283I-229J328D01*
G02Y349521I845J1119D01*
G03X194376Y350169I-241J320D01*
G02X196418Y352325I857J1233D01*
G03X197048I315J246D01*
G02X199156Y350217I1185J-923D01*
G03Y349587I246J-315D01*
G02X199326Y349432I-924J-1184D01*
G03X199918Y349442I291J274D01*
G02X201968Y347264I1127J-993D01*
G03Y346634I246J-315D01*
G02X202212Y346395I-922J-1186D01*
G03X202846Y346411I311J252D01*
G02X204983Y344342I1214J-884D01*
G03Y343712I246J-315D01*
G02X204996Y341353I-923J-1185D01*
G03X205018Y340711I249J-313D01*
G02X205207Y338396I-855J-1235D01*
G03X205210Y337818I278J-288D01*
G02X202992Y335805I-1033J-1090D01*
G03X202362I-315J-246D01*
G02X202100Y335543I-1185J923D01*
G03Y334913I246J-315D01*
G02Y332543I-923J-1185D01*
G03Y331913I246J-315D01*
G37*
G36*
G01X1106728Y335132D02*
G02X1104994Y335070I-828J-1132D01*
G03X1104972Y335698I-258J305D01*
G02X1106706Y335760I828J1132D01*
G03X1106728Y335132I258J-305D01*
G37*
G36*
G01X451673Y334540D02*
G02X449473Y334871I-973J1010D01*
G03X448830Y334949I-350J-194D01*
G02X449027Y336579I-1030J951D01*
G03X449670Y336501I350J194D01*
G02X451673Y336560I1030J-951D01*
G03X452227I277J288D01*
G02Y334540I973J-1010D01*
G03X451673I-277J-288D01*
G37*
G36*
G01X69546Y336983D02*
G02X67743Y337379I-1128J-833D01*
G03X67872Y337967I-193J350D01*
G02X67735Y338195I1128J833D01*
G03X67025Y338218I-361J-172D01*
G02X64643Y338108I-1225J682D01*
G03X64000Y338130I-330J-226D01*
G02X64057Y339792I-1100J870D01*
G03X64700Y339770I330J226D01*
G02X67065Y339505I1100J-870D01*
G03X67775Y339482I361J172D01*
G02X70167Y339577I1225J-682D01*
G03X70833I333J222D01*
G02X73073Y339702I1167J-777D01*
G03X73695Y339713I307J257D01*
G02X73727Y337948I1105J-863D01*
G03X73105Y337937I-307J-257D01*
G02X70833Y338023I-1105J863D01*
G03X70167I-333J-222D01*
G02X69675Y337571I-1167J777D01*
G03X69546Y336983I193J-350D01*
G37*
G36*
G01X1409740Y336269D02*
G02X1408622Y337811I-1392J167D01*
G03X1409097Y338155I78J392D01*
G02X1409130Y338332I1392J-168D01*
G03X1408866Y338568I-194J49D01*
G02X1409775Y339789I-490J1314D01*
G03X1410244Y339368I399J-27D01*
G02X1410215Y336613I245J-1380D01*
G03X1409740Y336269I-78J-392D01*
G37*
G36*
G01X1101253Y337632D02*
G02X1101084Y336002I1047J-932D01*
G03X1100438Y336069I-347J-199D01*
G02X1100607Y337699I-1047J932D01*
G03X1101253Y337632I347J199D01*
G37*
G36*
G01X1483734Y337311D02*
G02X1482776Y338273I-1348J-385D01*
G03X1483272Y338767I112J384D01*
G02X1483219Y339088I1348J387D01*
G03X1482768Y339466I-399J-18D01*
G02X1483986Y340920I-183J1390D01*
G03X1484437Y340542I399J18D01*
G02X1484230Y337805I183J-1390D01*
G03X1483734Y337311I-112J-384D01*
G37*
G36*
G01X66648Y559899D02*
G03X66455Y560099I-200J0D01*
G02X65333Y560723I45J1401D01*
G03X64667I-333J-222D01*
G02Y562277I-1167J777D01*
G03X65333I333J222D01*
G02X66455Y562901I1167J-777D01*
G03X66648Y563101I-7J200D01*
G01Y594399D01*
G03X66455Y594599I-200J0D01*
G02X65333Y595223I45J1401D01*
G03X64667I-333J-222D01*
G02X62723Y597167I-1167J777D01*
G03Y597833I-222J333D01*
G02Y600167I777J1167D01*
G03Y600833I-222J333D01*
G02X64667Y602777I777J1167D01*
G03X65333I333J222D01*
G02X66455Y603401I1167J-777D01*
G03X66648Y603601I-7J200D01*
G01Y614515D01*
X68231Y616098D01*
X68246Y616127D01*
G02X68873Y616754I1254J-627D01*
G01X68902Y616769D01*
X69785Y617652D01*
X88044D01*
X90502Y615194D01*
Y613783D01*
G03X91136Y613459I400J0D01*
G02X100735Y608620I3547J-4904D01*
G03X101417Y608342I400J5D01*
G01X104951Y611876D01*
X115846D01*
X119109Y615138D01*
X359603D01*
X363324Y618860D01*
X375707D01*
X383065Y611502D01*
X384616D01*
X384646Y611665D01*
G02X389617Y614311I3541J-660D01*
G03X389873Y614402I79J183D01*
G02X391116Y615156I1243J-648D01*
G01X393253D01*
G02X394365Y614607I-1J-1402D01*
G03X394999I317J243D01*
G02X396111Y615156I1113J-853D01*
G01X399946D01*
G02X401058Y614606I-1J-1401D01*
G03X401694I318J243D01*
G02X402806Y615156I1113J-851D01*
G01X413332D01*
G02X414444Y614607I-1J-1402D01*
G03X415078I317J243D01*
G02X416190Y615156I1113J-853D01*
G01X420025D01*
G02X421137Y614607I-1J-1402D01*
G03X421771I317J243D01*
G02X422883Y615156I1113J-853D01*
G01X426718D01*
G02X427830Y614607I-1J-1402D01*
G03X428464I317J243D01*
G02X429576Y615156I1113J-853D01*
G01X433411D01*
G02X434523Y614607I-1J-1402D01*
G03X435157I317J243D01*
G02X436269Y615156I1113J-853D01*
G01X444676D01*
X446195Y613636D01*
G03X446764Y613639I283J283D01*
G02X448746Y611657I1002J-980D01*
G03X448743Y611088I280J-286D01*
G01X450820Y609012D01*
Y606266D01*
G03X451298Y605874I400J0D01*
G02Y603124I275J-1375D01*
G03X450820Y602732I-78J-392D01*
G01Y595524D01*
G03X451298Y595132I400J0D01*
G02X451233Y592397I275J-1375D01*
G03X450755Y592129I-96J-388D01*
G02X448853Y591266I-1337J420D01*
G03X448336Y590717I-161J-366D01*
G02X448403Y590564I-1248J-638D01*
G03X448684Y590457I188J70D01*
G02X448834Y590526I660J-1237D01*
G03X448853Y590533I-129J379D01*
G02X450820Y589251I565J-1282D01*
G01Y576179D01*
G02X450294Y575085I-1402J0D01*
G03Y574461I250J-312D01*
G02X450820Y573367I-876J-1094D01*
G01Y570551D01*
G02X450345Y569500I-1402J1D01*
G03Y568900I265J-300D01*
G02X450741Y568311I-927J-1051D01*
G03X451220Y568056I378J132D01*
G02X451298Y565324I353J-1357D01*
G03X450820Y564932I-78J-392D01*
G01Y557724D01*
G03X451298Y557332I400J0D01*
G02X451233Y554597I275J-1375D01*
G03X450755Y554329I-96J-388D01*
G02X448853Y553466I-1337J420D01*
G03Y552734I-161J-366D01*
G02X450820Y551451I565J-1283D01*
G01Y551399D01*
G02X450521Y550534I-1402J0D01*
G03X450820Y549888I315J-247D01*
G01Y548150D01*
X450025Y547356D01*
X450021D01*
X448894Y546228D01*
Y538541D01*
X448148Y537796D01*
Y537085D01*
X448059Y536870D01*
G03Y536576I373J-147D01*
G01X448148Y536361D01*
Y531557D01*
X448046Y531323D01*
X448045Y531319D01*
G03Y530993I365J-163D01*
G01X448046Y530989D01*
X448148Y530755D01*
Y529972D01*
X448432Y529689D01*
Y515703D01*
X448329Y515468D01*
X448327Y515464D01*
G03Y515136I365J-164D01*
G01X448329Y515132D01*
X448432Y514897D01*
Y513445D01*
X447607Y513174D01*
G03X447796Y512398I127J-380D01*
G02X449418Y511015I221J-1384D01*
G01Y502610D01*
X415038Y468229D01*
Y430557D01*
X415020Y430538D01*
Y378985D01*
X413877Y377843D01*
G02X412828Y377434I-991J991D01*
G03X412412Y377018I-16J-400D01*
G02X412003Y375969I-1400J-58D01*
G01X411365Y375331D01*
X411013Y375253D01*
X411005Y375252D01*
G03X410688Y374816I81J-392D01*
G03X410747Y374647I398J44D01*
G01X410902Y374402D01*
Y370045D01*
G03X411356Y369649I400J0D01*
G02X412518Y367249I191J-1389D01*
G03Y366671I277J-289D01*
G02X412516Y364647I-971J-1011D01*
G03X412494Y364092I277J-289D01*
G02X410478Y364173I-1047J-932D01*
G03X410500Y364728I-277J289D01*
G02X410576Y366671I1047J932D01*
G03Y367249I-277J289D01*
G02X410417Y367430I970J1012D01*
G03X409812Y367476I-322J-237D01*
G01X408362Y366025D01*
Y358255D01*
X404255Y354149D01*
X404317Y354021D01*
G02X403599Y352117I-1261J-612D01*
G03X403471Y351465I155J-369D01*
G01X404265Y350672D01*
X418685D01*
X419888Y349469D01*
G03X420458Y349473I283J283D01*
G02X421786Y347132I1006J-976D01*
G01X421632Y347096D01*
Y345242D01*
X421799Y345074D01*
X421811D01*
X422403Y344482D01*
X431827D01*
X432898Y343411D01*
Y337196D01*
X431341Y335638D01*
X393895D01*
X391918Y337615D01*
Y337645D01*
X386907Y342657D01*
G03X386269Y342559I-283J-283D01*
G02X384377Y344451I-1242J650D01*
G03X384475Y345089I-185J355D01*
G01X380885Y348678D01*
X377147D01*
G02X374642Y349237I-1129J831D01*
G01X374610Y349398D01*
X374314D01*
G02X373083Y350131I1J1401D01*
G02X372191I-446J1329D01*
G02X370960Y349398I-1232J668D01*
G01X370664D01*
X370632Y349237D01*
G02X367882I-1375J272D01*
G01X367850Y349398D01*
X367554D01*
G02X366323Y350131I1J1401D01*
G02X365431I-446J1329D01*
G02X364200Y349398I-1232J668D01*
G01X363904D01*
X363872Y349237D01*
G02X361122I-1375J272D01*
G01X361090Y349398D01*
X360794D01*
G02X359563Y350131I1J1401D01*
G02X358671I-446J1329D01*
G02X357440Y349398I-1232J668D01*
G01X356346D01*
X356046Y349763D01*
G03X355428I-309J-254D01*
G01X355128Y349398D01*
X354034D01*
G02X352803Y350131I1J1401D01*
G02X351911I-446J1329D01*
G02X350680Y349398I-1232J668D01*
G01X349587D01*
X349287Y349763D01*
G03X348669I-309J-254D01*
G01X348369Y349398D01*
X347275D01*
G02X346044Y350131I1J1401D01*
G02X345152I-446J1329D01*
G02X343921Y349398I-1232J668D01*
G01X343625D01*
X343593Y349237D01*
G02X341223Y350497I-1375J272D01*
G03X341222Y351062I-284J282D01*
G01X339370Y352913D01*
Y359072D01*
X339305Y359138D01*
X339215Y359395D01*
G03X339017Y359618I-377J-135D01*
G01X338464Y359895D01*
Y361802D01*
X338335Y361851D01*
G02X338468Y364512I503J1309D01*
G01X338616Y364553D01*
Y365588D01*
X338507Y365697D01*
X338457Y365711D01*
G02X338310Y368359I381J1349D01*
G01X338348Y368374D01*
X338616Y368642D01*
Y369566D01*
X338468Y369607D01*
G02X338080Y372138I370J1352D01*
G03X338230Y372633I-217J336D01*
G02X338182Y373621I1286J558D01*
G02X337489Y375242I656J1239D01*
G02X336963Y375682I609J1262D01*
G03X336377Y375750I-324J-234D01*
G02X336376Y377868I-919J1059D01*
G03X336963Y377937I262J302D01*
G02X337489Y378378I1136J-821D01*
G02Y379142I1349J382D01*
G02X336698Y380402I610J1261D01*
G01Y395785D01*
X335192Y397290D01*
Y422685D01*
X334998Y422879D01*
Y434146D01*
G03X334262Y434362I-400J0D01*
G02Y443984I-7490J4811D01*
G03X334998Y444200I336J216D01*
G01Y469077D01*
X334952Y469123D01*
Y472302D01*
X309216Y498038D01*
Y508358D01*
G02X309773Y509476I1402J-1D01*
G02Y510752I1248J638D01*
G02X309216Y511870I845J1119D01*
G01Y516663D01*
G03X308563Y516972I-400J0D01*
G02X307732Y519458I-888J1085D01*
G03X308148Y519857I16J399D01*
G01Y527551D01*
X307982Y527579D01*
G02Y530147I216J1284D01*
G01X308148Y530175D01*
Y532619D01*
X308323Y532874D01*
G03Y533326I-331J226D01*
G01X308148Y533581D01*
Y536993D01*
X308080Y537062D01*
X308017Y537165D01*
G03X307883Y537299I-342J-208D01*
G01X307790Y537356D01*
X307720D01*
X307695Y537357D01*
G03X307655I-20J-400D01*
G01X307630Y537356D01*
X306318D01*
X303432Y540242D01*
X95108D01*
X94554Y539688D01*
G03X94828Y539005I283J-283D01*
G02X88735Y534075I-146J-6050D01*
G03X88342Y534548I-393J73D01*
G01X71585D01*
X70571Y535562D01*
G03X69891Y535329I-283J-283D01*
G02X67333Y534723I-1391J171D01*
G03X66667I-333J-222D01*
G02X64333I-1167J777D01*
G03X63667I-333J-222D01*
G02Y536277I-1167J777D01*
G03X64333I333J222D01*
G02X66667I1167J-777D01*
G03X67333I333J222D01*
G02X68329Y536891I1167J-777D01*
G03X68562Y537571I-50J397D01*
G01X66648Y539485D01*
Y552899D01*
G03X66455Y553099I-200J0D01*
G02X65333Y553723I45J1401D01*
G03X64667I-333J-222D01*
G02X62723Y555667I-1167J777D01*
G03Y556333I-222J333D01*
G02X64667Y558277I777J1167D01*
G03X65333I333J222D01*
G02X66455Y558901I1167J-777D01*
G03X66648Y559101I-7J200D01*
G01Y559899D01*
G37*
G36*
G01X53874Y338591D02*
G02X52942Y338875I-849J-1116D01*
G03X53248Y339502I-23J399D01*
G02X55802Y340299I1152J798D01*
G03X56224Y339900I400J0D01*
G02X57463Y339283I76J-1400D01*
G03X58162Y339350I331J224D01*
G02X58289Y338017I1290J-550D01*
G03X57590Y337950I-331J-224D01*
G02X54898Y338501I-1290J550D01*
G03X54476Y338900I-400J0D01*
G02X54045Y338944I-75J1400D01*
G03X53874Y338591I-50J-194D01*
G37*
G36*
G01X1488712Y338646D02*
G02X1487060Y338620I-808J-1146D01*
G03X1487050Y339266I-240J319D01*
G02X1488702Y339292I808J1146D01*
G03X1488712Y338646I240J-319D01*
G37*
G36*
G01X99363Y339304D02*
G02X97886Y339236I-684J-1224D01*
G03X97855Y339915I-226J330D01*
G02X99332Y339983I684J1224D01*
G03X99363Y339304I226J-330D01*
G37*
G36*
G01X1048923Y337564D02*
G02Y339118I-1167J777D01*
G03X1049589I333J222D01*
G02X1051885Y339173I1167J-777D01*
G03X1052539Y339187I322J237D01*
G02X1054790Y339289I1163J-783D01*
G03X1055456Y339359I310J252D01*
G02X1055594Y337767I1336J-686D01*
G03X1054926Y337720I-319J-242D01*
G02X1052573Y337572I-1224J684D01*
G03X1051919Y337558I-322J-237D01*
G02X1049589Y337564I-1163J783D01*
G03X1048923I-333J-222D01*
G37*
G36*
G01X1078467Y337610D02*
G02Y339456I-1185J923D01*
G03X1079097I315J246D01*
G02X1081382Y339556I1185J-923D01*
G03X1082017Y339620I293J272D01*
G02X1084446Y339813I1284J-779D01*
G03X1085040Y339796I305J259D01*
G02X1084981Y337786I1086J-1038D01*
G03X1084387Y337803I-305J-259D01*
G02X1082201Y337818I-1086J1038D01*
G03X1081566Y337754I-293J-272D01*
G02X1079097Y337610I-1284J779D01*
G03X1078467I-315J-246D01*
G37*
G36*
G01X128370Y338700D02*
G02X127731Y340196I-1370J299D01*
G03X128330Y340452I208J341D01*
G02X128969Y338956I1370J-299D01*
G03X128370Y338700I-208J-341D01*
G37*
G36*
G01X1564167Y340223D02*
G02Y341777I-1167J777D01*
G03X1564833I333J222D01*
G02Y340223I1167J-777D01*
G03X1564167I-333J-222D01*
G37*
G36*
G01X116300Y342684D02*
G02X114751Y342669I-763J-1176D01*
G03X114744Y343336I-224J331D01*
G02X116293Y343351I763J1176D01*
G03X116300Y342684I224J-331D01*
G37*
G36*
G01X765908D02*
G02X764359Y342669I-763J-1176D01*
G03X764352Y343336I-224J331D01*
G02X765901Y343351I763J1176D01*
G03X765908Y342684I224J-331D01*
G37*
G36*
G01X50027Y344982D02*
G02X48007I-1010J-973D01*
G03Y345536I-288J277D01*
G02X48048Y347522I1010J973D01*
G03X48070Y348077I-277J289D01*
G02X48097Y349971I1047J932D01*
G03X48091Y350526I-291J274D01*
G02X48312Y352675I1000J983D01*
G03X48314Y353339I-222J333D01*
G02X49879Y353334I786J1161D01*
G03X49877Y352670I222J-333D01*
G02X50336Y352153I-786J-1161D01*
G03X50960Y352040I355J184D01*
G02X50557Y350596I940J-1041D01*
G03X50207Y350660I-191J-57D01*
G02X50111Y350547I-1115J850D01*
G03X50117Y349992I291J-274D01*
G02X50086Y347996I-1000J-983D01*
G03X50064Y347441I277J-289D01*
G02X50244Y347187I-1047J-933D01*
G03X50889Y347111I350J194D01*
G02X50696Y345486I1034J-947D01*
G03X50051Y345562I-350J-194D01*
G02X50027Y345536I-1042J938D01*
G03Y344982I288J-277D01*
G37*
G36*
G01X102884Y347278D02*
G02X101000Y347391I-1004J-978D01*
G03X101036Y347982I-251J312D01*
G02X101165Y350055I1004J978D01*
G03X101169Y350676I-250J312D01*
G02X101336Y352959I891J1082D01*
G03X101358Y353630I-207J343D01*
G02X102884Y353580I802J1150D01*
G03X102862Y352909I207J-343D01*
G02X102935Y350664I-802J-1150D01*
G03X102931Y350043I250J-312D01*
G02X102920Y347869I-891J-1083D01*
G03X102884Y347278I251J-312D01*
G37*
G36*
G01X1331530Y347307D02*
G02X1331474Y345600I1083J-890D01*
G03X1330840Y345621I-325J-233D01*
G02X1330896Y347328I-1083J890D01*
G03X1331530Y347307I325J233D01*
G37*
G36*
G01X983198Y473933D02*
X958348Y498783D01*
Y508541D01*
G02X959252Y509851I1402J0D01*
G02Y510377I1377J263D01*
G02X958348Y511687I498J1310D01*
G01Y516383D01*
G03X957801Y516754I-400J-1D01*
G02Y519360I-518J1303D01*
G03X958348Y519731I147J372D01*
G01Y527168D01*
G03X957915Y527566I-400J-1D01*
G02Y530160I-109J1297D01*
G03X958348Y530558I33J399D01*
G01Y535443D01*
G02X959339Y536781I1401J-2D01*
G02Y537133I1290J176D01*
G02X958348Y538471I410J1340D01*
G01Y546400D01*
G02X959339Y547738I1401J-2D01*
G02Y548090I1290J176D01*
G02X958348Y549428I410J1340D01*
G01Y554291D01*
G03X957792Y554659I-400J0D01*
G02Y557055I-509J1198D01*
G03X958348Y557423I156J368D01*
G01Y565079D01*
G03X957865Y565470I-400J0D01*
G02Y568016I-273J1273D01*
G03X958348Y568407I83J391D01*
G01Y573243D01*
G02X958567Y573992I1401J-3D01*
G03X958440Y574547I-338J215D01*
G02X958187Y574747I737J1192D01*
G01X954998Y577935D01*
Y586874D01*
G02X955005Y587004I1401J-10D01*
G03X954458Y587413I-398J37D01*
G02X955332Y588583I-522J1301D01*
G03X955879Y588175I398J-37D01*
G02X957221Y588009I520J-1301D01*
G03X957730Y588626I236J324D01*
G02X957765Y590699I960J1021D01*
G03X957736Y591324I-265J301D01*
G02X957162Y592361I824J1133D01*
G02X955992Y593829I121J1296D01*
G02X954998Y595170I408J1341D01*
G01Y606044D01*
G02X955338Y606959I1402J0D01*
G03Y607481I-303J261D01*
G02X954998Y608396I1062J915D01*
G01Y609025D01*
G03X954451Y609396I-400J-1D01*
G02X955331Y610835I-515J1304D01*
G03X956012Y610591I398J39D01*
G01X956678Y611256D01*
X957243Y611202D01*
X957244D01*
G03X957672Y611693I39J398D01*
G02X957738Y612350I974J234D01*
G03X957750Y612378I-454J211D01*
G01X957839Y612616D01*
X959662Y614438D01*
X975657D01*
G02X976855Y613764I0J-1402D01*
G02X977869I507J-1307D01*
G02X979067Y614438I1198J-728D01*
G01X982350D01*
G02X983548Y613764I0J-1402D01*
G02X984562I507J-1307D01*
G02X985760Y614438I1198J-728D01*
G01X995773D01*
G02X997012Y613692I0J-1402D01*
G02X997870I429J-1335D01*
G02X999109Y614438I1239J-656D01*
G01X1002465D01*
G02X1003703Y613692I-1J-1401D01*
G02X1004563I430J-1334D01*
G02X1005801Y614438I1239J-655D01*
G01X1007066D01*
X1011529Y618902D01*
X1025415D01*
X1029385Y614931D01*
X1029491Y614953D01*
G02X1031149Y613295I286J-1372D01*
G01X1031127Y613189D01*
X1033854Y610462D01*
G03X1034196Y610603I142J141D01*
G01Y611005D01*
G02X1040528Y613353I3601J0D01*
G03X1041114Y613331I303J261D01*
G01X1042110Y614326D01*
X1043983D01*
G03X1044345Y614059I377J133D01*
G02X1045024Y613853I-54J-1401D01*
G02X1046073Y614326I1050J-928D01*
G01X1049202D01*
G02X1050251Y613853I-1J-1401D01*
G02X1051717I733J-1195D01*
G02X1052766Y614326I1050J-928D01*
G01X1062588D01*
G02X1063638Y613853I0J-1402D01*
G02X1065100I731J-1196D01*
G02X1066150Y614326I1050J-929D01*
G01X1069281D01*
G02X1070385Y613788I0J-1402D01*
G02X1071739I677J-1228D01*
G02X1072843Y614326I1104J-864D01*
G01X1075974D01*
G02X1077024Y613853I0J-1402D01*
G02X1078486I731J-1196D01*
G02X1079536Y614326I1050J-929D01*
G01X1082667D01*
G02X1083717Y613853I0J-1402D01*
G02X1085179I731J-1196D01*
G02X1086229Y614326I1050J-929D01*
G01X1095592D01*
G02X1096641Y613854I0J-1401D01*
G02X1098107I733J-1195D01*
G02X1099156Y614326I1049J-929D01*
G01X1099409D01*
G02X1100787Y612672I0J-1401D01*
G03X1101575I394J-73D01*
G02X1102953Y614326I1378J253D01*
G01X1106095D01*
G02X1107479Y612711I-1J-1402D01*
G03X1108269I395J-62D01*
G02X1109653Y614326I1385J213D01*
G01X1112568D01*
G02X1113946Y612672I0J-1401D01*
G03X1114062Y612311I394J-73D01*
G01X1114063Y612310D01*
G03X1114617I277J289D01*
G01X1114618Y612311D01*
G03X1114734Y612672I-278J288D01*
G02X1116112Y614326I1378J253D01*
G01X1117758D01*
G02X1119086Y612478I0J-1401D01*
G03X1119186Y612064I380J-127D01*
G02X1119306Y611930I-982J-1000D01*
G03X1119618Y611927I157J124D01*
G02X1119740Y612058I1085J-888D01*
G03X1119846Y612477I-274J292D01*
G02X1121174Y614326I1328J448D01*
G01X1122827D01*
G02X1124211Y612711I-1J-1402D01*
G03X1125001I395J-62D01*
G02X1126385Y614326I1385J213D01*
G01X1129520D01*
G02X1130904Y612711I-1J-1402D01*
G03X1131694I395J-62D01*
G02X1133078Y614326I1385J213D01*
G01X1136220D01*
G02X1137598Y612672I0J-1401D01*
G03X1138386I394J-73D01*
G02X1139764Y614326I1378J253D01*
G01X1140041D01*
G02X1141045Y613902I0J-1401D01*
G03X1141619I287J279D01*
G02X1142623Y614326I1004J-977D01*
G01X1142906D01*
G02X1144290Y612711I-1J-1402D01*
G03X1145080I395J-62D01*
G02X1146464Y614326I1385J213D01*
G01X1149380D01*
G02X1150758Y612672I0J-1401D01*
G03X1150874Y612311I394J-73D01*
G01X1150875Y612310D01*
G03X1151429I277J289D01*
G01X1151430Y612311D01*
G03X1151546Y612672I-278J288D01*
G02X1152924Y614326I1378J253D01*
G01X1154570D01*
G02X1155898Y612478I0J-1401D01*
G03X1155998Y612064I380J-127D01*
G02X1156118Y611930I-982J-1000D01*
G03X1156430Y611927I157J124D01*
G02X1156552Y612058I1085J-888D01*
G03X1156658Y612477I-274J292D01*
G02X1157986Y614326I1328J448D01*
G01X1159638D01*
G02X1161022Y612711I-1J-1402D01*
G03X1161812I395J-62D01*
G02X1163196Y614326I1385J213D01*
G01X1166331D01*
G02X1167715Y612711I-1J-1402D01*
G03X1168505I395J-62D01*
G02X1169889Y614326I1385J213D01*
G01X1173031D01*
G02X1174409Y612672I0J-1401D01*
G03X1175197I394J-73D01*
G02X1176575Y614326I1378J253D01*
G01X1179717D01*
G02X1181101Y612711I-1J-1402D01*
G03X1181891I395J-62D01*
G02X1183275Y614326I1385J213D01*
G01X1186191D01*
G02X1187569Y612672I0J-1401D01*
G03X1187685Y612311I394J-73D01*
G01X1187686Y612310D01*
G03X1188240I277J289D01*
G01X1188241Y612311D01*
G03X1188357Y612672I-278J288D01*
G02X1189735Y614326I1378J253D01*
G01X1191381D01*
G02X1192709Y612478I0J-1401D01*
G03X1192809Y612064I380J-127D01*
G02X1192929Y611930I-982J-1000D01*
G03X1193241Y611927I157J124D01*
G02X1193363Y612058I1085J-888D01*
G03X1193469Y612477I-274J292D01*
G02X1194797Y614326I1328J448D01*
G01X1196449D01*
G02X1197833Y612711I-1J-1402D01*
G03X1198623I395J-62D01*
G02X1200007Y614326I1385J213D01*
G01X1203142D01*
G02X1204526Y612711I-1J-1402D01*
G03X1205316I395J-62D01*
G02X1206700Y614326I1385J213D01*
G01X1209842D01*
G02X1211220Y612672I0J-1401D01*
G03X1212008I394J-73D01*
G02X1213386Y614326I1378J253D01*
G01X1216528D01*
G02X1217912Y612711I-1J-1402D01*
G03X1218702I395J-62D01*
G02X1220086Y614326I1385J213D01*
G01X1223002D01*
G02X1224380Y612672I0J-1401D01*
G03X1224496Y612311I394J-73D01*
G01X1224497Y612310D01*
G03X1225051I277J289D01*
G01X1225052Y612311D01*
G03X1225168Y612672I-278J288D01*
G02X1226546Y614326I1378J253D01*
G01X1228192D01*
G02X1229520Y612478I0J-1401D01*
G03X1229620Y612064I380J-127D01*
G02X1229740Y611930I-982J-1000D01*
G03X1230052Y611927I157J124D01*
G02X1230174Y612058I1085J-888D01*
G03X1230280Y612477I-274J292D01*
G02X1231608Y614326I1328J448D01*
G01X1233260D01*
G02X1234644Y612711I-1J-1402D01*
G03X1235434I395J-62D01*
G02X1236818Y614326I1385J213D01*
G01X1239953D01*
G02X1241337Y612711I-1J-1402D01*
G03X1242127I395J-62D01*
G02X1243511Y614326I1385J213D01*
G01X1246646D01*
G02X1248030Y612711I-1J-1402D01*
G03X1248820I395J-62D01*
G02X1250204Y614326I1385J213D01*
G01X1251463D01*
G03X1251825Y614058I378J132D01*
G02X1252502Y613853I-55J-1401D01*
G02X1253552Y614326I1050J-929D01*
G01X1254802D01*
G03X1255172Y614035I385J109D01*
G02X1255837Y613839I-52J-1401D01*
G02X1256899Y614326I1062J-914D01*
G01X1258156D01*
G03X1258518Y614058I378J132D01*
G02X1259195Y613853I-55J-1401D01*
G02X1260245Y614326I1050J-929D01*
G01X1261503D01*
G03X1261865Y614058I378J132D01*
G02X1262542Y613853I-55J-1401D01*
G02X1263592Y614326I1050J-929D01*
G01X1264849D01*
G03X1265211Y614058I378J132D01*
G02X1265888Y613853I-55J-1401D01*
G02X1266938Y614326I1050J-929D01*
G01X1282634D01*
G02X1283814Y613680I0J-1401D01*
G03X1284092Y613621I168J108D01*
G02X1290712Y613622I3311J-5066D01*
G03X1290989Y613682I109J168D01*
G02X1292167Y614326I1179J-757D01*
G01X1293565D01*
X1295890Y612002D01*
X1325115D01*
X1327052Y610065D01*
Y574235D01*
X1325100Y572284D01*
X1325185Y572149D01*
G02X1325010Y570427I-1185J-749D01*
G03Y569873I288J-277D01*
G02X1324809Y567755I-1010J-973D01*
G03X1324758Y567143I230J-327D01*
G02X1324551Y564978I-984J-998D01*
G03Y564312I222J-333D01*
G02X1324104Y561782I-777J-1167D01*
G01X1323952Y561745D01*
Y559734D01*
X1324070Y559681D01*
G02Y557119I-570J-1281D01*
G01X1323952Y557066D01*
Y556734D01*
X1324070Y556681D01*
G02Y554119I-570J-1281D01*
G01X1323952Y554066D01*
Y553734D01*
X1324070Y553681D01*
G02Y551119I-570J-1281D01*
G01X1323952Y551066D01*
Y547235D01*
X1323555Y546839D01*
X1323811Y546583D01*
X1323946Y546671D01*
G02X1323309Y545598I761J-1177D01*
G03X1322627Y545911I-399J30D01*
G01X1318649Y541932D01*
G03X1318836Y541261I283J-283D01*
G02X1317320Y540657I-336J-1361D01*
G03X1316984Y541274I-336J217D01*
G01X1310299D01*
G03X1309900Y540854I1J-400D01*
G02X1307100I-1400J-70D01*
G03X1306701Y541274I-400J20D01*
G01X1306181D01*
X1306138Y541252D01*
G02X1304143Y542149I-638J1248D01*
G01X1304104Y542298D01*
X1275415D01*
X1273615Y540498D01*
X1100025D01*
X1099002Y539475D01*
Y537275D01*
X1097981Y537119D01*
X1097980D01*
G03X1097819Y536390I60J-396D01*
G02X1097911Y534123I-777J-1167D01*
G03X1097874Y533529I249J-314D01*
G02X1097763Y531466I-1001J-981D01*
G03X1097839Y530798I255J-309D01*
G01X1097841Y530797D01*
X1098502Y530461D01*
Y519115D01*
X1099002Y518615D01*
Y515950D01*
X1098174Y515680D01*
G03X1097944Y515117I126J-380D01*
G02X1097200Y513168I-1247J-641D01*
G03X1097400Y512397I142J-375D01*
G02X1099002Y511011I201J-1387D01*
G01Y502585D01*
X1064646Y468229D01*
Y430557D01*
X1064628Y430538D01*
Y368811D01*
X1064439Y368623D01*
X1064622Y368441D01*
X1064678Y368428D01*
G02X1063086Y366498I-307J-1368D01*
G03X1062437Y366621I-366J-160D01*
G01X1061041Y365225D01*
G03X1061264Y364546I283J-283D01*
G02X1059669Y362951I-209J-1386D01*
G03X1058990Y363174I-396J-60D01*
G01X1057405Y361588D01*
X1054465D01*
G03X1054066Y361193I1J-400D01*
G02X1051262I-1402J16D01*
G03X1050863Y361588I-400J-5D01*
G01X1047705D01*
G03X1047306Y361193I1J-400D01*
G02X1044502I-1402J16D01*
G03X1044103Y361588I-400J-5D01*
G01X1040946D01*
G03X1040547Y361193I1J-400D01*
G02X1037743I-1402J16D01*
G03X1037344Y361588I-400J-5D01*
G01X1035767D01*
X1033199Y359021D01*
G03X1033239Y358421I283J-282D01*
G02X1031273Y356455I-854J-1112D01*
G03X1030673Y356495I-318J-243D01*
G01X1030231Y356053D01*
X1030287Y355928D01*
G02X1028437Y354078I-1282J-568D01*
G01X1028312Y354134D01*
X1026748Y352570D01*
X1026740Y352559D01*
G02X1026464Y352286I-1114J851D01*
G01X1025730Y351552D01*
G03X1025927Y350878I283J-283D01*
G02X1024270Y349870I-302J-1369D01*
G03X1023884Y350372I-386J102D01*
G01X1023130D01*
G02X1021360I-885J1088D01*
G01X1020606D01*
G03X1020220Y349870I0J-400D01*
G02X1017510I-1355J-361D01*
G03X1017124Y350372I-386J102D01*
G01X1016631D01*
X1015801Y349542D01*
G03X1015951Y348882I283J-283D01*
G02X1014430Y348483I-466J-1322D01*
G03X1014129Y349146I-301J263D01*
G01X1013466D01*
X1013418Y349017D01*
G02X1010792I-1313J492D01*
G01X1010744Y349146D01*
X1010081D01*
G03X1009780Y348483I0J-400D01*
G02X1007670I-1055J-923D01*
G03X1007369Y349146I-301J263D01*
G01X1007082D01*
X1005927Y350302D01*
X1005251D01*
X1004096Y349146D01*
X1003519D01*
G02X1002199Y350078I1J1402D01*
G02X1001731I-234J1382D01*
G02X1000411Y349146I-1321J470D01*
G01X999222D01*
X998943Y349692D01*
G03X998229I-357J-183D01*
G01X997950Y349146D01*
X996760D01*
G02X995440Y350078I1J1402D01*
G02X994972I-234J1382D01*
G02X993652Y349146I-1321J470D01*
G01X993187D01*
X993139Y349017D01*
G02X990629Y350239I-1313J492D01*
G01X990711Y350373D01*
X987774Y353309D01*
Y354700D01*
X988579Y354982D01*
G03Y355738I-133J378D01*
G01X987774Y356020D01*
Y358600D01*
X988579Y358882D01*
G03Y359638I-133J378D01*
G01X987774Y359920D01*
Y361929D01*
G02Y364391I672J1231D01*
G01Y365749D01*
X987475Y366049D01*
X987473Y366050D01*
G02X987436Y366087I973J1010D01*
G01X987435Y366089D01*
X987388Y366135D01*
Y366137D01*
X987345Y366191D01*
G02Y367929I1101J869D01*
G01X987388Y367983D01*
Y367985D01*
X987435Y368031D01*
X987436Y368033D01*
G02X987473Y368070I1010J-973D01*
G01X987475Y368071D01*
X987774Y368371D01*
Y369728D01*
G02X987334Y371813I672J1231D01*
G03X987318Y372076I-158J122D01*
G02X987308Y374041I995J988D01*
G02X987061Y374644I1138J818D01*
G02X985839Y375412I28J1401D01*
G03X985586Y375507I-178J-91D01*
G02Y378111I-520J1302D01*
G03X985838Y378207I73J186D01*
G02X986034Y378497I1250J-634D01*
G03Y379023I-301J263D01*
G02X985688Y379944I1055J922D01*
G01Y385503D01*
X984498Y386692D01*
Y425648D01*
X983574Y426574D01*
X983198Y426949D01*
Y432443D01*
G03X982522Y432732I-400J-1D01*
G02Y445614I-6144J6441D01*
G03X983198Y445903I276J290D01*
G01Y473933D01*
G37*
G36*
G01X65595Y349131D02*
G02X65121Y347275I755J-1181D01*
G03X64555Y347419I-350J-193D01*
G02X62757Y347664I-755J1181D01*
G03X62113Y347597I-298J-267D01*
G02X61943Y349236I-1213J702D01*
G03X62587Y349303I298J267D01*
G02X65029Y349275I1213J-703D01*
G03X65595Y349131I350J193D01*
G37*
G36*
G01X1644113Y349711D02*
G02X1642615Y349988I-963J-1019D01*
G03X1642737Y350648I-153J370D01*
G02X1644235Y350371I963J1019D01*
G03X1644113Y349711I153J-370D01*
G37*
G36*
G01X1338882Y350962D02*
G02X1338203Y349606I715J-1206D01*
G03X1337601Y349907I-398J-43D01*
G02X1338280Y351263I-715J1206D01*
G03X1338882Y350962I398J43D01*
G37*
G36*
G01X1588979Y351651D02*
G02X1588978Y350340I1239J-656D01*
G03X1588271I-354J-187D01*
G02X1588272Y351651I-1239J656D01*
G03X1588979I354J187D01*
G37*
G36*
G01X1508004Y354215D02*
G02X1506340Y354241I-850J-1115D01*
G03X1506350Y354885I-232J326D01*
G02X1506271Y357050I850J1115D01*
G03Y357650I-265J300D01*
G02X1508129I929J1050D01*
G03Y357050I265J-300D01*
G02X1508014Y354859I-929J-1050D01*
G03X1508004Y354215I232J-326D01*
G37*
G36*
G01X1539469Y360376D02*
G02X1537451Y360293I-969J-1013D01*
G03X1537428Y360848I-299J266D01*
G02X1537462Y362906I969J1013D01*
G03X1537418Y363536I-267J298D01*
G02X1539135Y363655I782J1164D01*
G03X1539179Y363025I267J-298D01*
G02X1539446Y360931I-782J-1164D01*
G03X1539469Y360376I299J-266D01*
G37*
G36*
G01X1343883Y360683D02*
G02X1343419Y359074I848J-1116D01*
G03X1342802Y359252I-375J-141D01*
G02X1343266Y360861I-848J1116D01*
G03X1343883Y360683I375J141D01*
G37*
G36*
G01X102517Y361294D02*
G02X100999Y361304I-767J-1174D01*
G03X101003Y361976I-215J337D01*
G02X102521Y361966I767J1174D01*
G03X102517Y361294I215J-337D01*
G37*
G36*
G01X1357712Y360037D02*
G02X1357659Y361417I-1246J643D01*
G03X1358354Y361443I340J210D01*
G02X1358407Y360063I1246J-643D01*
G03X1357712Y360037I-340J-210D01*
G37*
G36*
G01X1608786Y360618D02*
G02X1608339Y361947I-1374J277D01*
G03X1608996Y362167I265J300D01*
G02X1609443Y360838I1374J-277D01*
G03X1608786Y360618I-265J-300D01*
G37*
G36*
G01X60254Y363533D02*
G02X59542Y362141I680J-1226D01*
G03X58951Y362443I-397J-48D01*
G02X59663Y363835I-680J1226D01*
G03X60254Y363533I397J48D01*
G37*
G36*
G01X126608Y363251D02*
G02X124265Y361785I-1045J-935D01*
G03X123566Y361861I-370J-151D01*
G02X121424Y363913I-1235J855D01*
G03X121481Y364499I-241J319D01*
G02X123960Y366138I1119J1002D01*
G03X124590Y366012I362J170D01*
G02X126631Y363808I1010J-1112D01*
G03X126608Y363251I275J-290D01*
G37*
G36*
G01X776095Y363370D02*
G02X774172Y363300I-924J-1054D01*
G03X774136Y363894I-285J281D01*
G02X773991Y364025I932J1178D01*
G03X773406Y364015I-288J-278D01*
G02X771506Y363739I-1116J1005D01*
G03X770906Y363485I-209J-341D01*
G02X768332Y364824I-1466J325D01*
G03X768319Y365377I-295J270D01*
G02X770875Y366588I1061J1063D01*
G03X771487Y366289I398J39D01*
G02X773369Y366065I803J-1269D01*
G03X773954Y366075I288J278D01*
G02X776088Y363965I1116J-1006D01*
G03X776095Y363370I271J-294D01*
G37*
G36*
G01X679038Y364209D02*
G02X677514Y363539I-308J-1368D01*
G03X677255Y364128I-347J199D01*
G02X678779Y364798I308J1368D01*
G03X679038Y364209I347J-199D01*
G37*
G36*
G01X1381129Y371450D02*
G02X1379271I-929J-1050D01*
G03Y372050I-265J300D01*
G02X1378921Y372526I929J1050D01*
G03X1378233Y372599I-365J-164D01*
G02X1377889Y372267I-1131J828D01*
G03X1377862Y371625I224J-331D01*
G02X1375667Y370041I-883J-1089D01*
G03X1375083Y370239I-374J-142D01*
G02X1373459Y372518I-739J1191D01*
G03X1373442Y373152I-252J310D01*
G02X1375602Y374716I826J1133D01*
G03X1376231Y374526I380J123D01*
G02X1378382Y374002I872J-1098D01*
G03X1379070Y373929I365J164D01*
G02X1381129Y372050I1131J-829D01*
G03Y371450I265J-300D01*
G37*
G36*
G01X128750Y371148D02*
G02X128552Y372417I-1330J442D01*
G03X129255Y372527I323J236D01*
G02X129453Y371258I1330J-442D01*
G03X128750Y371148I-323J-236D01*
G37*
G36*
G01X764923Y374919D02*
G02X763374Y374904I-763J-1176D01*
G03X763367Y375571I-224J331D01*
G02X764916Y375586I763J1176D01*
G03X764923Y374919I224J-331D01*
G37*
G36*
G01X1333536Y375536D02*
G02X1331725Y375503I-886J-1086D01*
G03X1331714Y376114I-264J301D01*
G02X1331623Y376195I886J1087D01*
G03X1331090Y376217I-279J-287D01*
G02X1329151Y376370I-890J1083D01*
G03X1328574Y376392I-299J-266D01*
G02X1326551Y376470I-974J1008D01*
G03X1325974Y376492I-299J-266D01*
G02X1323787Y376797I-974J1008D01*
G03X1323143Y376864I-346J-200D01*
G02X1320807Y377258I-1043J936D01*
G03X1320186Y377413I-369J-155D01*
G02X1320673Y378784I-886J1087D01*
G03X1321022Y378697I196J41D01*
G02X1321181Y378859I1077J-898D01*
G03X1321171Y379471I-262J302D01*
G02X1323113Y381479I883J1089D01*
G03X1323738Y381506I302J263D01*
G02X1324095Y381849I1135J-824D01*
G03Y382515I-222J333D01*
G02X1326062Y384424I777J1167D01*
G03X1326711Y384384I339J212D01*
G02X1328875Y384400I1089J-884D01*
G03X1329531Y384464I306J257D01*
G02X1329981Y384952I1226J-679D01*
G03Y385618I-222J333D01*
G02Y387952I777J1167D01*
G03Y388618I-222J333D01*
G02X1331535I777J1167D01*
G03Y387952I222J-333D01*
G02Y385618I-777J-1167D01*
G03Y384952I222J-333D01*
G02X1329683Y382885I-777J-1167D01*
G03X1329027Y382821I-306J-257D01*
G02X1328475Y382271I-1227J679D01*
G03X1328453Y381583I192J-351D01*
G02X1328666Y381416I-755J-1182D01*
G03X1329219Y381417I276J290D01*
G02X1331148Y381430I971J-1011D01*
G03X1331715Y381451I273J292D01*
G02X1331790Y379479I1033J-948D01*
G03X1331223Y379458I-273J-292D01*
G02X1330905Y379200I-1033J948D01*
G03X1330907Y378511I204J-344D01*
G02X1331177Y378305I-709J-1209D01*
G03X1331710Y378283I279J287D01*
G02X1333525Y376147I890J-1083D01*
G03X1333536Y375536I264J-301D01*
G37*
G36*
G01X1446261Y374114D02*
G02X1446234Y375724I-1161J786D01*
G03X1446889Y375736I323J236D01*
G02X1446916Y374126I1161J-786D01*
G03X1446261Y374114I-323J-236D01*
G37*
G36*
G01X1631819Y376659D02*
G02X1629911Y376593I-919J-1059D01*
G03X1629862Y377201I-283J283D01*
G02X1629557Y379511I938J1299D01*
G03X1629414Y380126I-310J252D01*
G02X1631156Y380607I586J1274D01*
G03X1631349Y380005I330J-226D01*
G02X1631825Y377269I-549J-1505D01*
G03X1631819Y376659I256J-308D01*
G37*
G36*
G01X752570Y380608D02*
G02X752514Y379226I1304J-745D01*
G03X751804Y379255I-363J-169D01*
G02X751860Y380637I-1304J745D01*
G03X752570Y380608I363J169D01*
G37*
G36*
G01X766290Y380798D02*
G02X764936Y381765I-1333J-435D01*
G03X765310Y382289I-6J400D01*
G02X766009Y383974I1333J435D01*
G03X766122Y384602I-181J357D01*
G02X767789Y384300I1033J948D01*
G03X767676Y383672I181J-357D01*
G02X766664Y381322I-1033J-948D01*
G03X766290Y380798I6J-400D01*
G37*
G36*
G01X117981Y382436D02*
G02X117232Y381078I648J-1243D01*
G03X116648Y381400I-399J-33D01*
G02X115528Y383963I-649J1243D01*
G03X115764Y384490I-135J377D01*
G02X117535Y383696I1299J526D01*
G03X117299Y383169I135J-377D01*
G02X117397Y382758I-1299J-527D01*
G03X117981Y382436I399J33D01*
G37*
G36*
G01X701444Y383162D02*
G02X699108Y385037I-1240J848D01*
G03Y385583I-292J273D01*
G02X699427Y387896I1096J1027D01*
G03X699467Y388553I-207J342D01*
G02X699381Y390849I924J1184D01*
G03X699360Y391458I-269J296D01*
G02X699373Y393826I931J1179D01*
G03X699408Y394429I-244J317D01*
G02X701347Y396714I1050J1075D01*
G03X701917Y396815I237J322D01*
G02X704303Y396971I1252J-829D01*
G03X704933Y397004I302J262D01*
G02X707263Y397167I1231J-861D01*
G03X707854Y397174I292J273D01*
G02X710012Y397261I1121J-1000D01*
G03X710558Y397256I276J289D01*
G02X712498Y394965I1017J-1106D01*
G03Y394335I246J-315D01*
G02Y391965I-923J-1185D01*
G03Y391335I246J-315D01*
G02X712244Y388805I-923J-1185D01*
G03X712159Y388145I178J-358D01*
G02X712231Y385946I-986J-1133D01*
G03Y385378I282J-284D01*
G02X710031Y383336I-1059J-1066D01*
G03X709442Y383357I-304J-260D01*
G02X707307Y383354I-1069J1055D01*
G03X706739I-284J-282D01*
G02X704607I-1066J1058D01*
G03X704039I-284J-282D01*
G02X702026Y383246I-1066J1058D01*
G03X701444Y383162I-252J-310D01*
G37*
G36*
G01X1457707Y385768D02*
G02X1456192Y385728I-726J-1199D01*
G03X1456174Y386401I-225J331D01*
G02X1457689Y386441I726J1199D01*
G03X1457707Y385768I225J-331D01*
G37*
G36*
G01X680301Y386975D02*
G02X678638Y386895I-777J-1167D01*
G03X678607Y387538I-253J310D01*
G02X680270Y387618I777J1167D01*
G03X680301Y386975I253J-310D01*
G37*
G36*
G01X1381928Y391468D02*
G02Y393132I-1128J832D01*
G03X1382572I322J238D01*
G02Y391468I1128J-832D01*
G03X1381928I-322J-238D01*
G37*
G36*
G01X1470953Y393463D02*
G02X1469582Y393653I-853J-1113D01*
G03X1469737Y394285I-148J371D01*
G02X1469538Y395811I1063J915D01*
G03X1469332Y396354I-360J174D01*
G02X1468706Y396871I542J1293D01*
G03X1468040I-333J-222D01*
G02X1465862Y396677I-1167J777D01*
G03X1465284I-289J-277D01*
G02Y398619I-1011J971D01*
G03X1465862I289J277D01*
G02X1468040Y398425I1011J-971D01*
G03X1468706I333J222D01*
G02X1471135Y397037I1167J-777D01*
G03X1471341Y396494I360J-174D01*
G02X1472183Y395433I-541J-1294D01*
G03X1472689Y395116I394J67D01*
G02X1471700Y393537I394J-1346D01*
G03X1471194Y393854I-394J-67D01*
G02X1471040Y393819I-387J1348D01*
G03X1470953Y393463I34J-197D01*
G37*
G36*
G01X189179Y394187D02*
G02X188651Y392603I921J-1187D01*
G03X188021Y392813I-385J-106D01*
G02X188549Y394397I-921J1187D01*
G03X189179Y394187I385J106D01*
G37*
G36*
G01X776165Y395252D02*
G02X774299Y395452I-1044J-936D01*
G03X774350Y396056I-235J324D01*
G02X774323Y396084I1068J1056D01*
G03X773760Y396105I-292J-273D01*
G02X771863Y395991I-1018J1104D01*
G03X771238Y395752I-234J-324D01*
G02X768565Y395174I-1468J318D01*
G03X767953Y395210I-321J-239D01*
G02X768065Y397136I-1093J1030D01*
G03X768677Y397100I321J239D01*
G02X770649Y397288I1093J-1030D01*
G03X771274Y397527I234J324D01*
G02X773839Y398235I1468J-318D01*
G03X774402Y398214I292J273D01*
G02X776243Y395854I1019J-1103D01*
G03X776165Y395252I219J-334D01*
G37*
G36*
G01X123112Y395933D02*
G02X121168Y395777I-881J-1217D01*
G03X121119Y396383I-283J282D01*
G02X123280Y398385I881J1217D01*
G03X123974Y398406I341J209D01*
G02X124020Y396915I1326J-705D01*
G03X123326Y396894I-341J-209D01*
G02X123063Y396539I-1325J707D01*
G03X123112Y395933I283J-282D01*
G37*
G36*
G01X1631023Y396730D02*
G02X1629663Y396770I-723J-1430D01*
G03X1629703Y397484I-159J367D01*
G02X1629491Y399767I697J1216D01*
G03X1629524Y400344I-260J304D01*
G02X1631459Y400233I1026J956D01*
G03X1631426Y399656I260J-304D01*
G02X1631025Y397445I-1026J-956D01*
G03X1631023Y396730I178J-358D01*
G37*
G36*
G01X1244795Y398467D02*
G02X1244034Y399589I-1396J-128D01*
G03X1244614Y399982I182J356D01*
G02X1245375Y398860I1396J128D01*
G03X1244795Y398467I-182J-356D01*
G37*
G36*
G01X1332810Y400430D02*
G02X1330695Y398590I-1039J-941D01*
G03X1330094Y398605I-307J-256D01*
G02X1327897Y398779I-1030J951D01*
G03X1327231I-333J-222D01*
G02X1324897I-1167J777D01*
G03X1324231I-333J-222D01*
G02X1322028Y398611I-1167J777D01*
G03X1321442Y398616I-295J-270D01*
G02X1319229Y398844I-1019J963D01*
G03X1318644Y398952I-341J-209D01*
G02X1316778Y401035I-857J1110D01*
G03Y401589I-288J277D01*
G02X1319048Y403176I1010J973D01*
G03X1319361Y403113I180J87D01*
G02X1319442Y403180I933J-1046D01*
G03X1319456Y403487I-121J159D01*
G02X1321567Y405301I944J1037D01*
G03X1322233I333J222D01*
G02X1324567I1167J-777D01*
G03X1325233I333J222D01*
G02X1327567I1167J-777D01*
G03X1328233I333J222D01*
G02X1330380Y405527I1167J-777D01*
G03X1330951Y405539I280J286D01*
G02X1332902Y403530I1022J-959D01*
G03X1332876Y402956I265J-300D01*
G02X1332829Y400986I-1020J-961D01*
G03X1332810Y400430I278J-288D01*
G37*
G36*
G01X1466215Y401593D02*
G02Y403147I-1167J777D01*
G03X1466881I333J222D01*
G02Y401593I1167J-777D01*
G03X1466215I-333J-222D01*
G37*
G36*
G01X175831Y403321D02*
G02X175784Y404774I-1222J688D01*
G03X176467Y404797I335J219D01*
G02X178913Y404794I1222J-688D01*
G03X179603Y404780I349J195D01*
G02X179575Y403364I1196J-732D01*
G03X178885Y403378I-349J-195D01*
G02X176514Y403344I-1196J731D01*
G03X175831Y403321I-335J-219D01*
G37*
G36*
G01X1198437Y406752D02*
G02X1196898Y406240I-408J-1341D01*
G03X1196692Y406859I-323J236D01*
G02X1198231Y407371I408J1341D01*
G03X1198437Y406752I323J-236D01*
G37*
G36*
G01X105766Y407114D02*
G02X104251Y407757I-1248J-835D01*
G03X104512Y408373I-71J394D01*
G02X106070Y410678I1249J835D01*
G03X106543Y411155I83J391D01*
G02X107701Y410009I1467J324D01*
G03X107228Y409532I-83J-391D01*
G02X106027Y407730I-1467J-324D01*
G03X105766Y407114I71J-394D01*
G37*
G36*
G01X1467549Y405996D02*
G02Y407550I-1167J777D01*
G03X1468215I333J222D01*
G02Y405996I1167J-777D01*
G03X1467549I-333J-222D01*
G37*
G36*
G01X1513552Y408921D02*
G02X1511886Y408561I-598J-1268D01*
G03X1511752Y409182I-305J259D01*
G02X1511125Y409769I599J1268D01*
G03X1510425I-350J-194D01*
G02Y411131I-1225J681D01*
G03X1511125I350J194D01*
G02X1513418Y409542I1226J-680D01*
G03X1513552Y408921I305J-259D01*
G37*
G36*
G01X1613554Y410172D02*
G02X1611843Y409975I-729J-1198D01*
G03X1611771Y410602I-280J286D01*
G02X1613482Y410799I729J1198D01*
G03X1613554Y410172I280J-286D01*
G37*
G36*
G01X1440497Y410646D02*
G02X1439003Y410566I-684J-1224D01*
G03X1438967Y411242I-231J327D01*
G02X1440461Y411322I684J1224D01*
G03X1440497Y410646I231J-327D01*
G37*
G36*
G01X798376Y410593D02*
G02X797035Y411222I-1176J-763D01*
G03X797324Y411837I-47J397D01*
G02X798834Y413962I1176J763D01*
G03X799302Y414494I95J388D01*
G02X800276Y413638I1308J506D01*
G03X799808Y413106I-95J-388D01*
G02X798665Y411208I-1308J-506D01*
G03X798376Y410593I47J-397D01*
G37*
G36*
G01X1395067Y411723D02*
G02X1392890Y413473I-1167J778D01*
G03Y414027I-288J277D01*
G02X1393952Y416401I1010J973D01*
G03X1394357Y416888I14J400D01*
G02X1397076Y416819I1368J305D01*
G03X1397337Y416332I386J-107D01*
G02X1397910Y414027I-437J-1332D01*
G03Y413473I288J-277D01*
G02X1395733Y411723I-1010J-972D01*
G03X1395067I-333J-222D01*
G37*
G36*
G01X1535647Y412859D02*
G02X1535604Y414219I-1247J641D01*
G03X1536303Y414241I343J205D01*
G02X1536869Y414825I1246J-642D01*
G03Y415525I-194J350D01*
G02X1536325Y416069I681J1225D01*
G03X1535625I-350J-194D01*
G02Y417431I-1225J681D01*
G03X1536325I350J194D01*
G02X1538775I1225J-681D01*
G03X1539475I350J194D01*
G02X1541925I1225J-681D01*
G03X1542625I350J194D01*
G02X1545075I1225J-681D01*
G03X1545775I350J194D01*
G02Y416069I1225J-681D01*
G03X1545075I-350J-194D01*
G02X1544531Y415525I-1225J681D01*
G03Y414825I194J-350D01*
G02X1542625Y412919I-681J-1225D01*
G03X1541925I-350J-194D01*
G02X1539475I-1225J681D01*
G03X1538775I-350J-194D01*
G02X1536346Y412881I-1225J681D01*
G03X1535647Y412859I-343J-205D01*
G37*
G36*
G01X1516725Y412919D02*
G02Y414281I-1225J681D01*
G03X1517425I350J194D01*
G02X1517969Y414825I1225J-681D01*
G03Y415525I-194J350D01*
G02X1519331I681J1225D01*
G03Y414825I194J-350D01*
G02X1517425Y412919I-681J-1225D01*
G03X1516725I-350J-194D01*
G37*
G36*
G01X1526197Y412959D02*
G02X1524289Y414836I-1247J641D01*
G03X1524300Y415535I-189J353D01*
G02X1525661Y415514I699J1215D01*
G03X1525650Y414815I189J-353D01*
G02X1526154Y414319I-700J-1215D01*
G03X1526853Y414341I343J205D01*
G02X1526896Y412981I1247J-641D01*
G03X1526197Y412959I-343J-205D01*
G37*
G36*
G01X149308Y415575D02*
G02X147577Y415801I-1008J-975D01*
G03X147658Y416422I-206J343D01*
G02X149389Y416196I1008J975D01*
G03X149308Y415575I206J-343D01*
G37*
G36*
G01X621202Y416175D02*
G02X620188Y417547I-1402J25D01*
G03X620698Y417925I110J385D01*
G02X620711Y418092I1402J-25D01*
G03X620412Y418292I-198J28D01*
G02X618977Y420701I-712J1208D01*
G03X618973Y421389I-206J343D01*
G02X621066Y422810I707J1211D01*
G03X621537Y422477I396J60D01*
G02X622612Y422243I263J-1377D01*
G03X622924Y422368I116J163D01*
G02X622969Y422540I1376J-268D01*
G03X622794Y422802I-190J63D01*
G02X623345Y425530I107J1398D01*
G03X623855Y425796I127J379D01*
G02X626596Y425274I1345J-396D01*
G03X626996Y424838I398J-36D01*
G02X627621Y424693I4J-1402D01*
G03X628199Y425062I178J358D01*
G02X628979Y423843I1401J38D01*
G03X628401Y423474I-178J-358D01*
G02X627920Y422378I-1401J-39D01*
G03X627862Y421837I262J-302D01*
G02X626470Y419624I-1125J-837D01*
G03X625996Y419268I-76J-393D01*
G02X624051Y418110I-1396J132D01*
G03X623497Y417777I-156J-368D01*
G02X621712Y416553I-1397J123D01*
G03X621202Y416175I-110J-385D01*
G37*
G36*
G01X52868Y415596D02*
G02X52769Y417119I-1223J685D01*
G03X53439Y417163I321J239D01*
G02X53538Y415640I1223J-685D01*
G03X52868Y415596I-321J-239D01*
G37*
G36*
G01X1510425Y416069D02*
G02X1508519Y417975I-1225J681D01*
G03Y418675I-194J350D01*
G02Y421125I681J1225D01*
G03Y421825I-194J350D01*
G02Y424275I681J1225D01*
G03Y424975I-194J350D01*
G02Y427425I681J1225D01*
G03Y428125I-194J350D01*
G02X1508000Y428625I680J1226D01*
G03X1507303Y428602I-342J-207D01*
G02X1507259Y429974I-1244J647D01*
G03X1507956Y429997I342J207D01*
G02X1510425Y430031I1244J-647D01*
G03X1511125I350J194D01*
G02X1513575I1225J-681D01*
G03X1514275I350J194D01*
G02X1516725I1225J-681D01*
G03X1517425I350J194D01*
G02X1519331Y428125I1225J-681D01*
G03Y427425I194J-350D01*
G02Y424975I-681J-1225D01*
G03Y424275I194J-350D01*
G02X1517425Y422369I-681J-1225D01*
G03X1516725I-350J-194D01*
G02X1516181Y421825I-1225J681D01*
G03Y421125I194J-350D01*
G02X1514275Y419219I-681J-1225D01*
G03X1513575I-350J-194D01*
G02X1513031Y418675I-1225J681D01*
G03Y417975I194J-350D01*
G02X1511125Y416069I-681J-1225D01*
G03X1510425I-350J-194D01*
G37*
G36*
G01X1317793Y417890D02*
G02X1315810Y419873I-973J1010D01*
G03Y420427I-288J277D01*
G02X1317830I1010J973D01*
G03Y419873I288J-277D01*
G02X1317914Y419777I-1012J-970D01*
G03X1318226I156J125D01*
G02X1320417Y419773I1094J-877D01*
G03X1321060Y419796I313J249D01*
G02X1321233Y420003I1157J-791D01*
G03X1321267Y420535I-281J285D01*
G02X1323322Y422429I1104J864D01*
G03X1323881Y422445I271J294D01*
G02X1325879Y422462I1007J-975D01*
G03X1326434Y422453I282J284D01*
G02X1328372Y422426I955J-1027D01*
G03X1328927Y422420I281J285D01*
G02X1330862Y422410I962J-1020D01*
G03X1331416I277J288D01*
G02X1333362I973J-1010D01*
G03X1333916I277J288D01*
G02X1335965Y420501I973J-1010D01*
G03X1335982Y419968I306J-257D01*
G02X1333904Y418087I-1014J-968D01*
G03X1333297Y418088I-304J-260D01*
G02X1331263Y417994I-1062J916D01*
G03X1330709I-277J-288D01*
G02X1328753Y418004I-973J1010D01*
G03X1328198Y418010I-281J-285D01*
G02X1326246Y418038I-962J1020D01*
G03X1325691Y418047I-282J-284D01*
G02X1323784Y418045I-955J1027D01*
G03X1323225Y418029I-271J-294D01*
G02X1321120Y418131I-1008J975D01*
G03X1320477Y418108I-313J-249D01*
G02X1318347Y417890I-1157J792D01*
G03X1317793I-277J-288D01*
G37*
G36*
G01X123483Y419851D02*
G02X121934Y420567I-1241J-652D01*
G03X122200Y421143I-88J390D01*
G02X123749Y420427I1241J652D01*
G03X123483Y419851I88J-390D01*
G37*
G36*
G01X1468429Y419934D02*
G02Y421488I-1167J777D01*
G03X1469095I333J222D01*
G02Y419934I1167J-777D01*
G03X1468429I-333J-222D01*
G37*
G36*
G01X1525631Y424275D02*
G02X1524269I-681J-1225D01*
G03Y424975I-194J350D01*
G02Y427425I681J1225D01*
G03Y428125I-194J350D01*
G02X1525631I681J1225D01*
G03Y427425I194J-350D01*
G02Y424975I-681J-1225D01*
G03Y424275I194J-350D01*
G37*
G36*
G01X1532475Y422369D02*
G02X1530569Y424275I-1225J681D01*
G03Y424975I-194J350D01*
G02Y427425I681J1225D01*
G03Y428125I-194J350D01*
G02X1532475Y430031I681J1225D01*
G03X1533175I350J194D01*
G02X1535625I1225J-681D01*
G03X1536325I350J194D01*
G02X1538775I1225J-681D01*
G03X1539475I350J194D01*
G02X1541381Y428125I1225J-681D01*
G03Y427425I194J-350D01*
G02Y424975I-681J-1225D01*
G03Y424275I194J-350D01*
G02X1539475Y422369I-681J-1225D01*
G03X1538775I-350J-194D01*
G02X1536325I-1225J681D01*
G03X1535625I-350J-194D01*
G02X1533175I-1225J681D01*
G03X1532475I-350J-194D01*
G37*
G36*
G01X1668413Y425845D02*
G02X1667107Y425878I-684J-1224D01*
G03X1667125Y426585I-177J358D01*
G02X1666997Y428952I684J1224D01*
G03X1666962Y429627I-231J326D01*
G02X1668461Y429706I687J1222D01*
G03X1668496Y429031I231J-326D01*
G02X1668431Y426552I-687J-1222D01*
G03X1668413Y425845I177J-358D01*
G37*
G36*
G01X1612829Y430595D02*
G02X1611286Y430758I-894J-1080D01*
G03X1611356Y431420I-185J354D01*
G02X1611473Y433667I894J1080D01*
G03Y434333I-222J333D01*
G02X1613027I777J1167D01*
G03Y433667I222J-333D01*
G02X1612899Y431257I-777J-1167D01*
G03X1612829Y430595I185J-354D01*
G37*
G36*
G01X746945Y431271D02*
G02X745331Y431282I-815J-1141D01*
G03X745336Y431936I-228J329D01*
G02X746950Y431925I815J1141D01*
G03X746945Y431271I228J-329D01*
G37*
G36*
G01X1510425Y434969D02*
G02X1508519Y436875I-1225J681D01*
G03Y437575I-194J350D01*
G02Y440025I681J1225D01*
G03Y440725I-194J350D01*
G02X1510425Y442631I681J1225D01*
G03X1511125I350J194D01*
G02X1513575I1225J-681D01*
G03X1514275I350J194D01*
G02X1516181Y440725I1225J-681D01*
G03Y440025I194J-350D01*
G02X1516725Y439481I-681J-1225D01*
G03X1517425I350J194D01*
G02X1519331Y437575I1225J-681D01*
G03Y436875I194J-350D01*
G02X1517425Y434969I-681J-1225D01*
G03X1516725I-350J-194D01*
G02X1514275I-1225J681D01*
G03X1513575I-350J-194D01*
G02X1511125I-1225J681D01*
G03X1510425I-350J-194D01*
G37*
G36*
G01X1525631Y436875D02*
G02X1524269I-681J-1225D01*
G03Y437575I-194J350D01*
G02X1525631I681J1225D01*
G03Y436875I194J-350D01*
G37*
G36*
G01X1532475Y434969D02*
G02X1530569Y436875I-1225J681D01*
G03Y437575I-194J350D01*
G02X1532475Y439481I681J1225D01*
G03X1533175I350J194D01*
G02X1535625I1225J-681D01*
G03X1536325I350J194D01*
G02X1538775I1225J-681D01*
G03X1539475I350J194D01*
G02X1541381Y437575I1225J-681D01*
G03Y436875I194J-350D01*
G02X1540019I-681J-1225D01*
G03Y437575I-194J350D01*
G02X1539475Y438119I681J1225D01*
G03X1538775I-350J-194D01*
G02X1536325I-1225J681D01*
G03X1535625I-350J-194D01*
G02X1535081Y437575I-1225J681D01*
G03Y436875I194J-350D01*
G02X1533175Y434969I-681J-1225D01*
G03X1532475I-350J-194D01*
G37*
G36*
G01X1665691Y439085D02*
G02X1663833I-929J-1050D01*
G03Y439685I-265J300D01*
G02X1663985Y441902I929J1050D01*
G03Y442568I-222J333D01*
G02X1665539I777J1167D01*
G03Y441902I222J-333D01*
G02X1665812Y441664I-777J-1167D01*
G03X1666412I300J265D01*
G02X1668435Y441745I1050J-929D01*
G03X1668989I277J288D01*
G02X1670527Y439452I973J-1010D01*
G03X1670330Y438907I161J-366D01*
G02X1667769Y438789I-1254J-626D01*
G03X1667411Y439334I-373J145D01*
G02X1666412Y439806I51J1401D01*
G03X1665812I-300J-265D01*
G02X1665691Y439685I-1050J929D01*
G03Y439085I265J-300D01*
G37*
G36*
G01X1544591Y440047D02*
G02X1543231Y440004I-641J-1247D01*
G03X1543209Y440703I-205J343D01*
G02X1543169Y443175I641J1247D01*
G03Y443875I-194J350D01*
G02X1542625Y444419I681J1225D01*
G03X1541925I-350J-194D01*
G02X1539475I-1225J681D01*
G03X1538775I-350J-194D01*
G02X1536325I-1225J681D01*
G03X1535625I-350J-194D01*
G02X1533175I-1225J681D01*
G03X1532475I-350J-194D01*
G02X1530569Y446325I-1225J681D01*
G03Y447025I-194J350D01*
G02X1532475Y448931I681J1225D01*
G03X1533175I350J194D01*
G02X1535625I1225J-681D01*
G03X1536325I350J194D01*
G02X1538775I1225J-681D01*
G03X1539475I350J194D01*
G02X1541381Y447025I1225J-681D01*
G03Y446325I194J-350D01*
G02X1541925Y445781I-681J-1225D01*
G03X1542625I350J194D01*
G02X1544531Y443875I1225J-681D01*
G03Y443175I194J-350D01*
G02X1544569Y440746I-681J-1225D01*
G03X1544591Y440047I205J-343D01*
G37*
G36*
G01X1286805Y441007D02*
G02X1285559Y441448I-1036J-945D01*
G03X1285795Y442113I-60J395D01*
G02X1286911Y444458I1036J945D01*
G03X1287320Y444964I24J399D01*
G02X1288591Y443938I1351J374D01*
G03X1288182Y443432I-24J-399D01*
G02X1287041Y441672I-1351J-374D01*
G03X1286805Y441007I60J-395D01*
G37*
G36*
G01X1725270Y442675D02*
G02X1723640Y442799I-901J-1074D01*
G03X1723689Y443447I-208J342D01*
G02X1723579Y443550I902J1073D01*
G03X1723001I-289J-277D01*
G02Y445492I-1011J971D01*
G03X1723579I289J277D01*
G02X1725804Y445222I1011J-971D01*
G03X1726476Y445191I346J201D01*
G02X1726406Y443679I1144J-811D01*
G03X1725734Y443710I-346J-201D01*
G02X1725319Y443323I-1144J811D01*
G03X1725270Y442675I208J-342D01*
G37*
G36*
G01X1602290Y445654D02*
G02X1601199Y444330I310J-1367D01*
G03X1600710Y444733I-400J13D01*
G02X1601801Y446057I-310J1367D01*
G03X1602290Y445654I400J-13D01*
G37*
G36*
G01X1523025Y444419D02*
G02Y445781I-1225J681D01*
G03X1523725I350J194D01*
G02X1524269Y446325I1225J-681D01*
G03Y447025I-194J350D01*
G02X1525631I681J1225D01*
G03Y446325I194J-350D01*
G02X1523725Y444419I-681J-1225D01*
G03X1523025I-350J-194D01*
G37*
G36*
G01X1504495Y446629D02*
G02X1503769Y448171I-1370J297D01*
G03X1504344Y448442I184J355D01*
G02X1505070Y446900I1370J-297D01*
G03X1504495Y446629I-184J-355D01*
G37*
G36*
G01X1887393Y446949D02*
G02X1887357Y449106I-1063J1061D01*
G03X1887913Y449115I273J292D01*
G02X1890220Y448896I1063J-1061D01*
G03X1890882I331J224D01*
G02X1893369Y448897I1244J-842D01*
G03X1894032I332J224D01*
G02Y447211I1243J-843D01*
G03X1893369I-331J-224D01*
G02X1890882Y447212I-1243J843D01*
G03X1890220I-331J-224D01*
G02X1887949Y446958I-1244J842D01*
G03X1887393Y446949I-273J-292D01*
G37*
G36*
G01X1918547Y447249D02*
G02X1916039Y447364I-1225J681D01*
G03X1915340Y447424I-366J-162D01*
G02X1915456Y448766I-1167J777D01*
G03X1916155Y448706I366J162D01*
G02X1918547Y448611I1167J-776D01*
G03X1919247I350J194D01*
G02Y447249I1225J-681D01*
G03X1918547I-350J-194D01*
G37*
G36*
G01X1516725Y447569D02*
G02X1514777Y449451I-1225J681D01*
G03X1514753Y450151I-205J343D01*
G02X1516112Y450199I636J1249D01*
G03X1516136Y449499I205J-343D01*
G02X1516725Y448931I-636J-1249D01*
G03X1517425I350J194D01*
G02X1517996Y449490I1225J-681D01*
G03X1518002Y450195I-186J354D01*
G02X1519896Y452114I673J1230D01*
G03X1520590Y452108I349J196D01*
G02X1520579Y450711I1210J-708D01*
G03X1519885Y450717I-349J-196D01*
G02X1519329Y450185I-1210J708D01*
G03X1519323Y449480I186J-354D01*
G02X1517425Y447569I-673J-1230D01*
G03X1516725I-350J-194D01*
G37*
G36*
G01X1933562Y449612D02*
G02X1933835Y451960I-3243J1567D01*
G03X1934464Y451726I390J87D01*
G02X1934228Y449696I836J-1126D01*
G03X1933562Y449612I-306J-258D01*
G37*
G36*
G01X1887331Y453292D02*
G02X1887255Y455349I-1131J988D01*
G03X1887837Y455371I281J285D01*
G02X1890212Y455225I1131J-988D01*
G03X1890874I331J224D01*
G02Y453541I1244J-842D01*
G03X1890212I-331J-224D01*
G02X1887913Y453314I-1244J842D01*
G03X1887331Y453292I-281J-285D01*
G37*
G36*
G01X1842797Y453544D02*
G02Y455098I-1167J777D01*
G03X1843463I333J222D01*
G02Y453544I1167J-777D01*
G03X1842797I-333J-222D01*
G37*
G36*
G01X22025Y453470D02*
G02X20075Y455751I-1027J1096D01*
G03Y456381I-246J315D01*
G02X20300Y458896I923J1185D01*
G03X20326Y459590I-185J354D01*
G02X22145Y461962I792J1276D01*
G03X22691I273J292D01*
G02X24745I1027J-1096D01*
G03X25291I273J292D01*
G02X27368Y461940I1027J-1096D01*
G03X27930Y461942I280J286D01*
G02X29686Y459546I1058J-1066D01*
G03X29660Y458852I185J-354D01*
G02X29791Y456391I-792J-1276D01*
G03Y455761I246J-315D01*
G02X27818Y453502I-923J-1185D01*
G03X27256Y453500I-280J-286D01*
G02X25171Y453470I-1058J1066D01*
G03X24625I-273J-292D01*
G02X22571I-1027J1096D01*
G03X22025I-273J-292D01*
G37*
G36*
G01X620740Y465350D02*
G02X619173Y464668I-340J-1360D01*
G03X618920Y465250I-350J194D01*
G02X618450Y467754I340J1360D01*
G03X618479Y468385I-231J327D01*
G02X620200Y468306I911J1065D01*
G03X620171Y467675I231J-327D01*
G02X620487Y465932I-911J-1065D01*
G03X620740Y465350I350J-194D01*
G37*
G36*
G01X-5187Y465904D02*
G02X-6694Y466110I-913J-1064D01*
G03X-6603Y466776I-169J362D01*
G02X-5096Y466570I913J1064D01*
G03X-5187Y465904I169J-362D01*
G37*
G36*
G01X1916064Y467856D02*
G02Y466143I1234J-857D01*
G03X1915407I-329J-228D01*
G02X1912920Y466172I-1234J857D01*
G03X1912252I-334J-220D01*
G02Y467828I-1253J828D01*
G03X1912920I334J220D01*
G02X1915407Y467856I1253J-828D01*
G03X1916064I328J228D01*
G37*
G36*
G01X635060Y468734D02*
G02X633769Y469117I-1027J-1096D01*
G03X633980Y469794I-71J393D01*
G02X635277Y472157I987J996D01*
G03X635761Y472605I88J390D01*
G02X636838Y471442I1387J204D01*
G03X636354Y470994I-88J-390D01*
G02X635252Y469417I-1387J-204D01*
G03X635060Y468734I82J-391D01*
G37*
G36*
G01X1617774Y469168D02*
G02Y470722I-1167J777D01*
G03X1618440I333J222D01*
G02Y469168I1167J-777D01*
G03X1617774I-333J-222D01*
G37*
G36*
G01X1911277Y473167D02*
G02X1909723I-777J-1167D01*
G03Y473833I-222J333D01*
G02X1911277I777J1167D01*
G03Y473167I222J-333D01*
G37*
G36*
G01X607004Y472635D02*
G02X604816Y474367I-1179J759D01*
G03Y474921I-288J277D01*
G02X606836I1010J973D01*
G03Y474367I288J-277D01*
G02X606961Y474216I-1015J-967D01*
G03X607622Y474234I324J235D01*
G02X607665Y472653I1178J-759D01*
G03X607004Y472635I-324J-235D01*
G37*
G36*
G01X66784Y476042D02*
G02X65693Y476991I-1334J-432D01*
G03X66143Y477508I70J394D01*
G02X67234Y476559I1334J432D01*
G03X66784Y476042I-70J-394D01*
G37*
G36*
G01X1841917Y474947D02*
G02Y476501I-1167J777D01*
G03X1842583I333J222D01*
G02Y474947I1167J-777D01*
G03X1841917I-333J-222D01*
G37*
G36*
G01X4127Y479339D02*
G02X3786Y477842I973J-1009D01*
G03X3133Y477991I-375J-139D01*
G02X931Y478326I-973J1009D01*
G03X229I-351J-192D01*
G02Y479674I-1229J674D01*
G03X931I351J192D01*
G02X1566Y480270I1229J-674D01*
G03X1661Y480932I-170J362D01*
G02X3795Y482698I928J1051D01*
G03X4483I344J204D01*
G02Y481268I1206J-715D01*
G03X3795I-344J-204D01*
G02X3183Y480713I-1206J715D01*
G03X3088Y480051I170J-362D01*
G02X3474Y479488I-928J-1050D01*
G03X4127Y479339I375J139D01*
G37*
G36*
G01X90883Y478991D02*
G02X90312Y480342I-1386J210D01*
G03X90940Y480608I232J325D01*
G02X93029Y481611I1386J-210D01*
G03X93622Y481881I200J346D01*
G02X94295Y480399I1376J-269D01*
G03X93702Y480129I-200J-346D01*
G02X91511Y479257I-1376J269D01*
G03X90883Y478991I-232J-325D01*
G37*
G36*
G01X1599811Y478370D02*
G02Y480080I-1111J855D01*
G03X1600446I317J243D01*
G02Y478370I1111J-855D01*
G03X1599811I-317J-243D01*
G37*
G36*
G01X1570800Y480997D02*
G02X1569699Y482101I-1375J-271D01*
G03X1570170Y482571I78J392D01*
G02X1571271Y481467I1375J271D01*
G03X1570800Y480997I-78J-392D01*
G37*
G36*
G01X626879Y481069D02*
G02X626695Y482403I-1310J499D01*
G03X627390Y482499I321J239D01*
G02X627574Y481165I1310J-499D01*
G03X626879Y481069I-321J-239D01*
G37*
G36*
G01X32607Y481958D02*
G02X32544Y483698I-1130J830D01*
G03X33170Y483720I304J259D01*
G02X33233Y481980I1130J-830D01*
G03X32607Y481958I-304J-259D01*
G37*
G36*
G01X1688120Y485257D02*
G02X1686836Y485235I-621J-1257D01*
G03X1686823Y485946I-190J352D01*
G02X1688416Y488213I620J1257D01*
G03X1688970I277J288D01*
G02X1690893Y488234I973J-1010D01*
G03X1691448Y488247I271J294D01*
G02X1691493Y486228I995J-988D01*
G03X1690938Y486215I-271J-294D01*
G02X1688970Y486193I-995J988D01*
G03X1688416I-277J-288D01*
G02X1688107Y485968I-972J1010D01*
G03X1688120Y485257I190J-352D01*
G37*
G36*
G01X1457304Y487077D02*
G02X1455890Y487072I-703J-1213D01*
G03X1455888Y487763I-203J345D01*
G02X1457302Y487768I703J1213D01*
G03X1457304Y487077I203J-345D01*
G37*
G36*
G01X657051Y487930D02*
G02X655110Y487893I-951J-1030D01*
G03X655099Y488470I-282J283D01*
G02X657402Y489870I951J1030D01*
G03X658073Y489694I386J105D01*
G02X657718Y488339I997J-985D01*
G03X657047Y488515I-386J-105D01*
G02X657040Y488507I-1056J917D01*
G03X657051Y487930I282J-283D01*
G37*
G36*
G01X1642122Y488168D02*
G02X1641073Y489131I-1341J-408D01*
G03X1641539Y489639I83J391D01*
G02X1642588Y488676I1341J408D01*
G03X1642122Y488168I-83J-391D01*
G37*
G36*
G01X729744Y488062D02*
G02X729310Y489399I-1371J294D01*
G03X729968Y489613I267J298D01*
G02X730402Y488276I1371J-294D01*
G03X729744Y488062I-267J-298D01*
G37*
G36*
G01X1641064Y497040D02*
G02X1640645Y495487I899J-1076D01*
G03X1640012Y495658I-376J-136D01*
G02X1640431Y497211I-899J1076D01*
G03X1641064Y497040I376J136D01*
G37*
G36*
G01X1590192Y495198D02*
G02Y496752I-1167J777D01*
G03X1590858I333J222D01*
G02Y495198I1167J-777D01*
G03X1590192I-333J-222D01*
G37*
G36*
G01X1268014Y497007D02*
G02X1267785Y495327I992J-991D01*
G03X1267154Y495413I-348J-197D01*
G02X1267383Y497093I-992J991D01*
G03X1268014Y497007I348J197D01*
G37*
G36*
G01X1279705Y497522D02*
G02X1279311Y495877I890J-1083D01*
G03X1278690Y496025I-366J-161D01*
G02X1279084Y497670I-890J1083D01*
G03X1279705Y497522I366J161D01*
G37*
G36*
G01X1789242Y495925D02*
G02X1786803Y496003I-1197J729D01*
G03X1786100Y496014I-354J-185D01*
G02X1786120Y497352I-1222J687D01*
G03X1786823Y497341I354J185D01*
G02X1789235Y497396I1222J-687D01*
G03X1789916Y497399I340J211D01*
G02X1789923Y495928I1197J-730D01*
G03X1789242Y495925I-340J-211D01*
G37*
G36*
G01X1728638Y501596D02*
X1733639D01*
G02X1735150Y500095I0J-1511D01*
G01Y500000D01*
X1735141Y499916D01*
G02X1733639Y498574I-1502J169D01*
G01X1729462D01*
G03X1729184Y497886I0J-400D01*
G02X1726963Y495872I-1046J-1078D01*
G03X1726422Y495952I-313J-249D01*
G02X1724064Y497224I-856J1234D01*
G03X1723649Y497634I-400J11D01*
G02X1723676Y500635I-58J1501D01*
G03X1724098Y501027I22J399D01*
G02X1727036Y501439I1502J-27D01*
G03X1727674Y501248I383J117D01*
G02X1728638Y501596I965J-1163D01*
G37*
G36*
G01X689432Y497063D02*
G02X689149Y498770I-1230J673D01*
G03X689770Y498873I270J295D01*
G02X690053Y497166I1230J-673D01*
G03X689432Y497063I-270J-295D01*
G37*
G36*
G01X1616058Y497784D02*
G02X1615976Y499474I-1158J791D01*
G03X1616613Y499505I307J256D01*
G02X1616695Y497815I1158J-791D01*
G03X1616058Y497784I-307J-256D01*
G37*
G36*
G01X55164Y501438D02*
G02X53088Y503514I-1264J812D01*
G03Y504186I-216J336D01*
G02X55164Y506262I812J1264D01*
G03X55836I336J216D01*
G02X58364I1264J-812D01*
G03X59036I336J216D01*
G02X61112Y504186I1264J-812D01*
G03Y503514I216J-336D01*
G02X59036Y501438I-812J-1264D01*
G03X58364I-336J-216D01*
G02X55836I-1264J812D01*
G03X55164I-336J-216D01*
G37*
G36*
G01X1565777Y504496D02*
G02X1564223I-777J-1167D01*
G03Y505162I-222J333D01*
G02X1565777I777J1167D01*
G03Y504496I222J-333D01*
G37*
G36*
G01X680274Y503064D02*
G02X680159Y504602I-1225J682D01*
G03X680825Y504652I317J245D01*
G02X680940Y503114I1225J-682D01*
G03X680274Y503064I-317J-245D01*
G37*
G36*
G01X1689443Y505238D02*
G02X1688723Y503689I648J-1243D01*
G03X1688148Y503957I-391J-87D01*
G02X1686391Y504342I-648J1243D01*
G03X1685759I-316J-245D01*
G02Y506058I-1109J858D01*
G03X1686391I316J245D01*
G02X1688868Y505506I1109J-858D01*
G03X1689443Y505238I391J87D01*
G37*
G36*
G01X1333988Y506103D02*
G02X1331680Y507358I-1388J197D01*
G03X1331658Y507979I-263J302D01*
G02X1333892Y509263I842J1121D01*
G03X1334470Y508952I398J46D01*
G02X1334543Y506413I630J-1252D01*
G03X1333988Y506103I-159J-367D01*
G37*
G36*
G01X1534568Y510040D02*
G02X1532953Y510276I-972J-1010D01*
G03X1533047Y510920I-183J356D01*
G02X1534662Y510684I972J1010D01*
G03X1534568Y510040I183J-356D01*
G37*
G36*
G01X1401610Y509379D02*
G02X1401229Y511321I-1165J780D01*
G03X1401785Y511430I224J332D01*
G02X1404117Y511427I1165J-780D01*
G03X1404783I333J222D01*
G02X1406073Y512047I1167J-777D01*
G03X1406502Y512513I35J398D01*
G02X1407761Y511354I1382J238D01*
G03X1407332Y510888I-35J-398D01*
G02X1404783Y509873I-1382J-238D01*
G03X1404117I-333J-222D01*
G02X1402166Y509488I-1167J777D01*
G03X1401610Y509379I-224J-332D01*
G37*
G36*
G01X1910967Y509923D02*
G02Y511477I-1167J777D01*
G03X1911633I333J222D01*
G02Y509923I1167J-777D01*
G03X1910967I-333J-222D01*
G37*
G36*
G01X1296853Y509800D02*
G02X1294958Y511866I-973J1010D01*
G03X1294975Y512452I-263J301D01*
G02X1295183Y514617I985J998D01*
G03Y515283I-222J333D01*
G02Y517617I777J1167D01*
G03Y518283I-222J333D01*
G02X1296933Y520460I778J1167D01*
G03X1297487I277J288D01*
G02X1299237Y518283I972J-1010D01*
G03Y517617I222J-333D01*
G02Y515283I-777J-1167D01*
G03Y514617I222J-333D01*
G02X1299382Y512394I-777J-1167D01*
G03X1299365Y511808I263J-301D01*
G02X1297407Y509800I-985J-998D01*
G03X1296853I-277J-288D01*
G37*
G36*
G01X713293Y511963D02*
G02X713170Y513605I-1193J736D01*
G03X713816Y513654I305J259D01*
G02X713939Y512012I1193J-736D01*
G03X713293Y511963I-305J-259D01*
G37*
G36*
G01X1828753Y514383D02*
G02X1826598Y513175I-753J-1183D01*
G03X1826088Y513553I-400J-7D01*
G02X1826184Y516216I-388J1347D01*
G03X1826716Y516527I137J375D01*
G02X1827212Y517385I1384J-227D01*
G03X1827234Y517984I-254J309D01*
G02X1829088Y517915I966J1016D01*
G03X1829066Y517316I254J-309D01*
G02X1828775Y515071I-966J-1016D01*
G03X1828753Y514383I192J-351D01*
G37*
G36*
G01X1797553Y514117D02*
G02X1796878Y515400I-1400J83D01*
G03X1797483Y515719I206J343D01*
G02X1799952Y516543I1400J-83D01*
G03X1800555Y516535I305J259D01*
G02X1800531Y514693I1045J-935D01*
G03X1799928Y514701I-305J-259D01*
G02X1798158Y514436I-1045J935D01*
G03X1797553Y514117I-206J-343D01*
G37*
G36*
G01X1340419Y516938D02*
G02X1339015Y517074I-819J-1138D01*
G03X1339081Y517762I-167J363D01*
G02X1340485Y517626I819J1138D01*
G03X1340419Y516938I167J-363D01*
G37*
G36*
G01X1861057Y521367D02*
G02X1859312Y521214I-777J-1167D01*
G03X1859126Y521894I-276J290D01*
G02X1861122Y522069I728J3169D01*
G03X1861057Y521367I156J-368D01*
G37*
G36*
G01X41429Y521343D02*
G02X40279Y522116I-1318J-720D01*
G03X40675Y522705I45J397D01*
G02X41825Y521932I1318J720D01*
G03X41429Y521343I-45J-397D01*
G37*
G36*
G01X1804213Y522569D02*
G02X1802541Y526180I-3227J698D01*
G03X1803122Y526459I188J353D01*
G02X1803575Y527253I1378J-260D01*
G03X1803409Y527942I-264J301D01*
G02X1804677Y528248I343J1359D01*
G03X1804843Y527559I264J-301D01*
G02X1805726Y525521I-343J-1359D01*
G03X1806076Y524927I350J-194D01*
G02X1804931Y522716I0J-1402D01*
G03X1804213Y522569I-327J-231D01*
G37*
G36*
G01X1415993Y520663D02*
G02X1415941Y522214I-1193J736D01*
G03X1416607Y522237I325J233D01*
G02X1416659Y520686I1193J-736D01*
G03X1415993Y520663I-325J-233D01*
G37*
G36*
G01X90674Y523007D02*
G02X90451Y521273I976J-1007D01*
G03X89831Y521352I-342J-208D01*
G02X90054Y523086I-976J1007D01*
G03X90674Y523007I342J208D01*
G37*
G36*
G01X47646Y524933D02*
G02X46049Y525384I-1139J-980D01*
G03X46230Y526025I-122J381D01*
G02X47827Y525574I1139J980D01*
G03X47646Y524933I122J-381D01*
G37*
G36*
G01X1437747Y525335D02*
G02X1436550Y526531I-1389J-193D01*
G03X1437001Y526982I55J396D01*
G02X1438198Y525786I1389J193D01*
G03X1437747Y525335I-55J-396D01*
G37*
G36*
G01X717110Y526173D02*
G02X715090I-1010J-973D01*
G03Y526727I-288J277D01*
G02X715006Y526823I1012J970D01*
G03X714694I-156J-125D01*
G02X713488Y526302I-1094J877D01*
G03X713067Y525810I-32J-399D01*
G02X711816Y526881I-1363J-327D01*
G03X712237Y527373I32J399D01*
G02X712590Y528673I1363J328D01*
G03Y529227I-288J277D01*
G02Y531173I1010J973D01*
G03Y531727I-288J277D01*
G02X714573Y533710I1010J973D01*
G03X715127I277J288D01*
G02X717110Y531727I973J-1010D01*
G03Y531173I288J-277D01*
G02Y529227I-1010J-973D01*
G03Y528673I288J-277D01*
G02Y526727I-1010J-973D01*
G03Y526173I288J-277D01*
G37*
G36*
G01X1296749Y526817D02*
G02X1294883Y528867I-1089J883D01*
G03Y529533I-222J333D01*
G02Y531867I777J1167D01*
G03Y532533I-222J333D01*
G02Y534867I777J1167D01*
G03Y535533I-222J333D01*
G02X1296749Y537583I777J1167D01*
G03X1297371I311J252D01*
G02X1299237Y535533I1089J-883D01*
G03Y534867I222J-333D01*
G02Y532533I-777J-1167D01*
G03Y531867I222J-333D01*
G02Y529533I-777J-1167D01*
G03Y528867I222J-333D01*
G02X1297371Y526817I-777J-1167D01*
G03X1296749I-311J-252D01*
G37*
G36*
G01X686650Y529153D02*
G02X685186Y528521I-275J-1375D01*
G03X684925Y529125I-339J212D01*
G02X683958Y531151I275J1375D01*
G03X683803Y531684I-354J186D01*
G02X685742Y532249I697J1216D01*
G03X685897Y531716I354J-186D01*
G02X686389Y529757I-697J-1216D01*
G03X686650Y529153I339J-212D01*
G37*
G36*
G01X652317Y529423D02*
G02X650121Y531152I-1167J777D01*
G03X650110Y531707I-293J272D01*
G02X652283Y533453I991J992D01*
G03X652971Y533475I337J214D01*
G02X655151Y531770I1229J-675D01*
G03X655140Y531193I271J-294D01*
G02X652983Y529423I-990J-993D01*
G03X652317I-333J-222D01*
G37*
G36*
G01X658223Y530290D02*
G02X656473Y532467I-972J1010D01*
G03Y533133I-222J333D01*
G02X658223Y535310I778J1167D01*
G03X658777I277J288D01*
G02X660527Y533133I972J-1010D01*
G03Y532467I222J-333D01*
G02X658777Y530290I-778J-1167D01*
G03X658223I-277J-288D01*
G37*
G36*
G01X1460414Y532386D02*
G02X1460352Y530695I1086J-886D01*
G03X1459715Y530718I-327J-230D01*
G02X1459777Y532409I-1086J886D01*
G03X1460414Y532386I327J230D01*
G37*
G36*
G01X726180Y532943D02*
G02X726154Y534496I-1180J757D01*
G03X726820Y534507I329J227D01*
G02X726846Y532954I1180J-757D01*
G03X726180Y532943I-329J-227D01*
G37*
G36*
G01X1385303Y534550D02*
G02X1383533Y536707I-993J990D01*
G03Y537373I-222J333D01*
G02Y539707I777J1167D01*
G03Y540373I-222J333D01*
G02X1382961Y541923I777J1167D01*
G03X1382522Y542429I-384J110D01*
G02X1383680Y543435I-191J1389D01*
G03X1384119Y542929I384J-110D01*
G02X1385295Y542538I191J-1389D01*
G03X1385848Y542529I281J284D01*
G02X1386507Y542871I952J-1029D01*
G03X1386753Y543490I-83J391D01*
G02X1388200Y542915I1154J796D01*
G03X1387954Y542296I83J-391D01*
G02X1387577Y540333I-1154J-796D01*
G03Y539667I222J-333D01*
G02X1387632Y537372I-777J-1167D01*
G03Y536728I238J-322D01*
G02X1385856Y534564I-832J-1128D01*
G03X1385303Y534550I-269J-296D01*
G37*
G36*
G01X646927Y541517D02*
G02X645373I-777J-1167D01*
G03Y542183I-222J333D01*
G02Y544517I777J1167D01*
G03Y545183I-222J333D01*
G02X646927I777J1167D01*
G03Y544517I222J-333D01*
G02Y542183I-777J-1167D01*
G03Y541517I222J-333D01*
G37*
G36*
G01X1940620Y541958D02*
G02X1938484Y540203I-920J-1058D01*
G03X1937951Y540358I-347J-199D01*
G02X1938516Y542297I-651J1242D01*
G03X1939049Y542142I347J199D01*
G02X1939064Y542150I667J-1233D01*
G03X1939077Y542499I-91J178D01*
G02X1938408Y543537I723J1201D01*
G03X1937830Y543848I-398J-46D01*
G02X1937855Y546340I-630J1252D01*
G03X1938432Y546606I187J354D01*
G02X1940771Y545289I1368J-306D01*
G03Y544711I277J-289D01*
G02X1940642Y542579I-971J-1011D01*
G03X1940620Y541958I241J-319D01*
G37*
G36*
G01X1922965Y544767D02*
G02X1921424Y545028I-965J-1017D01*
G03X1921535Y545683I-164J365D01*
G02X1923076Y545422I965J1017D01*
G03X1922965Y544767I164J-365D01*
G37*
G36*
G01X1915609Y545971D02*
G02X1914125Y546118I-859J-1108D01*
G03X1914191Y546792I-179J358D01*
G02X1915675Y546645I859J1108D01*
G03X1915609Y545971I179J-358D01*
G37*
G36*
G01X1453744Y545652D02*
G02X1450890Y544963I-1352J-654D01*
G03X1450364Y545334I-400J-9D01*
G02X1448818Y545799I-443J1330D01*
G03X1448175Y545780I-314J-247D01*
G02X1448126Y547443I-1153J798D01*
G03X1448769Y547462I314J247D01*
G02X1451312Y546480I1153J-798D01*
G03X1451614Y546283I198J-26D01*
G02X1451651Y546305I786J-1280D01*
G03X1451814Y546827I-197J348D01*
G02X1454297Y548469I1352J654D01*
G03X1454910Y548482I301J263D01*
G02X1454949Y546552I1170J-942D01*
G03X1454336Y546539I-301J-263D01*
G02X1453907Y546174I-1171J941D01*
G03X1453744Y545652I197J-348D01*
G37*
G36*
G01X1811291Y544448D02*
G02X1811069Y546068I-1239J655D01*
G03X1811713Y546156I290J275D01*
G02X1811935Y544536I1239J-655D01*
G03X1811291Y544448I-290J-275D01*
G37*
G36*
G01X1899954Y546114D02*
G02X1898485Y546604I-1104J-864D01*
G03X1898696Y547236I-104J386D01*
G02X1898565Y547436I1103J865D01*
G03X1898010Y547591I-352J-190D01*
G02X1898535Y549464I-710J1209D01*
G03X1899090Y549309I352J190D01*
G02X1900165Y546746I710J-1209D01*
G03X1899954Y546114I104J-386D01*
G37*
G36*
G01X1857125Y548275D02*
G02X1855432Y549365I-1375J-275D01*
G03X1855733Y549833I-91J389D01*
G02X1856137Y551119I1375J275D01*
G03Y551697I-277J289D01*
G02X1856097Y551737I971J1011D01*
G03X1855519I-289J-277D01*
G02X1853146Y553039I-1011J971D01*
G03X1852678Y553526I-389J95D01*
G02X1853762Y554569I-278J1374D01*
G03X1854230Y554082I389J-95D01*
G02X1855519Y553679I278J-1374D01*
G03X1856097I289J277D01*
G02X1858119I1011J-971D01*
G03X1858697I289J277D01*
G02Y551737I1011J-971D01*
G03X1858119I-289J-277D01*
G02X1858079Y551697I-1011J971D01*
G03Y551119I277J-289D01*
G02X1857426Y548743I-971J-1011D01*
G03X1857125Y548275I91J-389D01*
G37*
G36*
G01X1849505Y549465D02*
G02X1848218Y549425I-605J-1265D01*
G03X1848195Y550135I-195J349D01*
G02X1849482Y550175I605J1265D01*
G03X1849505Y549465I195J-349D01*
G37*
G36*
G01X1836978Y550660D02*
G02X1836688Y549207I1022J-959D01*
G03X1836022Y549340I-374J-141D01*
G02X1836312Y550793I-1022J959D01*
G03X1836978Y550660I374J141D01*
G37*
G36*
G01X730541Y549008D02*
G02X728773Y551167I-991J992D01*
G03Y551833I-222J333D01*
G02Y554167I777J1167D01*
G03Y554833I-222J333D01*
G02X730541Y556992I777J1167D01*
G03X731107I283J282D01*
G02X732875Y554833I991J-992D01*
G03Y554167I222J-333D01*
G02Y551833I-777J-1167D01*
G03Y551167I222J-333D01*
G02X731107Y549008I-777J-1167D01*
G03X730541I-283J-282D01*
G37*
G36*
G01X1816995Y551606D02*
G02X1815565I-715J-1206D01*
G03Y552294I-204J344D01*
G02X1816995I715J1206D01*
G03Y551606I204J-344D01*
G37*
G36*
G01X658306Y551785D02*
G02Y553215I-1206J715D01*
G03X658994I344J204D01*
G02Y551785I1206J-715D01*
G03X658306I-344J-204D01*
G37*
G36*
G01X1755319Y553024D02*
G02X1754626Y554754I-1319J476D01*
G03X1755181Y554976I179J358D01*
G02X1757667Y555277I1319J-476D01*
G03X1758333I333J222D01*
G02Y553723I1167J-777D01*
G03X1757667I-333J-222D01*
G02X1755874Y553246I-1167J777D01*
G03X1755319Y553024I-179J-358D01*
G37*
G36*
G01X1913006Y556655D02*
G02X1912416Y555278I794J-1155D01*
G03X1911794Y555545I-395J-63D01*
G02X1912384Y556922I-794J1155D01*
G03X1913006Y556655I395J63D01*
G37*
G36*
G01X1536158Y560624D02*
G02X1533730Y558862I-1261J-817D01*
G03X1533118Y558873I-311J-252D01*
G02X1530920Y558802I-1132J987D01*
G03X1530352I-284J-282D01*
G02X1528220I-1066J1058D01*
G03X1527652I-284J-282D01*
G02X1525145Y560284I-1066J1058D01*
G03X1524714Y560794I-384J113D01*
G02X1525585Y563363I-176J1492D01*
G03X1526163Y563384I279J287D01*
G02X1528351Y563444I1122J-998D01*
G03X1528919I284J282D01*
G02X1531051I1066J-1058D01*
G03X1531619I284J282D01*
G02X1533751I1066J-1058D01*
G03X1534319I284J282D01*
G02X1536210Y563641I1066J-1058D01*
G03X1536830Y563962I220J334D01*
G02X1539013Y565251I1501J-49D01*
G03X1539591Y565660I182J356D01*
G02X1542265Y566782I1489J199D01*
G03X1542895I315J246D01*
G02X1543157Y567044I1185J-923D01*
G03Y567674I-246J315D01*
G02X1545193Y569867I922J1185D01*
G03X1545741Y569824I297J268D01*
G02X1547617Y569834I944J-1168D01*
G03X1548164Y569881I249J313D01*
G02X1550407Y567883I1121J-1000D01*
G03X1550437Y567321I299J-266D01*
G02X1550483Y565145I-1012J-1110D01*
G03X1550477Y564583I282J-284D01*
G02X1548463Y562363I-1081J-1042D01*
G03X1547916Y562316I-249J-313D01*
G02X1545725Y562262I-1121J1000D01*
G03X1545130Y562235I-285J-280D01*
G02X1542901Y562127I-1163J950D01*
G03X1542333I-284J-282D01*
G02X1539806Y562838I-1066J1058D01*
G03X1539461Y562923I-194J-47D01*
G02X1539307Y562772I-1126J994D01*
G03X1539319Y562154I260J-304D01*
G02X1536915Y561289I-934J-1176D01*
G03X1536563Y561454I-196J41D01*
G02X1536261Y561166I-1178J932D01*
G03X1536158Y560624I233J-325D01*
G37*
G36*
G01X1377031Y560781D02*
G02X1375025Y560694I-961J-1021D01*
G03X1375000Y561252I-299J266D01*
G02X1377314Y562642I961J1021D01*
G03X1377988Y562470I386J105D01*
G02X1377599Y561559I1012J-971D01*
G03X1377220Y561656I-200J9D01*
G02X1377006Y561339I-1258J619D01*
G03X1377031Y560781I299J-266D01*
G37*
G36*
G01X1744116Y562666D02*
G02X1742395Y562912I-1016J-966D01*
G03X1742484Y563534I-201J346D01*
G02X1742513Y565496I1016J966D01*
G03X1742447Y566118I-281J285D01*
G02X1742199Y568282I753J1183D01*
G03X1742155Y568881I-285J280D01*
G02X1744001Y569018I845J1119D01*
G03X1744045Y568419I285J-280D01*
G02X1744187Y566304I-845J-1119D01*
G03X1744253Y565682I281J-285D01*
G02X1744205Y563288I-753J-1182D01*
G03X1744116Y562666I201J-346D01*
G37*
G36*
G01X1934521Y563300D02*
G02X1933278Y562368I79J-1400D01*
G03X1932879Y562900I-377J133D01*
G02X1934122Y563832I-79J1400D01*
G03X1934521Y563300I377J-133D01*
G37*
G36*
G01X1417391Y563595D02*
G02X1417219Y561871I1011J-971D01*
G03X1416593Y561933I-337J-215D01*
G02X1416765Y563657I-1011J971D01*
G03X1417391Y563595I337J215D01*
G37*
G36*
G01X645967Y562523D02*
G02Y564077I-1167J777D01*
G03X646633I333J222D01*
G02X648967I1167J-777D01*
G03X649633I333J222D01*
G02X651967I1167J-777D01*
G03X652633I333J222D01*
G02Y562523I1167J-777D01*
G03X651967I-333J-222D01*
G02X649633I-1167J777D01*
G03X648967I-333J-222D01*
G02X646633I-1167J777D01*
G03X645967I-333J-222D01*
G37*
G36*
G01X1781547Y566291D02*
G02X1780064Y566043I-546J-1291D01*
G03X1779953Y566709I-267J298D01*
G02X1779579Y569057I547J1291D01*
G03Y569661I-262J302D01*
G02X1781421I921J1057D01*
G03Y569057I262J-302D01*
G02X1781436Y566957I-921J-1057D01*
G03X1781547Y566291I267J-298D01*
G37*
G36*
G01X1936343Y569287D02*
G02X1935512Y567803I557J-1287D01*
G03X1934957Y568113I-396J-57D01*
G02X1935788Y569597I-557J1287D01*
G03X1936343Y569287I396J57D01*
G37*
G36*
G01X1726471Y569981D02*
G02X1724917I-777J-1167D01*
G03Y570647I-222J333D01*
G02X1726471I777J1167D01*
G03Y569981I222J-333D01*
G37*
G36*
G01X1467630Y570975D02*
G02X1467374Y569429I1019J-963D01*
G03X1466719Y569537I-364J-166D01*
G02X1466975Y571083I-1019J963D01*
G03X1467630Y570975I364J166D01*
G37*
G36*
G01X1808834Y571292D02*
G02X1807280I-777J-1167D01*
G03Y571958I-222J333D01*
G02X1808834I777J1167D01*
G03Y571292I222J-333D01*
G37*
G36*
G01X1418208Y569756D02*
G02X1416196Y569715I-1026J955D01*
G03X1415654Y569735I-282J-284D01*
G02X1413758Y571797I-910J1066D01*
G03X1413757Y572366I-282J284D01*
G02X1415676Y574409I986J996D01*
G03X1416233Y574433I266J299D01*
G02X1416588Y574705I1019J-963D01*
G03X1416596Y575405I-190J352D01*
G02X1416340Y575591I691J1220D01*
G03X1415799I-270J-295D01*
G02Y577657I-948J1033D01*
G03X1416340I271J295D01*
G02X1418229Y577663I948J-1033D01*
G03X1418789Y577685I269J296D01*
G02X1420825Y577689I1020J-962D01*
G03X1421424Y577711I290J276D01*
G02X1423286Y575656I1085J-888D01*
G03Y574990I222J-333D01*
G02Y572656I-777J-1167D01*
G03Y571990I222J-333D01*
G02X1421493Y569857I-777J-1167D01*
G03X1420894Y569835I-290J-276D01*
G02X1418791Y569759I-1085J888D01*
G03X1418208Y569756I-290J-276D01*
G37*
G36*
G01X1764596Y575913D02*
G02X1763899Y574647I704J-1213D01*
G03X1763299Y574978I-400J-15D01*
G02X1763996Y576244I-704J1213D01*
G03X1764596Y575913I400J15D01*
G37*
G36*
G01X1386444Y573872D02*
G02X1384021Y574167I-1128J833D01*
G03X1383396Y574322I-370J-153D01*
G02X1383795Y575938I-896J1078D01*
G03X1384420Y575783I370J153D01*
G02X1386266Y575736I896J-1078D01*
G03X1386858Y575793I270J295D01*
G02X1387036Y573929I1128J-833D01*
G03X1386444Y573872I-270J-295D01*
G37*
G36*
G01X1935503Y577183D02*
G02X1935270Y578606I-1303J517D01*
G03X1935947Y578717I305J259D01*
G02X1936180Y577294I1303J-517D01*
G03X1935503Y577183I-305J-259D01*
G37*
G36*
G01X1383529Y580052D02*
G02X1381918Y580375I-1029J-952D01*
G03X1382045Y581011I-166J364D01*
G02X1383656Y580688I1029J952D01*
G03X1383529Y580052I166J-364D01*
G37*
G36*
G01X1780237Y580693D02*
G02X1778686Y580641I-736J-1193D01*
G03X1778663Y581307I-233J325D01*
G02X1778490Y583566I737J1193D01*
G03X1778401Y584232I-260J304D01*
G02X1778223Y586667I599J1268D01*
G03Y587333I-222J333D01*
G02X1779777I777J1167D01*
G03Y586667I222J-333D01*
G02X1779910Y584434I-777J-1167D01*
G03X1779999Y583768I260J-304D01*
G02X1780214Y581359I-599J-1268D01*
G03X1780237Y580693I233J-325D01*
G37*
G36*
G01X1431862Y580346D02*
G02X1429326Y580244I-1292J544D01*
G03X1428644Y580290I-355J-185D01*
G02X1428744Y581746I-1144J810D01*
G03X1429426Y581700I355J185D01*
G02X1431246Y582118I1144J-810D01*
G03X1431808Y582314I193J350D01*
G02X1432046Y582695I1293J-543D01*
G03X1431933Y583312I-301J264D01*
G02X1433644Y583625I658J1238D01*
G03X1433757Y583008I301J-264D01*
G02X1432424Y580542I-657J-1238D01*
G03X1431862Y580346I-193J-350D01*
G37*
G36*
G01X723628Y580068D02*
G02Y581732I-1128J832D01*
G03X724272I322J238D01*
G02Y580068I1128J-832D01*
G03X723628I-322J-238D01*
G37*
G36*
G01X1793330Y584687D02*
G02X1792007Y585292I-1160J-787D01*
G03X1792292Y585914I-46J398D01*
G02X1793615Y585309I1160J787D01*
G03X1793330Y584687I46J-398D01*
G37*
G36*
G01X1857775Y587634D02*
G02X1856700Y586776I225J-1384D01*
G03X1856265Y587320I-371J149D01*
G02X1857340Y588178I-225J1384D01*
G03X1857775Y587634I371J-149D01*
G37*
G36*
G01X1739937Y587832D02*
G02X1738234Y587102I-437J-1332D01*
G03X1737997Y587654I-361J172D01*
G02X1737778Y587747I437J1332D01*
G03X1737239Y587582I-186J-354D01*
G02X1736659Y589483I-1236J662D01*
G03X1737198Y589648I186J354D01*
G02X1738077Y590342I1236J-662D01*
G03X1738243Y591026I-101J387D01*
G02X1738719Y593394I936J1044D01*
G03X1738961Y593916I-131J378D01*
G02X1738950Y594891I1309J502D01*
G03X1738715Y595400I-377J135D01*
G02X1740531Y596239I496J1311D01*
G03X1740766Y595730I377J-135D01*
G02X1740730Y593095I-496J-1311D01*
G03X1740488Y592573I131J-378D01*
G02X1739536Y590714I-1309J-503D01*
G03X1739370Y590030I101J-387D01*
G02X1739700Y588384I-936J-1044D01*
G03X1739937Y587832I361J-172D01*
G37*
G36*
G01X1399147Y586309D02*
G02X1397189Y588243I-1167J777D01*
G03X1397195Y588899I-226J330D01*
G02X1396711Y589513I815J1141D01*
G03X1396056Y589644I-371J-151D01*
G02X1396359Y591157I-996J986D01*
G03X1397014Y591026I371J151D01*
G02X1399282Y590629I996J-986D01*
G03X1399942Y590528I363J168D01*
G02X1401990Y588613I1038J-942D01*
G03Y588059I288J-277D01*
G02X1399813Y586309I-1010J-972D01*
G03X1399147I-333J-222D01*
G37*
G36*
G01X1821030Y593534D02*
G02X1820316Y595039I-1376J269D01*
G03X1820897Y595315I189J353D01*
G02X1821611Y593810I1376J-269D01*
G03X1821030Y593534I-189J-353D01*
G37*
G36*
G01X1938781Y595545D02*
G02X1937060Y595624I-911J-1065D01*
G03X1937089Y596255I-231J327D01*
G02X1938810Y596176I911J1065D01*
G03X1938781Y595545I231J-327D01*
G37*
G36*
G01X1444034Y596099D02*
G02X1442396Y595368I-380J-1350D01*
G03X1442145Y595929I-359J176D01*
G02X1442075Y598607I380J1350D01*
G03X1442286Y599198I-128J379D01*
G02X1443923Y598616I1187J746D01*
G03X1443712Y598025I128J-379D01*
G02X1443783Y596660I-1187J-746D01*
G03X1444034Y596099I359J-176D01*
G37*
G36*
G01X1385675Y603929D02*
G02X1384126Y603796I-675J-1229D01*
G03X1384069Y604460I-249J313D01*
G02X1383529Y604989I675J1229D01*
G03X1382964Y605125I-347J-199D01*
G02X1383415Y607000I-764J1175D01*
G03X1383980Y606864I347J199D01*
G02X1385618Y604593I764J-1175D01*
G03X1385675Y603929I249J-313D01*
G37*
G36*
G01X1454689Y602452D02*
G02X1452656Y604378I-1061J916D01*
G03X1452616Y604988I-278J288D01*
G02X1452404Y605181I833J1128D01*
G03X1451798Y605171I-299J-266D01*
G02X1449720Y605084I-1078J896D01*
G03X1449132Y605065I-285J-280D01*
G02X1447003Y605073I-1061J916D01*
G03X1446354Y605016I-304J-259D01*
G02X1446213Y606635I-1209J710D01*
G03X1446862Y606692I304J259D01*
G02X1449071Y606964I1209J-711D01*
G03X1449659Y606983I285J280D01*
G02X1451767Y607000I1061J-916D01*
G03X1452373Y607010I299J266D01*
G02X1454451Y607097I1078J-896D01*
G03X1455039Y607116I285J280D01*
G02X1457072Y605190I1061J-916D01*
G03X1457112Y604580I278J-288D01*
G02X1455277Y602471I-835J-1126D01*
G03X1454689Y602452I-285J-280D01*
G37*
G36*
G01X713077Y605061D02*
G02X711135I-971J-1011D01*
G03Y605639I-277J289D01*
G02X711703Y607993I971J1011D01*
G03X711931Y608582I-115J383D01*
G02X714356Y609989I1201J724D01*
G03X715016Y609932I349J195D01*
G02X714882Y608367I1090J-882D01*
G03X714222Y608424I-349J-195D01*
G02X713535Y607963I-1090J882D01*
G03X713307Y607374I115J-383D01*
G02X713077Y605639I-1201J-724D01*
G03Y605061I277J-289D01*
G37*
G36*
G01X1758833Y605723D02*
G02X1757309Y605002I-283J-1373D01*
G03X1757036Y605580I-354J186D01*
G02X1758560Y606301I283J1373D01*
G03X1758833Y605723I354J-186D01*
G37*
G36*
G01X1921759Y605264D02*
G02X1921707Y603713I1141J-815D01*
G03X1921041Y603736I-341J-210D01*
G02X1921093Y605287I-1141J815D01*
G03X1921759Y605264I341J210D01*
G37*
G36*
G01X1470066Y608965D02*
G02X1468457Y608910I-765J-1175D01*
G03X1468435Y609564I-241J319D01*
G02X1470044Y609619I765J1175D01*
G03X1470066Y608965I241J-319D01*
G37*
G36*
G01X1498208Y611341D02*
G02X1496845Y611026I-408J-1341D01*
G03X1496689Y611702I-272J293D01*
G02X1495870Y612364I407J1342D01*
G03X1495205Y612417I-350J-193D01*
G02X1493487Y612019I-1105J863D01*
G03X1492913Y611675I-174J-360D01*
G02X1492125Y612993I-1401J57D01*
G03X1492699Y613337I174J360D01*
G02X1492859Y613932I1401J-58D01*
G03X1492559Y614514I-354J186D01*
G02X1493991Y615251I191J1389D01*
G03X1494291Y614669I354J-186D01*
G02X1495327Y613959I-191J-1389D01*
G03X1495992Y613906I350J193D01*
G02X1498052Y612017I1105J-862D01*
G03X1498208Y611341I272J-293D01*
G37*
G36*
G01X730778Y610078D02*
G02X728540Y609964I-1162J785D01*
G03X727928Y609966I-307J-256D01*
G02X727933Y611770I-1071J905D01*
G03X728545Y611768I307J256D01*
G02X730698Y611754I1071J-905D01*
G03X731338Y611785I308J255D01*
G02X731418Y610109I1162J-784D01*
G03X730778Y610078I-308J-255D01*
G37*
G36*
G01X1701138Y618388D02*
G02X1700272Y616314I4633J-3152D01*
G03X1699708Y616752I-392J77D01*
G02X1700430Y618481I-602J1266D01*
G03X1701138Y618388I377J132D01*
G37*
G36*
G01X1471710Y617638D02*
G02X1469044Y617506I-1354J362D01*
G03X1468485Y617720I-374J-141D01*
G02X1469151Y619458I-646J1244D01*
G03X1469710Y619244I374J141D01*
G02X1471006Y619242I646J-1244D01*
G03X1471578Y619493I185J355D01*
G02X1474057Y619968I1354J-362D01*
G03X1474712Y619987I321J239D01*
G02X1476871Y620212I1171J-770D01*
G03X1477451Y620231I281J284D01*
G02X1479164Y620535I1049J-931D01*
G03X1479714Y620712I190J352D01*
G02X1482272Y620633I1261J-612D01*
G03X1482783Y620411I370J152D01*
G02X1481982Y618567I496J-1311D01*
G03X1481471Y618789I-370J-152D01*
G02X1480311Y618865I-497J1311D01*
G03X1479761Y618688I-190J-352D01*
G02X1477512Y618305I-1261J612D01*
G03X1476932Y618286I-281J-284D01*
G02X1474758Y618380I-1049J931D01*
G03X1474103Y618361I-321J-239D01*
G02X1472282Y617889I-1171J770D01*
G03X1471710Y617638I-185J-355D01*
G37*
G36*
G01X92682Y618956D02*
G02X92719Y617218I1118J-846D01*
G03X92131Y617249I-308J-255D01*
G02X89762Y618451I-981J1001D01*
G03X89365Y618908I-396J57D01*
G02X88156Y619592I-5J1402D01*
G03X87461Y619579I-344J-205D01*
G02X87434Y620968I-1231J671D01*
G03X88129Y620981I344J205D01*
G02X90158Y621463I1231J-671D01*
G03X90734Y621594I228J328D01*
G02X92499Y619609I1218J-694D01*
G03X92321Y619021I156J-368D01*
G02X92351Y618974I-1167J-778D01*
G03X92682Y618956I172J103D01*
G37*
G36*
G01X1778267Y620296D02*
G02X1777054Y619294I133J-1396D01*
G03X1776633Y619804I-384J112D01*
G02X1777846Y620806I-133J1396D01*
G03X1778267Y620296I384J-112D01*
G37*
G36*
G01X1517373Y618790D02*
G02X1515315Y618912I-973J1010D01*
G03X1514716Y618934I-309J-254D01*
G02X1512666Y618953I-1016J966D01*
G03X1512112Y618988I-295J-270D01*
G02X1510259Y619021I-908J1068D01*
G03X1509670Y618966I-269J-296D01*
G02X1507346Y619092I-1120J844D01*
G03X1506708Y619159I-344J-204D01*
G02X1506883Y620829I-1029J952D01*
G03X1507521Y620762I344J204D01*
G02X1509495Y620845I1029J-952D01*
G03X1510084Y620900I269J296D01*
G02X1512238Y621003I1120J-844D01*
G03X1512792Y620968I295J270D01*
G02X1514785Y620788I908J-1068D01*
G03X1515384Y620766I309J254D01*
G02X1517373Y620810I1016J-966D01*
G03X1517927I277J288D01*
G02Y618790I973J-1010D01*
G03X1517373I-277J-288D01*
G37*
G36*
G01X1322260Y281218D02*
X1318751D01*
G02Y284242I0J1512D01*
G01X1322261D01*
G02X1323772Y282740I-1J-1512D01*
G01Y282645D01*
X1323762Y282561D01*
G02X1323058Y281447I-1502J170D01*
G03X1323004Y281396I108J-168D01*
G02X1322837Y281316I-160J120D01*
G03X1322763Y281305I-8J-200D01*
G02X1322260Y281218I-505J1425D01*
G37*
G36*
G01X1323733Y281174D02*
X1327244D01*
G02X1328422Y280609I0J-1511D01*
G03X1329023Y280584I311J251D01*
G02X1328993Y278685I1016J-966D01*
G03X1328390Y278679I-299J-266D01*
G02X1327243Y278152I-1147J984D01*
G01X1323734D01*
G02X1322936Y280946I0J1511D01*
G03X1322990Y280997I-108J168D01*
G02X1323157Y281077I160J-120D01*
G03X1323231Y281088I8J200D01*
G02X1323733Y281174I503J-1425D01*
G37*
G36*
G01X1498944Y114388D02*
G02X1501966Y114398I1511J0D01*
G01Y110848D01*
X1501957Y110764D01*
G02X1500456Y109422I-1502J169D01*
G03X1500091Y108859I1J-400D01*
G02X1498755Y109691I-1281J-569D01*
G03X1499098Y110267I-16J400D01*
G02X1498944Y110930I1357J665D01*
G01Y114388D01*
G37*
G36*
G01X1464743Y358094D02*
G02X1462744Y358356I-1126J-835D01*
G03X1462816Y358907I-249J313D01*
G02X1462742Y359017I1125J837D01*
G03X1462092Y359067I-343J-206D01*
G02X1461366Y361323I-1076J898D01*
G03X1461851Y361819I100J387D01*
G02X1464431Y361528I1349J381D01*
G03X1464595Y360983I351J-192D01*
G02X1464815Y358645I-653J-1241D01*
G03X1464743Y358094I249J-313D01*
G37*
G36*
G01X1559790Y361274D02*
G02X1558147Y361257I-810J-1144D01*
G03X1558140Y361906I-238J322D01*
G02X1559783Y361923I810J1144D01*
G03X1559790Y361274I238J-322D01*
G37*
G36*
G01X110785Y128096D02*
G02X110826Y129597I-1163J783D01*
G03X111501Y129578I344J205D01*
G02X111460Y128077I1163J-783D01*
G03X110785Y128096I-344J-205D01*
G37*
G36*
G01X118581Y133842D02*
G03X119128Y133859I264J300D01*
G02X121151Y131918I989J-994D01*
G03X121155Y131373I295J-270D01*
G02X119191Y129374I-1017J-965D01*
G03X118646Y129369I-270J-295D01*
G02X116626Y131310I-964J1018D01*
G03X116620Y131843I-301J263D01*
G02X118581Y133842I1032J949D01*
G37*
G54D67*
X1950000Y220787D03*
Y228661D03*
G54D46*
X44050Y504383D03*
X38389Y523748D03*
X27280Y510420D03*
X47550Y504367D03*
X50500Y205696D03*
X108174Y164127D03*
X123624Y164600D03*
X234501Y270392D03*
X224390Y258920D03*
X230800Y265200D03*
X219500Y254500D03*
X195300Y229250D03*
X219000Y335900D03*
X229100Y325900D03*
X224000Y330900D03*
X234000Y320900D03*
X214000Y340900D03*
X378577Y309795D03*
X374994Y309910D03*
X378294Y292904D03*
X605176Y487581D03*
X628589Y463649D03*
X641107Y471989D03*
X632771Y473269D03*
X629359Y469583D03*
X695790Y351300D03*
X747000Y386000D03*
X743500D03*
X750500D03*
X754000D03*
X743500Y374000D03*
X747000D03*
X754000D03*
X750500D03*
X743500Y380000D03*
X747000D03*
X818960Y202230D03*
X814849Y205001D03*
X808165Y203529D03*
X803134Y202969D03*
X792514Y201290D03*
X844400Y280500D03*
X845050Y229400D03*
X844350Y344000D03*
X844300Y312450D03*
X889586Y274278D03*
X884586Y269278D03*
X879586Y264278D03*
X874586Y259278D03*
X869586Y254278D03*
X877008Y326100D03*
X867008Y336100D03*
X872008Y331100D03*
X862008Y341100D03*
X1028136Y309815D03*
X1017083Y309910D03*
X1431664Y190213D03*
X1463369Y561763D03*
X1567425Y144373D03*
X1570020Y295340D03*
X1608099Y197125D03*
X1608280Y249234D03*
X1681586Y141438D03*
X1693586Y142438D03*
X1689785Y161180D03*
X1688207Y168972D03*
X1758324Y232657D03*
X1758000Y250000D03*
X1828390Y165600D03*
X1832000Y165800D03*
X1852654Y164624D03*
X1847654D03*
X1882669Y454368D03*
X1954271Y80449D03*
X1908400Y101010D03*
G54D60*
X1643803Y570630D03*
X1646756Y565118D03*
Y580079D03*
Y610000D03*
X1643803Y600551D03*
Y615512D03*
X1691047Y570630D03*
X1694000Y565118D03*
Y580079D03*
Y610000D03*
X1691047Y600551D03*
Y615512D03*
G54D48*
X85609Y385234D03*
X710800Y7100D03*
X705250Y8600D03*
X1301240Y476228D03*
X1490821Y73750D03*
X1573121Y120649D03*
X1591865Y237407D03*
X1569926Y308064D03*
X1576074Y359600D03*
X1590530Y610620D03*
X1598028Y256422D03*
X1600552Y261281D03*
X1640001Y370790D03*
X1644856Y604930D03*
X1640921Y605334D03*
X1680139Y99073D03*
X1695734Y164676D03*
X1663566Y213009D03*
X1687741Y466988D03*
X1759093Y9310D03*
X1761872Y-7220D03*
X1734875Y9238D03*
X1777000Y115750D03*
X1778000Y120000D03*
X1723189Y176012D03*
X1789356Y38286D03*
X1780720Y153850D03*
X1784750Y124000D03*
X1836396Y481349D03*
X1847000Y198600D03*
X1949389Y152083D03*
X1963092Y167936D03*
X1944550Y176450D03*
X1950981Y168064D03*
X1966700Y152400D03*
X251213Y646784D03*
Y652784D03*
X261125Y646784D03*
Y652784D03*
X389473Y646508D03*
Y652508D03*
X379561Y646508D03*
Y652508D03*
X448593Y652514D03*
Y646514D03*
X438681D03*
Y652514D03*
X567029Y652238D03*
Y646238D03*
X576941D03*
Y652238D03*
X951795Y652234D03*
Y646234D03*
X941883D03*
Y652234D03*
X1196198Y652206D03*
Y646206D03*
X1206110D03*
Y652206D03*
X1265293Y652264D03*
Y646264D03*
X1255381D03*
Y652264D03*
X1509696Y652236D03*
Y646236D03*
X1519608D03*
Y652236D03*
G54D69*
X1912406Y518328D03*
X1904532D03*
G54D43*
X10512Y467244D03*
X20512D03*
X50512D03*
X1884100Y493000D03*
X1894100D03*
X1891086Y592105D03*
Y612105D03*
Y602105D03*
X1904100Y493000D03*
G54D38*
X-11811Y204370D03*
Y227992D03*
Y313504D03*
Y337126D03*
X3937Y204370D03*
X-3937D03*
X3937Y227992D03*
X-3937D03*
X3937Y313504D03*
X-3937D03*
X3937Y337126D03*
X-3937D03*
G54D62*
X1779504Y-15000D03*
G54D55*
X1454902Y273603D03*
X1451754Y283053D03*
X1442304Y273603D03*
X1448603Y276753D03*
X1445454Y279902D03*
X1464351D03*
X1461300Y270400D03*
X1442303Y270454D03*
Y267303D03*
X1454902Y276753D03*
X1451753Y279902D03*
X1464351Y283052D03*
X1448603Y267304D03*
Y270454D03*
X1451753Y273603D03*
X1445454D03*
X1461202D03*
Y279902D03*
X1464351Y276753D03*
X1448603Y279902D03*
X1461202Y276753D03*
X1451753Y270454D03*
X1458052Y279902D03*
X1454902Y283052D03*
X1461400Y264700D03*
X1442304Y279902D03*
X1445454Y276753D03*
X1458052D03*
Y273603D03*
X1458102Y270402D03*
X1461202Y283052D03*
X1445454Y267304D03*
X1464424Y273676D03*
X1454902Y270454D03*
X1448603Y283053D03*
X1442304Y305098D03*
X1445454Y308247D03*
X1451753Y286202D03*
X1448603D03*
Y314546D03*
X1454928Y317723D03*
X1445427Y292526D03*
X1440910Y316693D03*
X1458052Y298798D03*
X1451753Y317696D03*
X1448603D03*
X1458400Y318500D03*
X1445454Y305098D03*
X1448603D03*
X1454902Y308247D03*
X1451753Y305098D03*
X1464351Y298798D03*
X1461202D03*
Y295649D03*
X1445528Y317772D03*
X1461202Y286202D03*
X1464351D03*
X1461202Y289351D03*
X1442303Y298799D03*
X1454902Y301948D03*
X1461202D03*
Y314546D03*
X1458052Y289351D03*
X1448603D03*
X1442304Y292499D03*
X1445427Y295624D03*
X1448577D03*
X1451751Y295649D03*
X1454902Y286202D03*
Y314546D03*
Y311397D03*
X1463610Y321329D03*
X1451753Y301948D03*
X1445454D03*
X1454902Y289351D03*
X1458052Y286202D03*
X1464351Y301948D03*
X1451753Y298798D03*
X1442304Y289350D03*
X1445454Y311397D03*
X1442304D03*
X1454902Y298798D03*
X1458052Y295649D03*
X1448603Y301948D03*
X1442304Y308247D03*
X1448603Y298798D03*
X1445454D03*
X1451753Y289351D03*
X1445454D03*
X1451753Y311397D03*
X1458052Y314546D03*
X1462776Y318200D03*
X1451753Y314546D03*
X1448603Y308247D03*
X1473798Y273603D03*
X1496030Y267665D03*
X1486397Y283052D03*
X1470649Y273603D03*
X1486574Y267127D03*
X1476948Y276753D03*
X1480098D03*
X1483247Y279902D03*
X1473798D03*
X1480098Y283052D03*
X1476948Y279902D03*
X1483247Y267304D03*
X1486397Y270454D03*
X1480098Y273603D03*
X1473798Y283052D03*
X1483247D03*
X1469829Y266909D03*
X1473798Y270454D03*
X1476948D03*
X1480098Y267304D03*
X1470649Y276753D03*
X1476948Y273603D03*
X1470649Y270454D03*
Y283052D03*
Y279902D03*
X1473798Y276753D03*
X1489546Y279902D03*
X1483247Y270454D03*
Y273603D03*
X1480098Y270454D03*
X1473798Y305098D03*
X1480098Y301948D03*
Y298798D03*
X1493400Y300800D03*
X1486397Y298798D03*
X1480098Y295649D03*
X1476948Y298798D03*
X1486397Y305098D03*
X1470649Y298798D03*
Y286202D03*
X1473798Y295649D03*
X1483247Y305098D03*
X1480098Y308247D03*
X1473798Y298798D03*
Y289351D03*
Y286202D03*
Y308247D03*
X1476948Y305098D03*
X1497509Y303120D03*
X1489546Y308247D03*
X1476948Y289351D03*
X1480098Y286202D03*
X1476948Y311397D03*
X1480098Y314546D03*
X1486397Y286202D03*
X1489546D03*
Y317696D03*
X1470649Y305098D03*
X1486397Y295649D03*
Y308247D03*
X1483247Y298798D03*
X1473798Y301948D03*
X1476948Y295649D03*
X1486396Y317696D03*
X1483247Y289351D03*
X1476948Y308247D03*
X1470649Y311397D03*
X1473798Y314546D03*
X1470649Y301948D03*
X1483247Y314546D03*
X1489546Y301948D03*
Y311397D03*
X1483247Y286202D03*
X1470649Y308247D03*
X1486397Y314546D03*
X1483247Y311397D03*
X1495300Y297300D03*
X1478524Y318900D03*
X1480098Y311397D03*
X1483247Y301948D03*
X1473798Y311397D03*
X1493500Y304400D03*
X1486397Y301948D03*
X1470649Y314546D03*
X1476948Y286202D03*
X1588176Y157600D03*
X1591950Y158250D03*
X1590569Y152464D03*
X1604000Y93925D03*
X1607442Y159585D03*
X1616891Y150137D03*
X1654686Y109191D03*
X1613741Y146987D03*
X1648387Y159585D03*
X1651536D03*
X1632574Y106107D03*
X1620100Y153300D03*
X1613741Y121790D03*
X1610591D03*
X1629489Y115491D03*
X1632615Y109215D03*
X1632638Y112341D03*
Y115491D03*
X1616890Y112341D03*
X1616848Y115449D03*
X1654673Y118628D03*
X1654685Y112341D03*
X1613741Y153286D03*
X1648387Y115491D03*
X1651536D03*
X1610591Y112341D03*
X1607441Y115491D03*
X1610591Y118640D03*
X1607441Y112341D03*
X1616891Y128089D03*
X1620040Y134388D03*
Y128089D03*
X1629489Y153286D03*
X1613741Y118640D03*
X1610645Y143783D03*
X1600148Y142262D03*
X1610591Y159585D03*
X1604292Y150137D03*
X1607401Y146947D03*
X1600182Y148562D03*
X1600148Y151711D03*
X1596427Y157975D03*
X1600490Y158010D03*
X1610591Y156436D03*
X1604169Y156407D03*
X1610591Y153286D03*
X1607441Y156436D03*
X1651536Y156435D03*
X1613741Y106042D03*
Y109191D03*
X1616890Y118641D03*
X1638938Y159585D03*
X1616900Y143880D03*
X1653111Y102240D03*
X1645237Y115491D03*
X1641770Y112340D03*
X1607441Y134389D03*
X1610591Y140688D03*
Y137538D03*
Y124939D03*
Y150137D03*
X1613741Y159585D03*
Y137538D03*
X1607441Y153286D03*
X1600900Y131900D03*
X1595390Y151778D03*
X1629489Y159585D03*
X1635788D03*
X1642087D03*
X1610591Y134389D03*
X1613741Y140688D03*
X1613690Y124990D03*
X1613741Y134389D03*
X1608000Y99400D03*
X1607441Y143837D03*
X1610591Y146987D03*
X1645237Y112341D03*
X1607441Y106042D03*
X1654638Y159685D03*
X1613741Y150137D03*
Y156436D03*
X1626339Y115491D03*
X1613741Y128089D03*
X1620040Y159585D03*
X1626339Y118651D03*
Y109191D03*
X1626300Y112300D03*
X1651536Y112341D03*
X1623200Y153100D03*
X1607441Y124939D03*
X1654685Y143837D03*
X1651536Y146988D03*
X1654686Y150138D03*
X1654685Y140687D03*
X1654686Y124940D03*
Y134389D03*
X1654685Y131239D03*
X1654686Y153288D03*
X1651536Y128089D03*
X1635750Y128240D03*
X1642087Y143837D03*
X1623190Y124940D03*
Y128089D03*
Y134388D03*
Y140687D03*
Y146987D03*
X1635788Y153286D03*
X1626339Y150136D03*
X1637363Y149484D03*
X1645237Y124940D03*
X1642087D03*
X1651536Y134388D03*
Y131239D03*
Y124939D03*
Y140687D03*
Y143837D03*
X1626364Y121765D03*
X1635788Y118640D03*
X1632639D03*
X1642150Y118660D03*
X1645237Y118640D03*
X1626313Y153312D03*
X1642087Y153286D03*
X1632638D03*
X1620100Y150200D03*
X1620040Y146987D03*
Y140687D03*
X1632639Y124940D03*
X1648393Y153280D03*
X1651532Y137534D03*
X1626339Y124940D03*
X1645237Y159585D03*
X1607441Y121790D03*
X1604292Y137538D03*
X1607239Y131358D03*
X1626339Y159585D03*
X1623189D03*
X1629400Y106131D03*
X1629487Y109280D03*
X1642084Y115494D03*
X1629489Y112341D03*
X1648387D03*
Y109191D03*
X1651536D03*
X1607441Y137538D03*
X1604292Y134388D03*
X1616890Y159585D03*
X1610591Y128089D03*
X1654686Y156436D03*
X1610591Y115491D03*
X1648386Y156435D03*
X1645237Y109191D03*
X1594565Y148720D03*
X1613741Y162735D03*
X1607441D03*
X1645237Y165884D03*
X1626339Y162735D03*
X1623276Y165798D03*
X1600490Y167459D03*
X1629489Y162735D03*
X1624966Y172936D03*
X1621942Y173237D03*
X1629489Y165884D03*
X1645151Y162649D03*
X1642101Y162749D03*
X1610591Y162735D03*
X1651536Y165884D03*
X1622217Y177809D03*
X1654685Y162735D03*
X1613741Y165885D03*
X1616891D03*
X1638938Y162735D03*
X1635788Y165885D03*
X1642088D03*
X1638938Y165884D03*
X1608731Y180819D03*
X1620006Y168956D03*
X1620041Y165885D03*
X1616890Y162735D03*
X1651536D03*
X1610591Y165885D03*
X1648320Y172690D03*
X1648326Y162674D03*
X1648386Y165885D03*
X1623250Y162611D03*
X1626339Y165884D03*
X1635788Y162735D03*
X1643662Y172609D03*
X1660985Y159585D03*
X1657835Y115491D03*
Y109191D03*
X1660985D03*
X1670434Y115491D03*
X1667284D03*
X1660985D03*
X1664135Y118640D03*
X1657835Y112341D03*
X1660985D03*
X1667238Y112387D03*
X1660985Y156435D03*
X1660986Y137538D03*
X1657835Y143837D03*
X1664186Y147038D03*
X1657835Y146987D03*
X1660985Y150137D03*
X1657836Y153288D03*
X1664135Y153286D03*
X1660985Y143837D03*
X1664136Y137538D03*
X1695236Y138938D03*
Y135788D03*
X1664135Y121790D03*
X1660985Y128089D03*
Y121790D03*
X1657835D03*
X1667284Y131239D03*
X1664135Y128089D03*
X1660985Y131239D03*
Y124939D03*
X1677386Y132788D03*
Y129638D03*
X1676886Y120038D03*
Y123188D03*
X1660985Y146987D03*
X1657836Y137538D03*
Y140688D03*
X1660985D03*
X1664134Y156436D03*
X1667348Y156500D03*
X1664135Y112341D03*
Y115491D03*
X1660985Y118640D03*
X1657835D03*
Y159585D03*
Y165884D03*
Y162735D03*
X1665063Y172608D03*
X1660985Y165885D03*
Y162735D03*
X1723314Y98550D03*
X1717014Y97550D03*
X1735914Y139500D03*
X1723314Y142650D03*
X1735989Y133250D03*
X1739064Y145800D03*
X1728789Y136250D03*
X1723264Y145850D03*
X1735989Y149050D03*
X1726539Y139450D03*
X1734989Y142750D03*
X1720164Y139500D03*
X1739064Y142650D03*
X1720164Y145800D03*
X1742214D03*
X1726464D03*
X1739064Y139500D03*
X1723314D03*
X1739064Y136350D03*
Y126900D03*
X1723314Y130050D03*
Y126900D03*
X1726464Y133200D03*
Y111150D03*
X1739064Y120600D03*
X1735914Y104850D03*
X1723314D03*
X1720164Y108000D03*
X1735914D03*
X1723314D03*
X1739064Y123750D03*
X1726464Y120600D03*
X1742214D03*
X1723314Y120601D03*
X1735912Y123750D03*
X1726464D03*
X1720164Y104850D03*
X1739064Y117450D03*
X1735914D03*
X1723314Y101700D03*
X1731789Y139450D03*
X1717014Y142650D03*
X1739064Y130050D03*
X1746189Y153250D03*
X1723314Y133200D03*
X1742214Y142650D03*
X1746189Y134777D03*
X1742214Y130050D03*
X1745768Y111743D03*
X1745363Y108004D03*
X1735914Y101700D03*
X1742214Y114300D03*
Y123750D03*
X1745364D03*
X1723314D03*
X1720164D03*
Y117451D03*
X1726464Y117450D03*
X1745364Y142650D03*
X1746189Y131624D03*
X1745364Y117450D03*
X1717014Y133200D03*
Y111150D03*
Y104850D03*
X1745500Y104500D03*
G54D53*
X1392264Y23976D03*
X1513918D03*
G54D40*
X-10236Y116969D03*
X-4725D03*
X23228Y124843D03*
X17716D03*
X-10236Y132717D03*
X-4725D03*
X6299D03*
X11811D03*
X17716Y140591D03*
X23228D03*
X-10236Y373110D03*
X-4725D03*
X23228Y380984D03*
X17716D03*
X-10236Y388858D03*
X-4725D03*
X6299D03*
X11811D03*
X17716Y396732D03*
X23228D03*
G54D57*
X1527844Y80791D03*
X1724606Y235430D03*
G54D51*
X476672Y220096D03*
X480052Y210346D03*
Y225947D03*
X476672Y235696D03*
X483432Y216196D03*
X531871Y202547D03*
X525111D03*
X483432Y212296D03*
Y231797D03*
Y239596D03*
X501452Y337096D03*
X531871Y331247D03*
X525111Y323446D03*
X531871D03*
X525111Y327347D03*
X528491Y333196D03*
X521731Y329296D03*
X518352Y335147D03*
X521731Y340996D03*
X525111Y319547D03*
X528491Y321496D03*
Y325396D03*
Y329296D03*
X525111Y331247D03*
X521731Y333196D03*
Y337096D03*
X535251Y344896D03*
X542011D03*
Y340996D03*
Y337096D03*
X538631Y331247D03*
Y327347D03*
X535251Y340996D03*
X538631Y342947D03*
X542011Y333196D03*
Y329296D03*
Y325396D03*
X538631Y323446D03*
X535251Y337096D03*
X528491Y340996D03*
X531871Y339047D03*
Y342947D03*
X528491Y344896D03*
X491312Y342947D03*
X484552Y389747D03*
X494692Y399496D03*
X491312Y393647D03*
X487932Y383896D03*
X484552Y374146D03*
X511592Y362447D03*
X514972Y368296D03*
X508212Y364396D03*
X498072Y378047D03*
X494692Y379996D03*
Y387796D03*
X518352Y350747D03*
Y354647D03*
X511592Y358547D03*
X514972Y360496D03*
Y364396D03*
X511592Y366347D03*
X508212Y368296D03*
Y372197D03*
X504832Y374146D03*
X501452Y376096D03*
X498072Y381947D03*
X494692Y383896D03*
X518352Y346847D03*
X521731Y352696D03*
X511592Y354647D03*
X498072Y374146D03*
X528491Y387796D03*
X521731D03*
Y391696D03*
X518352Y393647D03*
X514972Y395597D03*
X511592Y389747D03*
X528491Y379996D03*
Y383896D03*
X525111Y385847D03*
X521731Y383896D03*
X525111Y389747D03*
X521731Y395597D03*
X514972Y391696D03*
Y387796D03*
X528491Y376096D03*
X531871Y381947D03*
X535251Y348796D03*
X538631Y346847D03*
Y354647D03*
Y358547D03*
Y362447D03*
X531871D03*
Y366347D03*
X535251Y372197D03*
Y379996D03*
X538631Y350747D03*
X542011Y356596D03*
X535251Y360496D03*
X531871Y358547D03*
X535251Y364396D03*
Y368296D03*
X538631Y374146D03*
X531871Y378047D03*
X525111Y346847D03*
X528491Y348796D03*
Y352696D03*
X487932Y356596D03*
X491312Y354647D03*
X511592Y401447D03*
X508212Y383896D03*
X514972Y376096D03*
X504832Y401446D03*
X552151Y331247D03*
Y335147D03*
Y342947D03*
X548771Y344896D03*
Y333196D03*
X552151Y339047D03*
X555531Y340996D03*
X545391Y327347D03*
Y339047D03*
X562591Y340996D03*
X558911Y339047D03*
X555531Y344896D03*
X562591Y337096D03*
X555531D03*
X552151Y346847D03*
X548771Y387796D03*
X552151Y385847D03*
X555531Y352696D03*
Y348796D03*
X552151Y354647D03*
X558911Y350747D03*
X559211Y366347D03*
X555531Y379996D03*
X552151Y381947D03*
X558911Y354647D03*
X552151Y362447D03*
X545391Y350747D03*
X548771Y348796D03*
X947887Y324160D03*
X937747Y322209D03*
X930987D03*
X941127Y324160D03*
G54D66*
X1892720Y525415D03*
X1900595D03*
X1894689Y518328D03*
X1908469Y525415D03*
X1916343D03*
X1924217D03*
G54D58*
X1627642Y-14488D03*
X1647327Y-315D03*
X1667012Y-14488D03*
X1969291Y486064D03*
Y497874D03*
G54D26*
X1630386Y413942D03*
X1634400Y412900D03*
X1630120Y418887D03*
X1621347Y415297D03*
X1603000Y422971D03*
X1611418D03*
X1673800Y201070D03*
X1681352Y196092D03*
X1469000Y345850D03*
X-19210Y162529D03*
X-17014Y455604D03*
X-17200Y510800D03*
X-17302Y506798D03*
X-13500Y486400D03*
X-14800Y526100D03*
X-18160Y522609D03*
X-19802Y476738D03*
X-19783Y481286D03*
X-16186Y519304D03*
X-12600Y578900D03*
X-14971Y540000D03*
X-17500Y574000D03*
X8660Y27274D03*
X43960Y20572D03*
X-3560Y34620D03*
X-10850Y30800D03*
X2871Y22791D03*
X19964Y18793D03*
X2934Y26933D03*
X16550Y18300D03*
X602Y30502D03*
X25827Y-16958D03*
X8988Y58267D03*
X-1750Y43320D03*
X-1920Y47290D03*
X11925Y74867D03*
X11864Y71294D03*
X11539Y39927D03*
X11500Y43400D03*
X-1470Y63910D03*
X37037Y138425D03*
X39109Y154901D03*
X5120Y276058D03*
X2269Y273532D03*
X48550Y301650D03*
X1500Y295000D03*
X47100Y327000D03*
X49200Y340650D03*
X10365Y461602D03*
X37550Y425400D03*
X40965Y429434D03*
X2450Y460000D03*
X-9600Y526100D03*
X-6650Y487800D03*
X-5680Y524570D03*
X47800Y487600D03*
X3354Y517143D03*
X6748Y517021D03*
X-6200Y505400D03*
X-6676Y501800D03*
X10932Y523601D03*
X14700Y517000D03*
X-9900Y486400D03*
X-2430Y524340D03*
X-7360Y512000D03*
X-6712Y515731D03*
X-2083Y513704D03*
X-4350Y482100D03*
X-900Y482300D03*
X22491Y500618D03*
X2350Y469650D03*
X-8318Y542216D03*
X-8200Y578600D03*
X-3100Y533991D03*
X-2500Y569500D03*
X-10947Y544117D03*
X-4300Y558400D03*
X-4100Y554400D03*
X1439Y546583D03*
X1539Y550183D03*
Y586183D03*
X1439Y582583D03*
X-9287Y531604D03*
X-6566Y568363D03*
X-9291Y535201D03*
X-9283Y571324D03*
X-4500Y594000D03*
X93500Y-18000D03*
X82300Y-16600D03*
X53382Y-1173D03*
X52744Y-4368D03*
X74386Y-18439D03*
X71172Y-18486D03*
X87091Y-16391D03*
X52389Y-14258D03*
X60035Y7508D03*
X51090Y8080D03*
X54307Y-8051D03*
X76106Y89337D03*
X86600Y94000D03*
X70980Y97166D03*
X82046Y90043D03*
X98420Y112198D03*
X99250Y160370D03*
X104424Y110833D03*
X87200Y152374D03*
X91913Y121318D03*
X77790Y121030D03*
X79670Y132300D03*
X75660Y152380D03*
X78950Y152810D03*
X91306Y157194D03*
X61800Y191600D03*
X76143Y183019D03*
X61356Y181000D03*
X61256Y186000D03*
X90831Y184982D03*
X86731Y189148D03*
X107700Y211040D03*
X104820Y202100D03*
X102507Y211047D03*
X79300Y272300D03*
X84000Y272500D03*
X99500Y223800D03*
X97200Y265000D03*
X99758Y240300D03*
X91600Y278700D03*
X70700Y330349D03*
X93500Y289000D03*
X71500Y298000D03*
X66000Y292700D03*
X76800Y298000D03*
X76900Y292600D03*
X66500Y303400D03*
X76800D03*
X58400Y314600D03*
X53000Y323500D03*
X52804Y333247D03*
X61300Y328600D03*
X93500Y285000D03*
X93400Y296000D03*
X53400Y298100D03*
X79410Y331636D03*
X84000Y324542D03*
X53100Y327000D03*
X64700Y310525D03*
X69125Y310625D03*
X84300Y305700D03*
Y310700D03*
X66300Y285850D03*
X72904Y284898D03*
X84300Y289000D03*
X82050Y283951D03*
X77103Y283900D03*
X88000Y343900D03*
X88600Y302997D03*
X94360Y335210D03*
X82500Y341400D03*
X103500Y304700D03*
X104600Y316602D03*
X103500Y308500D03*
X84866Y294213D03*
X79400Y325400D03*
X84300Y299000D03*
X87400Y337200D03*
X103200Y330190D03*
X88840Y324740D03*
X53100Y315000D03*
X53250Y302800D03*
X102322Y295478D03*
X66900Y322000D03*
X60400Y355750D03*
X57395Y366795D03*
X55500Y371700D03*
X109500Y370000D03*
X61914Y368731D03*
X57800Y376100D03*
X60565Y380131D03*
X65000Y383000D03*
X74800Y379700D03*
X80200D03*
X62600Y375100D03*
X87900Y347500D03*
X93712Y380507D03*
X97472Y380934D03*
X90518Y388828D03*
X54900Y389400D03*
X110452Y407092D03*
X79100Y347000D03*
X61041Y351737D03*
X74800Y383114D03*
X66016Y468350D03*
X106392Y527413D03*
X59731Y480066D03*
X71050Y478670D03*
X86100Y505200D03*
X102236Y614167D03*
X132959Y71500D03*
X130313Y92757D03*
X163391Y71500D03*
X160431Y92757D03*
X163477Y87714D03*
X132959D03*
X157084Y71900D03*
X153738Y92757D03*
X157084Y87714D03*
X126580Y71500D03*
X123620Y92757D03*
X126666Y87714D03*
X150391Y71900D03*
X147045Y92757D03*
X150391Y87714D03*
X169770Y71500D03*
X167124Y92757D03*
X169770Y87714D03*
X119892Y84700D03*
X117600Y193805D03*
X122542Y214019D03*
X150000Y194850D03*
Y199850D03*
X162800Y195600D03*
X162788Y200650D03*
X124340Y197750D03*
X122203Y246675D03*
X122400Y278671D03*
X125563Y234316D03*
X125663Y230716D03*
X125563Y227116D03*
Y259116D03*
X125663Y262716D03*
X125563Y266316D03*
X122361Y342649D03*
X122493Y310633D03*
X125663Y294716D03*
X125563Y298316D03*
Y291116D03*
Y323116D03*
X125663Y326716D03*
X122473Y374716D03*
X153392Y404000D03*
X167640Y404842D03*
X118220Y360500D03*
X125563Y355116D03*
X125663Y358716D03*
Y390716D03*
X125563Y387116D03*
Y394316D03*
X151909Y413267D03*
X148409Y422239D03*
X153392Y407500D03*
X167680Y408440D03*
X157862Y416012D03*
X150650Y409860D03*
X130313Y518157D03*
X160431D03*
X163477Y513114D03*
X160431Y528899D03*
X132959Y513114D03*
X130313Y528899D03*
X153738Y518157D03*
Y528899D03*
X157084Y513114D03*
X123620Y518157D03*
Y528899D03*
X126666Y513114D03*
X147045Y518157D03*
X150391Y513114D03*
X147045Y528899D03*
X167124Y518157D03*
Y528899D03*
X169770Y513114D03*
X119892Y510100D03*
X116927Y517900D03*
X132959Y534700D03*
X163391D03*
X157084Y535100D03*
X126580Y534700D03*
X150391Y535100D03*
X169770Y534700D03*
X119892Y536983D03*
X193895Y71900D03*
X190549Y92757D03*
X193895Y87714D03*
X187202Y71900D03*
X183856Y92757D03*
X187202Y87714D03*
X206581Y71500D03*
X203935Y92757D03*
X206581Y87714D03*
X230706Y71900D03*
X227360Y92757D03*
X230706Y87714D03*
X200202Y71500D03*
X197242Y92757D03*
X200288Y87714D03*
X224013Y71900D03*
X220667Y92761D03*
X224013Y87714D03*
X234053Y92757D03*
Y112327D03*
X206600Y372400D03*
X190549Y518157D03*
X193895Y513114D03*
X190549Y528899D03*
X183856Y518157D03*
Y528899D03*
X187202Y513114D03*
X203935Y518157D03*
X206581Y513114D03*
X203935Y528899D03*
X227360Y518157D03*
Y528899D03*
X230706Y513114D03*
X197242Y518157D03*
X200288Y513114D03*
X197242Y528899D03*
X220667Y518161D03*
Y528899D03*
X224013Y513114D03*
X234053Y518157D03*
Y528899D03*
X233292Y498500D03*
X193895Y535100D03*
X187202D03*
X206581Y534700D03*
X230706Y535100D03*
X200202Y534700D03*
X224013Y535100D03*
X243392Y71500D03*
X240746Y92757D03*
X243392Y87714D03*
X267517Y71900D03*
X264171Y92757D03*
X267517Y87714D03*
X237013Y71500D03*
X237099Y87714D03*
X260824Y71900D03*
X257478Y92757D03*
X260824Y87714D03*
X280203Y71500D03*
X277557Y92757D03*
X280203Y87714D03*
X270864Y92757D03*
X273824Y71500D03*
X273910Y87714D03*
X294289Y92757D03*
X240746Y112327D03*
X243392Y106934D03*
X264171Y112327D03*
X267517Y107284D03*
X237099D03*
X257478Y112327D03*
X260824Y107284D03*
X277557Y112327D03*
X280203Y106934D03*
X270864Y112327D03*
X273910Y107284D03*
X294889Y110927D03*
X274619Y205210D03*
X271239Y207159D03*
X277999Y218860D03*
X281379Y216909D03*
X284759Y218860D03*
X294899Y216909D03*
Y220809D03*
X288139D03*
X284759Y203260D03*
Y211060D03*
X294899Y205210D03*
Y209109D03*
X281379Y205210D03*
Y209109D03*
X291519Y203260D03*
Y211060D03*
X288139Y201309D03*
Y213009D03*
Y205210D03*
Y209109D03*
X267859D03*
X277999Y199360D03*
X274619Y201309D03*
X271239Y203260D03*
X294899Y197409D03*
X274619Y209109D03*
X264179Y257860D03*
X281379Y228610D03*
X288139Y224709D03*
X271239Y257860D03*
X284759Y230559D03*
X288139Y228610D03*
X277999Y222760D03*
X264092Y242260D03*
X271239D03*
X264179Y261760D03*
X271239D03*
X264179Y246160D03*
X271239D03*
Y250060D03*
X277999Y226660D03*
X271239Y253960D03*
X267859Y248109D03*
X281379Y224709D03*
X284759Y222760D03*
X267859Y255909D03*
X281379Y267609D03*
X277999Y238360D03*
X281379Y236409D03*
X284759Y250060D03*
X288139Y248109D03*
X277999Y242260D03*
X284759Y238360D03*
X288139Y263709D03*
X277999Y257860D03*
X281379Y255909D03*
X284759Y269560D03*
X288139Y267609D03*
X277999Y261760D03*
X284759Y257860D03*
X281379Y248109D03*
X288139Y244209D03*
Y259809D03*
X277999Y246160D03*
X288139Y240309D03*
X277999Y265660D03*
X284759Y261760D03*
X281379Y244209D03*
X284759Y242260D03*
X281379Y263709D03*
X294899Y232509D03*
Y236409D03*
Y252009D03*
Y255909D03*
Y240309D03*
Y259809D03*
X239778Y274478D03*
X271239Y277360D03*
Y281260D03*
X267392Y276000D03*
X267359Y279310D03*
Y283209D03*
X288139Y279310D03*
X284759Y281260D03*
X291519D03*
X277999D03*
X274619Y279310D03*
Y283209D03*
X288139D03*
X281379Y279310D03*
Y283209D03*
X294899D03*
Y279310D03*
X267859Y271509D03*
X264179Y273460D03*
X274619Y271509D03*
X294899D03*
Y267609D03*
X291519Y273460D03*
X277999D03*
X271239Y335860D03*
X264179D03*
X271239Y331960D03*
X264179D03*
X271239Y343660D03*
Y339760D03*
X267859Y345609D03*
Y337809D03*
X288139Y333909D03*
X281379Y330009D03*
Y341709D03*
X277999Y339760D03*
X288139Y330009D03*
X284759Y328060D03*
Y339760D03*
X277999Y335860D03*
Y331960D03*
X284759Y335860D03*
X281379Y333909D03*
X288139Y337809D03*
X294899Y341709D03*
Y337809D03*
X271239Y320260D03*
Y324160D03*
X270939Y316160D03*
X267359Y318309D03*
X267859Y326110D03*
X267392Y322000D03*
X270892Y304660D03*
Y311960D03*
Y300760D03*
Y308560D03*
Y292959D03*
Y289060D03*
Y285500D03*
Y296860D03*
X281379Y302709D03*
X288139D03*
X294899D03*
X291519Y304660D03*
X281379Y306609D03*
Y310509D03*
X288139Y306609D03*
Y310509D03*
X284759Y304660D03*
X294899Y310509D03*
Y306609D03*
X281379Y287109D03*
X288139Y291009D03*
X284759Y289060D03*
X291519D03*
Y296860D03*
X288139Y298809D03*
X274619Y306609D03*
Y310509D03*
X277999Y304660D03*
X274619Y302709D03*
Y298809D03*
Y294909D03*
X277999Y289060D03*
X274619Y287109D03*
Y291009D03*
X277999Y296860D03*
X288139Y287109D03*
X281379Y298809D03*
Y294909D03*
X288139D03*
X284759Y296860D03*
X281379Y291009D03*
X294899Y298809D03*
Y294909D03*
Y291009D03*
Y287109D03*
X291519Y312460D03*
X284759D03*
X277999D03*
X274619Y314409D03*
X294899D03*
X281379D03*
X288139D03*
X274619Y318309D03*
X291519Y320260D03*
X284759D03*
X288139Y322209D03*
X281379D03*
X291519Y324160D03*
X277999D03*
X294899Y326109D03*
Y330009D03*
X288139Y372909D03*
X281379Y369010D03*
Y380709D03*
X277999Y378760D03*
X288139Y369010D03*
X284759Y367060D03*
Y378760D03*
X277999Y374860D03*
X294899Y376809D03*
Y380709D03*
X264179Y351460D03*
X271239D03*
X264179Y347560D03*
X271239D03*
X284759Y374860D03*
X277999Y370959D03*
X288139Y376809D03*
X281379Y372909D03*
X284759Y359260D03*
X281379Y361209D03*
X288139Y349509D03*
X284759Y347560D03*
X277999Y355360D03*
Y359260D03*
X284759Y386560D03*
Y394359D03*
X294899Y388509D03*
Y392410D03*
X281379Y388509D03*
Y392410D03*
X291519Y386560D03*
Y394359D03*
X288139Y353409D03*
X281379Y349509D03*
X284759Y355360D03*
X288139Y388509D03*
X277999Y351460D03*
X288139Y396309D03*
Y357309D03*
Y384609D03*
X281379Y353409D03*
X288139Y392410D03*
X294899Y361209D03*
Y365109D03*
Y345609D03*
Y357309D03*
X274619Y400209D03*
X281379D03*
X271239Y394359D03*
X267859Y392410D03*
X294899Y400209D03*
X271239Y398260D03*
X277999D03*
X274619Y396309D03*
X240746Y518157D03*
Y528899D03*
X243392Y513114D03*
X264171Y518157D03*
Y528899D03*
X267517Y513114D03*
X237099D03*
X257478Y518157D03*
Y528899D03*
X260824Y513114D03*
X277557Y518157D03*
X280203Y513114D03*
X277557Y528899D03*
X270864Y518157D03*
X273910Y513114D03*
X270864Y528899D03*
X294289Y518157D03*
Y528899D03*
X239592Y495900D03*
X243392Y495694D03*
X264171Y498487D03*
X267584Y493919D03*
X236892Y490800D03*
X257478Y498487D03*
X260824Y493744D03*
X277557Y498644D03*
X280203Y493244D03*
X271092Y498644D03*
X273992Y493744D03*
X294392Y493100D03*
X243392Y534700D03*
X267517Y535100D03*
X237013Y534700D03*
X260824Y535100D03*
X280203Y534700D03*
X273824D03*
X304328Y71900D03*
X300982Y92757D03*
X304328Y87714D03*
X297635Y71900D03*
Y87714D03*
X300982Y109700D03*
X304178Y107684D03*
X297635Y105084D03*
X298279Y214960D03*
X308418Y216909D03*
Y220809D03*
X305039Y214960D03*
X301659Y213009D03*
Y216909D03*
Y220809D03*
X338838Y250060D03*
X298279Y222760D03*
X305039D03*
X328698Y236409D03*
X301659Y224709D03*
X328698Y248109D03*
Y240309D03*
Y244209D03*
X325318Y238360D03*
Y246160D03*
X335458Y240309D03*
Y244209D03*
X321938Y240309D03*
Y244209D03*
X332078Y238360D03*
Y246160D03*
X298279Y261760D03*
Y230559D03*
X301659Y244209D03*
X305039Y242260D03*
X301659Y232509D03*
X311798Y230559D03*
X318558Y234460D03*
Y222760D03*
X321938Y224709D03*
X305039Y257860D03*
X311798Y234460D03*
X315178Y236409D03*
Y224709D03*
X321938Y228610D03*
X328698Y255909D03*
Y263709D03*
X338838Y257860D03*
Y261760D03*
X325318Y257860D03*
Y261760D03*
X335458Y255909D03*
Y263709D03*
X298279Y250060D03*
X301659Y263709D03*
X305039Y261760D03*
X301659Y252009D03*
X298279Y242260D03*
X305039Y238360D03*
Y253960D03*
X311798Y226660D03*
X332078Y253960D03*
X315178Y263709D03*
X305039Y234460D03*
X321938Y232509D03*
X332078Y265660D03*
X315178Y275409D03*
X301659Y255909D03*
X298279Y238360D03*
X315178Y228610D03*
X332078Y257860D03*
X315178Y267609D03*
X301659Y236409D03*
X318558Y230559D03*
X332078Y261760D03*
X315178Y271509D03*
X298279Y257860D03*
X311798Y265660D03*
Y273460D03*
X321938Y267609D03*
Y271509D03*
X308418Y267609D03*
Y271509D03*
X318558Y265660D03*
Y273460D03*
X301659Y279310D03*
X298279Y281260D03*
X308418Y283209D03*
X305039Y281260D03*
X308418Y279310D03*
X311798Y281260D03*
X301659Y283209D03*
X348978Y267609D03*
X357057Y277360D03*
Y281260D03*
X345598D03*
X348978Y283209D03*
X345598Y277360D03*
X348978Y279310D03*
Y275409D03*
Y271509D03*
X352357Y265660D03*
X355737Y263709D03*
X332078Y222760D03*
X328698Y224709D03*
X332078Y226660D03*
X335458Y228610D03*
X328698D03*
X332078Y230560D03*
X335458Y232510D03*
X311798Y242260D03*
X315178Y244209D03*
X311798Y246160D03*
X315178Y248109D03*
X308418D03*
X352357Y250060D03*
X345598D03*
X318558D03*
X355737Y252009D03*
X348978D03*
X321938D03*
X352357Y253960D03*
X345598D03*
X355737Y255909D03*
X348978D03*
X338838Y273460D03*
X345598Y261760D03*
X338838Y269560D03*
X332078Y273460D03*
X298279D03*
X335458Y275409D03*
X328698D03*
X338838Y277360D03*
X332078D03*
X325318D03*
X335458Y279310D03*
X328698D03*
X321938D03*
X335458Y271509D03*
X342218Y252009D03*
X301659Y271509D03*
X328698D03*
X298279Y269560D03*
X348978Y259809D03*
X345598Y257860D03*
X352357D03*
X348978Y337809D03*
X305039Y339760D03*
X298279Y335860D03*
X332078D03*
Y343660D03*
X342218Y337809D03*
Y341709D03*
X328698Y337809D03*
Y341709D03*
X338838Y335860D03*
Y343660D03*
X305039Y335860D03*
X301659Y333909D03*
X335458Y337809D03*
X318558Y328060D03*
Y335860D03*
X301659Y341709D03*
X298279Y339760D03*
X335458Y333909D03*
X318558Y324160D03*
X335458Y341709D03*
X318558Y331960D03*
X305039Y343660D03*
X315178Y326110D03*
Y333909D03*
X325318Y328060D03*
Y331960D03*
X311798Y328060D03*
Y331960D03*
X321938Y326110D03*
Y333909D03*
X308418Y306609D03*
X301659Y310509D03*
Y306609D03*
X311798Y304660D03*
X305039D03*
X321938Y306609D03*
X325318Y304660D03*
Y308560D03*
X298279Y304660D03*
X308418Y302709D03*
X301659D03*
X315178D03*
X321938D03*
X318558Y304660D03*
Y308560D03*
X321938Y291009D03*
X318558Y296860D03*
X315178Y294909D03*
X321938D03*
X301659D03*
X325318Y285160D03*
Y289060D03*
Y296860D03*
X298279D03*
Y289060D03*
X308418Y298809D03*
X301659D03*
X305039Y289060D03*
X308418Y291009D03*
Y287109D03*
X311798Y289060D03*
X308418Y294909D03*
X311798Y296860D03*
X305039D03*
X315178Y287109D03*
X318558Y285160D03*
X321938Y287109D03*
X301659D03*
Y291009D03*
X315178Y298809D03*
X321938D03*
X318558Y289060D03*
X315178Y291009D03*
X332078Y308560D03*
Y304660D03*
X328698Y302709D03*
Y306609D03*
Y287109D03*
Y291009D03*
Y294909D03*
Y298809D03*
X332078Y296860D03*
Y285160D03*
Y289060D03*
X315178Y306609D03*
X308418Y310509D03*
X311798Y312460D03*
X305039D03*
X298279D03*
X308418Y314409D03*
X301659D03*
X335458Y298809D03*
X357057Y296860D03*
X348978Y287109D03*
X345598Y285160D03*
X357057D03*
Y292959D03*
X348978Y298809D03*
Y291009D03*
X345598Y289060D03*
Y292959D03*
Y296860D03*
X348978Y294909D03*
X345598Y300760D03*
X348978Y302709D03*
X357057Y300760D03*
Y308560D03*
X348978Y306609D03*
X345598Y304660D03*
Y308560D03*
X348978Y310509D03*
X357057Y304660D03*
Y289060D03*
X342218Y302709D03*
Y306609D03*
Y291009D03*
Y287109D03*
Y294909D03*
Y298809D03*
X338838Y308560D03*
X335458Y302709D03*
X338838Y304660D03*
X335458Y306609D03*
Y287109D03*
X338838Y289060D03*
Y285160D03*
X335458Y291009D03*
X338838Y296860D03*
X335458Y294909D03*
X348978Y314409D03*
X357057Y312460D03*
X345598D03*
X357987Y327609D03*
X348978Y322209D03*
X355737Y333909D03*
X345598Y316360D03*
X348978Y318309D03*
Y330009D03*
X352357Y331960D03*
X348978Y326110D03*
X357057Y320260D03*
Y324160D03*
Y316360D03*
X328698Y314409D03*
X321938D03*
X332078Y328060D03*
X328698Y322209D03*
Y318309D03*
X332078Y324160D03*
Y320260D03*
Y316360D03*
X325318Y320260D03*
X305039D03*
X321938Y318309D03*
X315178D03*
X318558Y316360D03*
X301659Y322209D03*
X325318Y316360D03*
X305039Y324160D03*
X311798Y320260D03*
X308418Y322209D03*
X301659Y326110D03*
X335458Y314409D03*
Y326110D03*
Y318309D03*
Y322209D03*
X338838Y320260D03*
Y324160D03*
Y328060D03*
X298279Y324160D03*
Y320260D03*
X355737Y345609D03*
X348978Y341709D03*
X352357Y343660D03*
X321938Y341709D03*
X352357Y339760D03*
X321938Y345609D03*
X359117Y343660D03*
X355737Y341709D03*
X298279Y374860D03*
Y382660D03*
X308418Y376809D03*
Y380709D03*
X305039Y374860D03*
Y382660D03*
X301659Y376809D03*
X328698Y353409D03*
X301659Y384609D03*
X328698Y361209D03*
X301659Y372909D03*
X328698Y349509D03*
X301659Y380709D03*
X328698Y357309D03*
X325318Y351460D03*
Y359260D03*
X335458Y353409D03*
Y357309D03*
X321938Y353409D03*
Y357309D03*
X332078Y351460D03*
Y359260D03*
X301659Y365109D03*
X298279Y367060D03*
X305039Y355360D03*
X301659Y353409D03*
X318558Y363160D03*
X311798Y367060D03*
X321938Y372909D03*
X318558Y374860D03*
X315178Y361209D03*
X311798Y363160D03*
X321938Y369010D03*
X315178Y372909D03*
X298279Y347560D03*
X301659Y345609D03*
X305039Y359260D03*
X298279Y355360D03*
X301659Y361209D03*
X318558Y367060D03*
X311798Y370959D03*
X335458Y345609D03*
X305039Y363160D03*
X321938Y365109D03*
X298279Y359260D03*
X315178Y369010D03*
Y349509D03*
Y353409D03*
X348978Y345609D03*
X311798Y355360D03*
Y347560D03*
Y351460D03*
X308418Y349509D03*
X345598Y347560D03*
X315178Y384609D03*
Y380709D03*
X332078Y374860D03*
X328698Y372909D03*
X332078Y370959D03*
X328698Y369010D03*
X335458D03*
X332078Y367060D03*
X335458Y365109D03*
X352357Y347560D03*
X300982Y518157D03*
Y528899D03*
X304328Y513114D03*
X297635D03*
X301092Y493300D03*
X304392Y494700D03*
X297835Y494944D03*
X304328Y535100D03*
X297635D03*
X415634Y220096D03*
Y216196D03*
X419214Y218147D03*
Y222047D03*
X415634Y239596D03*
Y243496D03*
X419214Y245447D03*
X415634Y227896D03*
Y231797D03*
X419214Y225947D03*
Y229847D03*
X368127Y264300D03*
X364747Y266300D03*
X362497Y259809D03*
X365877Y257860D03*
X369257Y255909D03*
X374887Y260300D03*
X359117Y261760D03*
X371507Y262300D03*
X418084Y253546D03*
X359117Y250060D03*
Y253960D03*
X365877Y250060D03*
X362497Y252009D03*
X364747Y331509D03*
X361367Y329560D03*
X371507Y335409D03*
X362497Y337809D03*
X369257Y341709D03*
X368127Y333460D03*
X365877Y339760D03*
X372637Y343660D03*
X374887Y337360D03*
X381647Y341260D03*
X378267Y339309D03*
X359117Y335860D03*
X362497Y345609D03*
X411431Y359351D03*
X411086Y355360D03*
X365877Y347560D03*
X359117D03*
X460912Y33700D03*
X458266Y27899D03*
X481691D03*
X454533Y33700D03*
X478344Y34100D03*
X474998Y27899D03*
X460912Y-4100D03*
X458266Y17157D03*
Y-9901D03*
X460912Y12114D03*
X481691Y17157D03*
Y-9901D03*
X451573Y17157D03*
X454533Y-4100D03*
X451573Y-9901D03*
X454619Y12114D03*
X478344Y-3700D03*
X474998Y17157D03*
Y-9901D03*
X478344Y12114D03*
X460912Y71500D03*
X458266Y92757D03*
Y65699D03*
X460912Y87714D03*
X481691Y92757D03*
Y65699D03*
X454533Y71500D03*
X451573Y92757D03*
Y65699D03*
X454619Y87714D03*
X478344Y71900D03*
X474998Y92757D03*
Y65699D03*
X478344Y87714D03*
X458266Y54957D03*
X460912Y49914D03*
X481691Y54957D03*
X451573D03*
X454619Y49564D03*
X474998Y54957D03*
X478344Y49914D03*
X436113Y220096D03*
X446253Y222047D03*
X432733D03*
X442873Y220096D03*
X456393D03*
X466533Y222047D03*
X453013D03*
X463153Y220096D03*
X473292Y222047D03*
X439493Y218147D03*
X459773D03*
X480052D03*
X439493Y222047D03*
X459773D03*
X480052D03*
X425974D03*
X422594Y220096D03*
X458400Y276400D03*
X436113Y227896D03*
X446253Y225947D03*
X432733D03*
X442873Y227896D03*
X456393D03*
X466533Y225947D03*
X453013D03*
X463153Y227896D03*
X476672D03*
X473292Y225947D03*
X439493Y229847D03*
X459773D03*
X439493Y225947D03*
X459773D03*
X480052Y229847D03*
X425974Y225947D03*
X422594Y227896D03*
X466533Y233746D03*
Y241547D03*
X476672Y239596D03*
X463153Y235696D03*
Y239596D03*
X473292Y233746D03*
Y241547D03*
X469913Y231797D03*
Y243496D03*
Y235696D03*
Y239596D03*
X425974Y233746D03*
Y241547D03*
X436113Y235696D03*
Y239596D03*
X422594Y235696D03*
Y239596D03*
X432733Y233746D03*
Y241547D03*
X446253Y233746D03*
Y241547D03*
X456393Y235696D03*
Y239596D03*
X442873Y235696D03*
Y239596D03*
X453013Y233746D03*
Y241547D03*
X456393Y247396D03*
Y255196D03*
X466533Y249347D03*
Y253247D03*
X453013Y249347D03*
Y253247D03*
X463153Y247396D03*
Y255196D03*
X476672Y247396D03*
Y255196D03*
X473292Y249347D03*
Y253247D03*
X429354Y231797D03*
X449633D03*
X459773Y245447D03*
X480052D03*
X429354Y243496D03*
X449633D03*
X459773Y257147D03*
X480052D03*
X429354Y235696D03*
X449633D03*
X459773Y249347D03*
X480052D03*
X429354Y239596D03*
X449633D03*
X459773Y253247D03*
X480052D03*
X452865Y270081D03*
X465100Y280300D03*
X434983Y255497D03*
X438363Y257446D03*
X431604D03*
X448503Y263297D03*
X441743Y259397D03*
X455263Y267197D03*
X436113Y247396D03*
X446253Y249347D03*
X442873Y251296D03*
X439493Y249347D03*
X442873Y247396D03*
X439493Y245447D03*
X446253Y253247D03*
X466533Y261047D03*
X463153Y262996D03*
X477792Y276646D03*
Y280547D03*
X469913Y282496D03*
X474413Y274696D03*
X469913Y278596D03*
X466533Y268847D03*
X422594Y247396D03*
X459773Y264947D03*
X469913Y266896D03*
Y262996D03*
X473292Y261047D03*
X469913Y259096D03*
X481172Y282496D03*
Y270796D03*
X480052Y264947D03*
X473292D03*
Y268847D03*
X476672Y266896D03*
Y262996D03*
X474413Y344896D03*
X481172Y321496D03*
Y325396D03*
Y317596D03*
Y333196D03*
X463671Y319386D03*
X466734Y287074D03*
X442020Y339220D03*
X438240Y339380D03*
X451883Y342646D03*
X448503Y344597D03*
X481172Y298096D03*
X469913D03*
Y301996D03*
X481172Y305896D03*
X477792Y284447D03*
Y296147D03*
Y300047D03*
Y292247D03*
X481172Y294196D03*
X469913D03*
Y290296D03*
X474413Y329296D03*
X468783Y332897D03*
X474413Y333196D03*
Y325396D03*
X477792Y323446D03*
X463800Y289500D03*
X464273Y342947D03*
X471033Y339047D03*
X456900Y333000D03*
X481172Y329296D03*
X471033Y342947D03*
X466100Y300021D03*
X460893Y344896D03*
X481172Y286396D03*
X477792Y311747D03*
X469913Y309797D03*
Y313696D03*
Y317596D03*
X477792Y339047D03*
Y335147D03*
Y331247D03*
X481172Y340996D03*
Y337096D03*
X453400Y293686D03*
X477792Y346847D03*
X481172Y348796D03*
X477792Y350747D03*
X443993Y381947D03*
Y389747D03*
X454133Y383896D03*
Y387796D03*
X440613Y383896D03*
Y387796D03*
X450753Y381947D03*
Y389747D03*
X464273Y381947D03*
Y389747D03*
X474413Y383896D03*
Y387796D03*
X460893Y383896D03*
Y387796D03*
X471033Y381947D03*
Y389747D03*
X481172Y383896D03*
Y387796D03*
X447373Y383896D03*
X467653Y379996D03*
X447373Y391696D03*
X467653D03*
X447373Y379996D03*
X467653Y383896D03*
X447373Y387796D03*
X467653D03*
X423714Y389747D03*
Y393647D03*
X433854Y383896D03*
Y387796D03*
X423714Y378047D03*
Y381947D03*
X430474D03*
Y389747D03*
X474413Y368296D03*
Y376096D03*
X481172Y364396D03*
X471033Y370247D03*
Y374146D03*
X481172Y368296D03*
Y376096D03*
X427094Y383896D03*
X477792Y370247D03*
X427094Y391696D03*
X477792Y378047D03*
X427094Y379996D03*
X477792Y366347D03*
X427094Y387796D03*
X477792Y374146D03*
X427094Y364396D03*
X423714Y370247D03*
X437233Y366347D03*
Y370247D03*
X423714Y358547D03*
Y366347D03*
X433854Y364396D03*
Y372197D03*
X454133Y368296D03*
Y376096D03*
X464273Y370247D03*
Y374146D03*
X450753Y370247D03*
Y374146D03*
X460893Y368296D03*
Y376096D03*
X443993Y354647D03*
Y362447D03*
X454133Y356596D03*
Y360496D03*
X440613Y356596D03*
Y360496D03*
X450753Y354647D03*
Y362447D03*
X464273Y354647D03*
Y362447D03*
X474413Y356596D03*
Y360496D03*
X460893Y356596D03*
Y360496D03*
X471033Y354647D03*
Y362447D03*
X430474Y366347D03*
X457513Y370247D03*
X447373Y356596D03*
X467653D03*
X430474Y370247D03*
X457513Y378047D03*
X447373Y364396D03*
X467653D03*
X430474Y362447D03*
X457513Y366347D03*
X447373Y352696D03*
X467653D03*
X430474Y374146D03*
X457513D03*
X447373Y360496D03*
X467653D03*
X438363Y346546D03*
X424844D03*
X434983Y348497D03*
X428224D03*
X431604Y346546D03*
X471033Y346847D03*
X464273D03*
X457513Y350747D03*
X430474Y358547D03*
X433854Y356596D03*
X437233Y378047D03*
X440613Y376096D03*
X443993Y374147D03*
Y370247D03*
X481172Y356596D03*
X458266Y518157D03*
X460912Y513114D03*
X458266Y528899D03*
X481691Y518157D03*
Y528899D03*
X451573Y518157D03*
Y528899D03*
X454619Y513114D03*
X474998Y518157D03*
Y528899D03*
X478344Y513114D03*
X460912Y534700D03*
X454533D03*
X478344Y535100D03*
X458266Y555957D03*
X460912Y572500D03*
Y550914D03*
X458266Y566699D03*
X481691Y555957D03*
Y566699D03*
X454533Y572500D03*
X454619Y550914D03*
X474998Y555957D03*
X478344Y572900D03*
Y550914D03*
X474998Y566699D03*
X460912Y588714D03*
X454619D03*
X478344D03*
X458266Y593757D03*
X460912Y610300D03*
X458266Y604499D03*
X481691Y593757D03*
Y604499D03*
X454533Y610300D03*
X478344Y610700D03*
X474998Y593757D03*
Y604499D03*
X485037Y34100D03*
X497723Y33700D03*
X495077Y27899D03*
X521848Y34100D03*
X518502Y27899D03*
X491344Y33700D03*
X488384Y27899D03*
X515155Y34100D03*
X511809Y27899D03*
X534534Y33700D03*
X531888Y27899D03*
X528155Y33700D03*
X525195Y27899D03*
X485037Y-3700D03*
Y12114D03*
X497723Y-4100D03*
X495077Y17157D03*
Y-9901D03*
X497723Y12114D03*
X521848Y-3700D03*
X518502Y17157D03*
Y-9901D03*
X521848Y12114D03*
X491344Y-4100D03*
X488384Y17157D03*
Y-9901D03*
X491430Y12114D03*
X511809Y17157D03*
X515155Y-3700D03*
X511809Y-9901D03*
X515155Y12114D03*
X534534Y-4100D03*
X531888Y17157D03*
Y-9901D03*
X534534Y12114D03*
X528155Y-4100D03*
X525195Y17157D03*
Y-9901D03*
X528241Y12114D03*
X485037Y71900D03*
Y87714D03*
X497723Y71500D03*
X495077Y92757D03*
Y65699D03*
X497723Y87714D03*
X521848Y71900D03*
X518502Y92757D03*
Y65699D03*
X521848Y87714D03*
X491344Y71500D03*
X488384Y92757D03*
Y65699D03*
X491430Y87714D03*
X511809Y92757D03*
X515155Y71900D03*
X511809Y65699D03*
X515155Y87714D03*
X534534Y71500D03*
X531888Y92757D03*
Y65699D03*
X534534Y87714D03*
X528155Y71500D03*
X525195Y92757D03*
Y65699D03*
X528241Y87714D03*
X485037Y49914D03*
X495077Y54957D03*
X497723Y49914D03*
X518502Y54957D03*
X521848Y49914D03*
X488384Y54957D03*
X491430Y49914D03*
X511809Y54957D03*
X515155Y49914D03*
X531888Y54957D03*
X534534Y49914D03*
X525195Y54957D03*
X528241Y49914D03*
X494927Y112357D03*
X497723Y106964D03*
X518317Y112357D03*
X521113Y106964D03*
X488634Y112357D03*
X491430Y106964D03*
X512024Y112357D03*
X514820Y106964D03*
X531888Y112357D03*
X534534Y106964D03*
X525134Y112357D03*
X528241Y107314D03*
X483432Y220096D03*
X511592Y222047D03*
X514972Y220096D03*
X518352Y222047D03*
X521731Y216196D03*
X531871Y218147D03*
X542011Y208396D03*
X528491Y204496D03*
X538631Y202247D03*
X525111Y222047D03*
Y210346D03*
X521731Y212296D03*
X514972Y208397D03*
Y212296D03*
X508212Y216196D03*
X501452Y220096D03*
X504832Y214247D03*
X498072Y218147D03*
Y214247D03*
X494692Y220096D03*
X542011Y216196D03*
X538631Y218147D03*
X535251Y212296D03*
X531871Y210346D03*
Y214247D03*
X525111D03*
X518352D03*
Y210345D03*
X514972Y216196D03*
X511592Y214247D03*
X504832Y222047D03*
Y218147D03*
X501452Y216196D03*
X494692Y212296D03*
Y216196D03*
X542011Y212296D03*
Y220096D03*
X535251D03*
Y208397D03*
X528491Y212296D03*
X535251Y216196D03*
X484552Y272747D03*
Y276646D03*
X501452Y270796D03*
X511592Y268847D03*
X514972Y255196D03*
X501452D03*
Y251296D03*
X521731Y270796D03*
X514972Y282496D03*
X521731D03*
X508212D03*
X494692D03*
X491312Y280547D03*
X486812Y261047D03*
X483432Y262996D03*
X518352Y261047D03*
X525111D03*
X514972Y251296D03*
X518352Y272747D03*
X521731Y255196D03*
Y251296D03*
X498072Y264947D03*
X511592Y245447D03*
X514972Y243496D03*
X483432Y227896D03*
X486812Y249347D03*
Y253247D03*
X483432Y247396D03*
Y255196D03*
X498072Y280547D03*
X514972Y274696D03*
X525111Y272747D03*
X518352Y257147D03*
X508212Y274696D03*
X504832Y268847D03*
X491312Y272747D03*
X511592D03*
X504832Y276647D03*
X498072Y245447D03*
X494692Y223996D03*
X504832Y225947D03*
X484552Y280547D03*
X518352Y233746D03*
X531871Y241547D03*
Y249347D03*
X528491Y223996D03*
X531871Y237647D03*
X535251Y223996D03*
X542011D03*
X528491Y270796D03*
Y278596D03*
X542011Y270796D03*
X535251Y255196D03*
X531871Y264947D03*
X494692Y266896D03*
X504832Y257147D03*
X508212Y251296D03*
X504832Y249347D03*
X508212Y247396D03*
X518352Y264947D03*
X508212Y243496D03*
X518352Y245447D03*
X531871Y257147D03*
X528491Y255196D03*
X511592Y253247D03*
X525111Y268847D03*
X518352Y241547D03*
Y237647D03*
X521731Y239596D03*
Y243496D03*
X528491Y262996D03*
Y266896D03*
X498072Y249347D03*
X525111D03*
Y245447D03*
X508212Y266896D03*
X521731Y278596D03*
X498072Y276647D03*
X491312D03*
X511592D03*
X504832Y272747D03*
X498072Y253247D03*
Y257147D03*
X518352Y280547D03*
X535251Y243496D03*
X542011Y266896D03*
X538631Y272747D03*
X531871D03*
X538631Y280547D03*
X542011Y282496D03*
X538631Y276646D03*
X535251Y278596D03*
X531871Y280547D03*
X538631Y241547D03*
X542011Y243496D03*
Y251296D03*
Y255196D03*
Y262996D03*
X538631Y261047D03*
X531871Y245447D03*
X538631Y264947D03*
Y268847D03*
X535251Y270796D03*
X542011Y278596D03*
X535251Y274696D03*
Y282496D03*
X528491D03*
X538631Y245447D03*
Y253247D03*
X542011Y259096D03*
X535251Y262996D03*
X511592Y229847D03*
Y225947D03*
Y237647D03*
X508212Y235696D03*
X498072Y229847D03*
X504832Y233746D03*
X494692Y227896D03*
X501452Y235696D03*
X498072Y237647D03*
Y241547D03*
X542011Y227896D03*
Y235696D03*
X535251Y231797D03*
Y227896D03*
X531871Y229847D03*
X525111Y233746D03*
X521731Y223996D03*
X525111Y229847D03*
X514972Y231797D03*
X508212Y227896D03*
X511592Y233746D03*
X504832Y237647D03*
X501452Y227896D03*
Y231797D03*
X494692D03*
X501452Y239596D03*
X494692D03*
X501452Y243496D03*
X542011Y231797D03*
X538631Y233746D03*
Y229847D03*
X531871Y225947D03*
Y233746D03*
X528491Y231797D03*
X525111Y225947D03*
X518352D03*
X521731Y227896D03*
X525111Y257147D03*
X528491Y259096D03*
X525111Y276646D03*
X504832Y280547D03*
X511592D03*
X518352Y276646D03*
Y268847D03*
X498072Y272747D03*
X531871Y253247D03*
X528491Y251296D03*
X525111Y241547D03*
X528491Y239596D03*
X518352Y249347D03*
X513857Y260881D03*
X501452Y262996D03*
X504832Y261047D03*
X501452Y278596D03*
X498072Y268847D03*
X504832Y264947D03*
X494692Y262996D03*
X491312Y264947D03*
X487932Y266896D03*
X491312Y268847D03*
X487932Y270796D03*
X498072Y261047D03*
X494692Y259096D03*
X521731Y262996D03*
X525111Y264947D03*
X494692Y274696D03*
X487932Y313696D03*
X491312Y315647D03*
X484552Y319546D03*
Y331247D03*
X491312Y288347D03*
Y284447D03*
X498072D03*
Y288347D03*
X501452Y286396D03*
X494692Y290296D03*
X498072Y292247D03*
X504832D03*
X518352Y284447D03*
X504832Y288347D03*
Y284447D03*
X508212Y286396D03*
X531871Y315647D03*
X487932Y286396D03*
X514972Y344896D03*
X511592Y342947D03*
X508212Y340996D03*
Y344896D03*
X487932Y290296D03*
X484552Y288347D03*
Y296147D03*
X498072Y339047D03*
X504832Y327347D03*
X508212Y321496D03*
X514972Y340996D03*
X518352Y331247D03*
X521731Y344896D03*
Y321496D03*
X525111Y339047D03*
X535251Y333196D03*
Y325396D03*
X484552Y284447D03*
X487932Y305896D03*
X491312Y303947D03*
X501452Y305896D03*
X494692Y298096D03*
X498072Y307847D03*
X484552Y303947D03*
X487932Y294196D03*
X491312Y296147D03*
X494692Y301996D03*
X487932D03*
X501452Y309797D03*
X487932Y298096D03*
X511592Y311747D03*
X508212Y309797D03*
X511592Y300047D03*
Y303947D03*
X542011Y286396D03*
X531871Y284447D03*
X542011Y290296D03*
X535251Y286396D03*
X542011Y313696D03*
Y309797D03*
X538631Y307847D03*
Y303947D03*
Y300047D03*
X535251Y298096D03*
Y317596D03*
X542011D03*
Y305896D03*
X535251D03*
X542011Y301996D03*
X538631Y296147D03*
X531871D03*
X535251Y313696D03*
X538631Y315647D03*
X484552Y311747D03*
Y315647D03*
X511592Y288347D03*
Y292245D03*
X491312Y323446D03*
X528491Y305896D03*
X518352Y311747D03*
X504832D03*
X508212Y305896D03*
Y301996D03*
X504832Y303947D03*
Y300045D03*
X518352Y303947D03*
X514972Y305896D03*
Y309797D03*
X528491Y301996D03*
Y309797D03*
X525111Y311747D03*
Y307847D03*
Y303947D03*
X521731Y305896D03*
Y309797D03*
X518352Y307847D03*
X514972Y313696D03*
X528491D03*
X521731D03*
X487932Y344896D03*
X484552Y342947D03*
X518352Y296147D03*
Y300047D03*
X521731Y294196D03*
X525111Y288347D03*
X528491Y290296D03*
X525111Y296147D03*
Y292245D03*
X521731Y298096D03*
Y290296D03*
Y286396D03*
X518352Y288347D03*
Y292245D03*
X514972Y298096D03*
X501452Y325396D03*
X498072Y323446D03*
Y315647D03*
X501452Y317596D03*
X498072Y335147D03*
X501452Y321496D03*
X498072Y331247D03*
X501452Y329296D03*
Y313696D03*
X498072Y300047D03*
X508212Y298096D03*
X504832Y296147D03*
X498072D03*
X501452Y294196D03*
X511592Y296147D03*
X498072Y311747D03*
X501452Y301996D03*
X494692Y325396D03*
Y321496D03*
X491312Y319547D03*
X494692Y333196D03*
X491312Y335147D03*
X487932Y333196D03*
Y337096D03*
X484552Y339047D03*
Y335147D03*
X491312Y327347D03*
X494692Y329296D03*
X487932D03*
Y340996D03*
X494692Y313696D03*
X484552Y307847D03*
X491312D03*
Y311747D03*
X494692Y305896D03*
Y317596D03*
X487932Y321496D03*
X484552Y327347D03*
X487932Y325396D03*
X484552Y381947D03*
X494692Y395597D03*
X491312Y401447D03*
X487932Y379996D03*
Y391696D03*
Y387796D03*
X514972Y352696D03*
Y348796D03*
X511592Y350747D03*
Y346847D03*
X508212Y348796D03*
X504832Y362447D03*
X494692Y368296D03*
Y352696D03*
X508212Y356596D03*
X504832Y350747D03*
X511592Y374146D03*
X501452Y383896D03*
X498072Y389747D03*
X494692Y376096D03*
X508212Y379996D03*
X521731Y368296D03*
X518352Y366347D03*
Y358547D03*
X542011Y364396D03*
X538631Y370247D03*
X542011Y372197D03*
Y352696D03*
X525111Y350747D03*
X514972Y399496D03*
X538631Y381947D03*
X531871Y385847D03*
X528491Y391696D03*
X525111Y397546D03*
X531871Y405347D03*
X504832Y370247D03*
X508212Y376096D03*
X501452Y372197D03*
X498072Y370247D03*
X504832Y397546D03*
Y393647D03*
X511592D03*
X501452Y387796D03*
X511592Y385847D03*
X518352D03*
Y381947D03*
Y378047D03*
X508212Y395597D03*
X504832Y389747D03*
X508212Y391696D03*
X504832Y385847D03*
X511592Y381947D03*
X514972Y383896D03*
X521731Y379996D03*
X518352Y374146D03*
Y405347D03*
X525111D03*
Y401447D03*
X528491Y395597D03*
X535251Y399496D03*
X531871Y393647D03*
X538631Y389747D03*
Y385847D03*
X518352Y401447D03*
X521731Y403396D03*
X528491Y399496D03*
X531871Y397546D03*
X535251Y395597D03*
Y391696D03*
Y387796D03*
X542011Y383896D03*
Y391696D03*
Y395597D03*
Y387796D03*
X525111Y370247D03*
X531871D03*
X525111Y362447D03*
X528491Y360496D03*
Y356596D03*
X535251Y352696D03*
X525111Y378047D03*
Y374146D03*
Y366347D03*
X528491Y368296D03*
X521731Y364396D03*
X525111Y358547D03*
X531871Y354647D03*
Y350747D03*
X521731Y376096D03*
X528491Y372197D03*
X542011Y379996D03*
X535251Y376096D03*
X487932Y352696D03*
X484552Y354647D03*
Y350747D03*
Y358547D03*
X487932Y348796D03*
X485037Y513114D03*
X495077Y518157D03*
X497723Y513114D03*
X495077Y528899D03*
X518502Y518157D03*
X521848Y513114D03*
X518502Y528899D03*
X488384Y518157D03*
Y528899D03*
X491430Y513114D03*
X511809Y518157D03*
Y528899D03*
X515155Y513114D03*
X531888Y518157D03*
X534534Y513114D03*
X531888Y528899D03*
X525195Y518157D03*
X528241Y513114D03*
X525195Y528899D03*
X494777Y498487D03*
X497723Y490894D03*
X517902Y498487D03*
X521048Y493844D03*
X488384Y498487D03*
X491430Y491144D03*
X511809Y498487D03*
X514755Y493744D03*
X530792Y498387D03*
X534534Y493394D03*
X524595Y498387D03*
X528191Y493544D03*
X485037Y535100D03*
X497723Y534700D03*
X521848Y535100D03*
X491344Y534700D03*
X515155Y535100D03*
X534534Y534700D03*
X528155D03*
X485037Y572900D03*
Y550914D03*
X495077Y555957D03*
X497723Y572500D03*
Y550914D03*
X495077Y566699D03*
X518502Y555957D03*
X521848Y572900D03*
Y550914D03*
X518502Y566699D03*
X488384Y555957D03*
X491344Y572500D03*
X491430Y550914D03*
X488384Y566699D03*
X511809Y555957D03*
X515155Y572900D03*
Y550914D03*
X511809Y566699D03*
X531888Y555957D03*
X534534Y572500D03*
Y550914D03*
X531888Y566699D03*
X525195Y555957D03*
X528155Y572500D03*
X528241Y550914D03*
X525195Y566699D03*
X485037Y588714D03*
X497723D03*
X521848D03*
X491430D03*
X515155D03*
X534534D03*
X528241D03*
X485037Y610700D03*
X495077Y593757D03*
X498092Y611200D03*
X495077Y604499D03*
X521848Y610700D03*
X518502Y593757D03*
Y604499D03*
X488384Y593757D03*
X491724Y611668D03*
X488384Y604499D03*
X515155Y610700D03*
X511809Y593757D03*
Y604499D03*
X534534Y610300D03*
X531888Y593757D03*
Y604499D03*
X528155Y610300D03*
X525195Y593757D03*
Y604499D03*
X558659Y34100D03*
X555313Y27899D03*
X551966Y34100D03*
X548620Y27899D03*
X571345Y33700D03*
X568699Y27899D03*
X595470Y34100D03*
X592124Y27899D03*
X564966Y33700D03*
X562006Y27899D03*
X588777Y34100D03*
X585431Y27899D03*
X558659Y-3700D03*
X555313Y17157D03*
Y-9901D03*
X558659Y12114D03*
X551966Y-3700D03*
X548620Y17157D03*
Y-9901D03*
X551966Y12114D03*
X571345Y-4100D03*
X568699Y17157D03*
Y-9901D03*
X571345Y12114D03*
X595470Y-3700D03*
X592124Y17157D03*
Y-9901D03*
X595470Y12114D03*
X564966Y-4100D03*
X561868Y17019D03*
X562006Y-9901D03*
X565052Y12114D03*
X588777Y-3700D03*
X585431Y17157D03*
Y-9901D03*
X588777Y12114D03*
X598817Y17057D03*
X602163Y9157D03*
Y-1743D03*
Y36057D03*
Y27899D03*
X605510D03*
Y-9901D03*
Y16999D03*
Y-1743D03*
Y9157D03*
Y36057D03*
X558659Y71900D03*
X555313Y92757D03*
Y65699D03*
X558659Y87714D03*
X551966Y71900D03*
X548620Y92757D03*
Y65699D03*
X551966Y87714D03*
X571345Y71500D03*
X568699Y92757D03*
Y65699D03*
X571345Y87714D03*
X595470Y71900D03*
X592124Y92757D03*
Y65699D03*
X595470Y87714D03*
X564966Y71500D03*
X562006Y92757D03*
Y65699D03*
X565266Y87374D03*
X588777Y71900D03*
X585431Y92757D03*
Y65699D03*
X588777Y87714D03*
X555313Y54957D03*
X558659Y49914D03*
X548620Y54957D03*
X551966Y49914D03*
X568699Y54957D03*
X571345Y49914D03*
X592124Y54957D03*
X595470Y49914D03*
X562006Y54957D03*
X565052Y49914D03*
X585431Y54957D03*
X588777Y49914D03*
X598817Y92657D03*
X602163Y84757D03*
Y54799D03*
Y46957D03*
X598817Y54857D03*
X602163Y73857D03*
X605510Y92599D03*
Y65699D03*
Y54799D03*
Y46957D03*
Y84757D03*
Y73857D03*
X603163Y103971D03*
X555313Y112357D03*
X558659Y107314D03*
X548620Y112357D03*
X551966Y107314D03*
X605028Y119000D03*
X604977Y110200D03*
X558911Y218147D03*
X555531Y220096D03*
X548771D03*
X545391Y218147D03*
Y214247D03*
X552151Y222047D03*
X548771Y216196D03*
X603273Y198896D03*
X600286Y202921D03*
X599773Y199596D03*
X592300Y220500D03*
X552151Y237647D03*
X555531Y231797D03*
X548771Y227896D03*
X552151Y245447D03*
X548771Y251296D03*
X545391Y237647D03*
X548771Y282496D03*
Y270796D03*
Y262996D03*
X545391Y276646D03*
Y245447D03*
Y253247D03*
X548771Y259096D03*
X545391Y241547D03*
X548771Y247396D03*
X545391Y249347D03*
Y257147D03*
Y261047D03*
Y229847D03*
X548771Y231797D03*
X562616Y223996D03*
X555531Y259096D03*
Y266896D03*
X558911Y268847D03*
X552151D03*
Y276646D03*
X555531Y278596D03*
Y282496D03*
X562640Y231735D03*
X555531Y243496D03*
X552151Y253247D03*
X558911Y249347D03*
Y257147D03*
Y225947D03*
X555531Y262996D03*
X552151Y264947D03*
X555531Y270796D03*
X552151Y272747D03*
X548771Y274696D03*
X552151Y280547D03*
X562630Y227896D03*
X558911Y241547D03*
X555531Y251296D03*
X558911Y253247D03*
X555531Y255196D03*
Y227896D03*
Y223996D03*
X548771D03*
Y321496D03*
X545391Y323446D03*
X548771Y337096D03*
X545391Y342947D03*
X548771Y329296D03*
Y290296D03*
Y294196D03*
X545391Y284447D03*
X560884Y290296D03*
X555831Y294196D03*
X552151Y292245D03*
X545391Y311747D03*
X552151Y319547D03*
Y315647D03*
Y311747D03*
X548771Y305896D03*
X552151Y300047D03*
X548771Y301996D03*
X559211Y331103D03*
X555531Y329296D03*
X559211Y323446D03*
X555531Y321496D03*
X548771Y317596D03*
X555831Y313696D03*
X552151Y307847D03*
Y303947D03*
X555831Y301996D03*
X548771Y298096D03*
X559211Y327347D03*
X552151D03*
X555531Y325396D03*
X555831Y317446D03*
X559212Y385847D03*
X552151Y393647D03*
X545391Y389747D03*
Y393647D03*
X559212Y389747D03*
X545391Y378047D03*
X552151Y374146D03*
X545391D03*
X548771Y364396D03*
Y360496D03*
Y356596D03*
Y383896D03*
Y376096D03*
Y372196D03*
X545391Y370247D03*
Y362447D03*
X552151Y358547D03*
X548771Y352696D03*
X545391Y381947D03*
X548771Y379996D03*
X552151Y366347D03*
Y370247D03*
X563500Y360500D03*
X555531Y372197D03*
X548990Y403670D03*
X555750Y399770D03*
X562591Y348796D03*
X592216Y445152D03*
X595070Y447970D03*
X555313Y518157D03*
X558659Y513114D03*
X555313Y528899D03*
X548620Y518157D03*
Y528899D03*
X551966Y513114D03*
X568699Y518157D03*
X571345Y513114D03*
X568699Y528899D03*
X592124Y518157D03*
X595470Y513114D03*
X592124Y528899D03*
X562006Y518157D03*
Y528899D03*
X565266Y512774D03*
X585431Y518157D03*
X588777Y513114D03*
X585431Y528899D03*
X554792Y498487D03*
X558659Y496144D03*
X548492Y498400D03*
X551366Y493344D03*
X602163Y510157D03*
X598817Y518057D03*
X605510Y528899D03*
Y517999D03*
Y510157D03*
X558659Y535100D03*
X551966D03*
X571345Y534700D03*
X595470Y535100D03*
X564966Y534700D03*
X588777Y535100D03*
X555313Y555957D03*
X558659Y572900D03*
Y550914D03*
X555313Y566699D03*
X548620Y555957D03*
X551966Y572900D03*
Y550914D03*
X548620Y566699D03*
X568699Y555957D03*
X571345Y572500D03*
Y550914D03*
X568699Y566699D03*
X592124Y555957D03*
X595470Y572900D03*
Y550914D03*
X592124Y566699D03*
X562006Y555957D03*
X564966Y572500D03*
X565266Y550574D03*
X562006Y566699D03*
X585431Y555957D03*
X588777Y572900D03*
Y550914D03*
X585431Y566699D03*
X558659Y588714D03*
X551966D03*
X571345D03*
X595470D03*
X565052D03*
X588777D03*
X602163Y574857D03*
Y566699D03*
Y555799D03*
X598817Y555857D03*
X602163Y547957D03*
Y537057D03*
Y585757D03*
X605510Y555799D03*
Y566699D03*
Y585757D03*
Y547957D03*
Y574857D03*
Y537057D03*
X558659Y610700D03*
X555313Y593757D03*
Y604499D03*
X551966Y610700D03*
X548620Y593757D03*
Y604499D03*
X571345Y610300D03*
X568699Y593757D03*
Y604499D03*
X592124Y593757D03*
X595470Y610700D03*
X592124Y604499D03*
X564966Y610300D03*
X562006Y593757D03*
Y604499D03*
X585431Y593757D03*
X588777Y610700D03*
X585431Y604499D03*
X598817Y593657D03*
X602163Y612657D03*
X605510Y604499D03*
Y593599D03*
Y612657D03*
X661494Y32946D03*
X657250Y-2050D03*
X608856Y16999D03*
X612203D03*
Y9157D03*
X608856D03*
X615549D03*
X608856Y-9901D03*
X612203D03*
X608856Y-1743D03*
X612203D03*
X615549D03*
Y36057D03*
X608856D03*
X612203D03*
Y27899D03*
X608856D03*
X659747Y-12132D03*
X615549Y27899D03*
Y-9901D03*
Y16999D03*
X659700Y22900D03*
X665396Y23000D03*
X615549Y84757D03*
X608856D03*
X612203D03*
X608856Y92599D03*
X612203D03*
X608856Y46957D03*
X612203D03*
X608856Y54799D03*
X615549Y46957D03*
X612203Y54799D03*
X608856Y65699D03*
X612203D03*
X615549Y73857D03*
X608856D03*
X612203D03*
X652718Y93881D03*
X664471Y86061D03*
X662352Y89566D03*
X615549Y92599D03*
Y65699D03*
Y54799D03*
X626040Y98281D03*
X608600Y103000D03*
X613602Y118047D03*
Y109247D03*
X633800Y119000D03*
X658055Y141493D03*
X647555Y143643D03*
X651055Y142893D03*
X654555Y142193D03*
X642673Y139811D03*
X644055Y144493D03*
X635673Y141318D03*
X639173Y140618D03*
X632173Y142018D03*
X628673Y142718D03*
X609482Y124568D03*
X618800Y100100D03*
X644750Y175650D03*
X660600Y170000D03*
Y175000D03*
X611148Y206994D03*
X618648Y219494D03*
Y214494D03*
X608648Y204494D03*
X613648D03*
X610273Y197496D03*
X613773Y196796D03*
X613082Y200676D03*
X609860Y201356D03*
X654950Y253446D03*
X627529Y280441D03*
X618279Y251393D03*
X624500Y240500D03*
X639320Y268000D03*
X643500Y274868D03*
X633410Y269610D03*
Y274610D03*
X651235Y249165D03*
X641665Y281139D03*
X643100Y253700D03*
X649800Y252600D03*
X656100Y275500D03*
X606148Y229494D03*
X617235Y247735D03*
X614456Y244956D03*
X637681Y337390D03*
X628525Y287832D03*
X631250Y289650D03*
X639622Y290210D03*
X643823Y289650D03*
X658500Y284500D03*
X632869Y293720D03*
X648900Y336600D03*
X646520Y297400D03*
X664267Y292668D03*
X637143Y322000D03*
X637561Y312000D03*
Y317000D03*
X637600Y302000D03*
Y307000D03*
X646700Y308850D03*
X658900Y339150D03*
X628950Y293550D03*
X654600Y296000D03*
X662238Y296146D03*
X659694Y351206D03*
X664194D03*
X649194D03*
X654194D03*
X649600Y391200D03*
X640300Y437600D03*
X608800Y463475D03*
Y468475D03*
X609191Y451454D03*
X615300Y457900D03*
X641150Y484300D03*
X653800Y496600D03*
X618430Y491550D03*
X623400Y476300D03*
X629300Y490000D03*
X648500Y477400D03*
X662640Y528330D03*
X608856Y517999D03*
X612203D03*
Y528899D03*
X608856D03*
X615549Y510157D03*
X608856D03*
X612203D03*
X612515Y498752D03*
X609284Y480055D03*
X636500Y493924D03*
X627000Y478300D03*
X611250Y476750D03*
X618800Y474500D03*
X615549Y517999D03*
Y528899D03*
X639120Y475620D03*
X658900Y509300D03*
X639197Y490367D03*
X623600Y521700D03*
X608856Y574857D03*
X612203D03*
X615549D03*
X612203Y566699D03*
X608856D03*
Y555799D03*
X612203D03*
Y547957D03*
X615549D03*
X608856D03*
Y537057D03*
X615549D03*
X612203D03*
X615549Y585757D03*
X612203D03*
X608856D03*
X660217Y576734D03*
X615549Y555799D03*
Y566699D03*
X662000Y589000D03*
X608856Y593599D03*
X612203D03*
X608856Y604499D03*
X612203D03*
X608856Y612657D03*
X615549D03*
X612203D03*
X615549Y604499D03*
Y593599D03*
X665000Y598500D03*
X631741Y615759D03*
X723715Y23462D03*
X692500Y15300D03*
X708000Y26600D03*
X700500D03*
X724837Y13852D03*
X714300Y-1900D03*
X680200Y13100D03*
X675235Y36797D03*
X719400Y14300D03*
X679936Y18406D03*
X670227Y34277D03*
X670400Y26100D03*
X701100Y8100D03*
X704450Y4950D03*
X720572Y88700D03*
X715130Y79574D03*
X697200Y79500D03*
X697100Y90600D03*
X670795Y89189D03*
X716894Y84047D03*
X701500Y85500D03*
X694600Y85000D03*
X698300Y85300D03*
X709560Y84648D03*
X689500Y37900D03*
X685000Y46650D03*
X670503Y115884D03*
X670600Y144900D03*
Y150000D03*
X706500Y207800D03*
X706561Y211417D03*
X705292Y195729D03*
X701956Y195294D03*
X701129Y192106D03*
X709341Y190507D03*
X725725Y241560D03*
X697255Y267098D03*
X710500Y224500D03*
X700400Y257200D03*
X710272Y281911D03*
X706800Y281900D03*
X704500Y252500D03*
X700800Y261300D03*
X690130Y277380D03*
X715200Y258900D03*
X704090Y256080D03*
X689960Y260500D03*
X700000Y233700D03*
X710900Y231660D03*
X677800Y254100D03*
X667700Y275600D03*
X710700Y260200D03*
X710675Y263425D03*
X679300Y261700D03*
X712400Y324400D03*
X711900Y327700D03*
X697120Y305349D03*
Y300349D03*
X704404Y315875D03*
Y310875D03*
X697521Y325500D03*
Y320500D03*
X724000Y291700D03*
X686140Y298260D03*
X695000Y289500D03*
X686600Y335600D03*
X670800Y292600D03*
X667900Y339000D03*
X697352Y335500D03*
Y330500D03*
X705800Y301600D03*
X674700Y339200D03*
X688100Y308600D03*
X688924Y288147D03*
X674469Y287375D03*
X674194Y358467D03*
X683417Y364972D03*
X686619Y392600D03*
X683100Y392200D03*
X691240Y390039D03*
X687427Y384926D03*
X676900Y381800D03*
X669194Y351206D03*
X674194D03*
X679194D03*
X684194D03*
X695700Y346300D03*
X680370Y427770D03*
X680200Y432100D03*
X687400Y411200D03*
X674300Y489500D03*
X679700Y489400D03*
X718546Y500283D03*
X696000Y496800D03*
X669300Y504000D03*
X708500Y512500D03*
X680000Y511800D03*
X686200Y511700D03*
X700500Y512850D03*
X690500Y523300D03*
X675500Y521900D03*
X721894Y501346D03*
X726040Y506080D03*
X696600Y581400D03*
X722200Y571300D03*
X718200Y581000D03*
X680029Y577503D03*
X680910Y582000D03*
X693200Y575900D03*
X717612Y598554D03*
X722406Y598950D03*
X756176Y-4300D03*
X782567Y33700D03*
X779921Y27899D03*
X776188Y33700D03*
X773228Y27899D03*
X782567Y-4100D03*
X779921Y17157D03*
X782567Y12114D03*
X779921Y-9901D03*
X776188Y-4100D03*
X773228Y17157D03*
X776274Y12114D03*
X773228Y-9901D03*
X729500Y23500D03*
X764100Y17100D03*
X760100Y17255D03*
X769881Y9157D03*
X763500Y23940D03*
X765900Y35800D03*
X765400Y-9800D03*
X766300Y-1800D03*
X729600Y17991D03*
X734256D03*
X755000Y17255D03*
X753100Y92111D03*
X782567Y71500D03*
X779921Y92757D03*
Y65699D03*
X782567Y87714D03*
X776188Y71500D03*
X773228Y92757D03*
Y65699D03*
X776274Y87714D03*
X779921Y54957D03*
X782567Y49914D03*
X773228Y54957D03*
X776274Y49914D03*
X764100Y55100D03*
X751600Y41000D03*
X755500Y55200D03*
X769881Y46957D03*
X763500Y59700D03*
X766500Y102900D03*
X752900Y101000D03*
X769044Y191348D03*
X770300Y204930D03*
X771232Y214033D03*
X749126Y220843D03*
X761580Y220160D03*
X748700Y257500D03*
X771650Y246451D03*
Y278451D03*
X759700Y232000D03*
X739400Y253400D03*
X739500Y247500D03*
X731662Y247716D03*
X775200Y230500D03*
X775171Y227116D03*
Y234316D03*
X775271Y262716D03*
X775171Y259116D03*
X730000Y254675D03*
X737750Y298894D03*
X771600Y310600D03*
X771700Y342501D03*
X729405Y290725D03*
X737912Y315500D03*
X741512Y315538D03*
X736000Y303400D03*
X775271Y294716D03*
X775171Y291116D03*
X775271Y326716D03*
X775171Y323116D03*
X757956Y328095D03*
X741250Y298856D03*
X743600Y304100D03*
X771400Y374400D03*
X760500Y359800D03*
X775271Y358716D03*
X775171Y355116D03*
X775221Y390716D03*
X775121Y387116D03*
X765007Y348363D03*
X732000Y380000D03*
X739933Y447401D03*
X756000Y525950D03*
X779921Y518157D03*
Y528899D03*
X782567Y513114D03*
X773228Y518157D03*
Y528899D03*
X776274Y513114D03*
X743483Y492937D03*
X764400Y528600D03*
X738648Y492050D03*
X763544Y522236D03*
X769500Y510100D03*
X766535Y517900D03*
X763706Y514250D03*
X782567Y534700D03*
X776188D03*
X779921Y555957D03*
X782567Y572500D03*
Y550914D03*
X779921Y566699D03*
X773228Y555957D03*
X776188Y572500D03*
X776274Y550914D03*
X773228Y566699D03*
X782567Y588714D03*
X776274D03*
X763300Y566000D03*
X769500Y536983D03*
X755000Y566000D03*
X769500Y547900D03*
Y574700D03*
Y585700D03*
X764117Y575658D03*
X765100Y537110D03*
X766535Y555700D03*
X732600Y573950D03*
X763450Y585200D03*
X765900Y587300D03*
X782567Y610300D03*
X779921Y593757D03*
Y604499D03*
X776188Y610300D03*
X773228Y593757D03*
Y604499D03*
X764400Y604600D03*
X739307Y598850D03*
X755800Y604600D03*
X769500Y612583D03*
X766535Y593500D03*
X733032Y604000D03*
X843503Y34100D03*
X840157Y27899D03*
X812999Y33700D03*
X810039Y27899D03*
X836810Y34100D03*
X833464Y27899D03*
X849810Y33700D03*
X846850Y27899D03*
X806692Y34100D03*
X803346Y27899D03*
X799999Y34100D03*
X796653Y27899D03*
X819378Y33700D03*
X816732Y27899D03*
X843503Y-3700D03*
X840157Y17157D03*
Y-9901D03*
X843503Y12114D03*
X812999Y-4100D03*
X810039Y17157D03*
Y-9901D03*
X813085Y12114D03*
X833464Y17157D03*
X836810Y-3700D03*
X833464Y-9901D03*
X836810Y12114D03*
X849810Y-4100D03*
X846850Y17157D03*
Y-9901D03*
X849896Y12114D03*
X806692Y-3700D03*
X803346Y17157D03*
Y-9901D03*
X806692Y12114D03*
X799999Y-3700D03*
X796653Y17157D03*
Y-9901D03*
X799999Y12114D03*
X816732Y17157D03*
X819378Y-4100D03*
Y12114D03*
X816732Y-9901D03*
X843503Y71900D03*
X840157Y92757D03*
Y65699D03*
X843503Y87714D03*
X812999Y71500D03*
X810039Y92757D03*
Y65699D03*
X813085Y87714D03*
X836810Y71900D03*
X833464Y92757D03*
Y65699D03*
X836810Y87714D03*
X849810Y71500D03*
X846850Y92757D03*
Y65699D03*
X849896Y87714D03*
X806692Y71900D03*
X803346Y92757D03*
Y65699D03*
X806692Y87714D03*
X799999Y71900D03*
X796653Y92757D03*
Y65699D03*
X799999Y87714D03*
X816732Y92757D03*
X819378Y71500D03*
X816732Y65699D03*
X819378Y87714D03*
X840157Y54957D03*
X843503Y49914D03*
X810039Y54957D03*
X813085Y49914D03*
X833464Y54957D03*
X836810Y49914D03*
X846850Y54957D03*
X849896Y49914D03*
X803346Y54957D03*
X806692Y49914D03*
X796653Y54957D03*
X799999Y49914D03*
X816732Y54957D03*
X819378Y49914D03*
X798337Y181216D03*
X799300Y195600D03*
X813700D03*
Y198900D03*
X799620Y186547D03*
X804470Y186814D03*
X824000Y402863D03*
X797000Y404700D03*
X851430Y367468D03*
X805600Y403900D03*
X840871Y391380D03*
X837272Y391420D03*
X827800Y402863D03*
X832300D03*
X805367Y407400D03*
X797780Y423484D03*
X840157Y518157D03*
Y528899D03*
X843503Y513114D03*
X810039Y518157D03*
X813085Y513114D03*
X810039Y528899D03*
X833464Y518157D03*
Y528899D03*
X836810Y513114D03*
X846850Y518157D03*
X849896Y513114D03*
X846850Y528899D03*
X803346Y518157D03*
X806692Y513114D03*
X803346Y528899D03*
X796653Y518157D03*
X799999Y513114D03*
X796653Y528899D03*
X816732Y518157D03*
Y528899D03*
X819378Y513114D03*
X843503Y535100D03*
X812999Y534700D03*
X836810Y535100D03*
X849810Y534700D03*
X806692Y535100D03*
X799999D03*
X819378Y534700D03*
X840157Y555957D03*
X843503Y572900D03*
Y550914D03*
X840157Y566699D03*
X810039Y555957D03*
X812999Y572500D03*
X813085Y550914D03*
X810039Y566699D03*
X833464Y555957D03*
X836810Y572900D03*
Y550914D03*
X833464Y566699D03*
X846850Y555957D03*
X849810Y572500D03*
X849896Y550914D03*
X846850Y566699D03*
X803346Y555957D03*
X806692Y572900D03*
Y550914D03*
X803346Y566699D03*
X796653Y555957D03*
X799999Y572900D03*
Y550914D03*
X796653Y566699D03*
X816732Y555957D03*
X819378Y572500D03*
X816732Y566699D03*
X819378Y550914D03*
X843503Y588714D03*
X813085D03*
X836810D03*
X849896D03*
X806692D03*
X799999D03*
X819378D03*
X840157Y593757D03*
X843503Y610700D03*
X840157Y604499D03*
X812999Y610300D03*
X810039Y593757D03*
Y604499D03*
X833464Y593757D03*
X836810Y610700D03*
X833464Y604499D03*
X846850Y593757D03*
X849810Y610300D03*
X846850Y604499D03*
X806692Y610700D03*
X803346Y593757D03*
Y604499D03*
X799999Y610700D03*
X796653Y593757D03*
Y604499D03*
X816732Y593757D03*
X819378Y610300D03*
X816732Y604499D03*
X856189Y33700D03*
X853543Y27899D03*
X880314Y34100D03*
X876968Y27899D03*
X873621Y34100D03*
X870275Y27899D03*
X893000Y33700D03*
X890354Y27899D03*
X913779D03*
X886621Y33700D03*
X883661Y27899D03*
X910432Y34100D03*
X907086Y27899D03*
X856189Y-4100D03*
X853543Y17157D03*
Y-9901D03*
X856189Y12114D03*
X880314Y-3700D03*
X876968Y17157D03*
Y-9901D03*
X880314Y12114D03*
X873621Y-3700D03*
X870275Y17157D03*
Y-9901D03*
X873621Y12114D03*
X893000Y-4100D03*
X890354Y17157D03*
X893000Y12114D03*
X890354Y-9901D03*
X913779Y17157D03*
Y-9901D03*
X883661Y17157D03*
X886621Y-4100D03*
X886707Y12114D03*
X883661Y-9901D03*
X907086Y17157D03*
X910432Y-3700D03*
X907086Y-9901D03*
X910432Y12114D03*
X856189Y71500D03*
X853543Y92757D03*
Y65699D03*
X856189Y87714D03*
X876968Y92757D03*
X880314Y71900D03*
X876968Y65699D03*
X880314Y87714D03*
X873621Y71900D03*
X870275Y92761D03*
Y65699D03*
X873621Y87714D03*
X893000Y71500D03*
X890354Y92757D03*
X893000Y87714D03*
X890354Y65699D03*
X913779Y92757D03*
Y65699D03*
X886621Y71500D03*
X883661Y92757D03*
X886707Y87714D03*
X883661Y65699D03*
X910432Y71900D03*
X907086Y92757D03*
X910432Y87714D03*
X907086Y65699D03*
X853543Y54957D03*
X856189Y49914D03*
X876968Y54957D03*
X880314Y49914D03*
X870275Y54957D03*
X873621Y49914D03*
X890354Y54957D03*
X893000Y49914D03*
X913779Y54957D03*
X883661D03*
X886707Y49914D03*
X907086Y54957D03*
X910432Y49914D03*
X890354Y112327D03*
X893000Y106934D03*
X913779Y112327D03*
X883661D03*
X886707Y107284D03*
X907086Y112327D03*
X910432Y107284D03*
X913787Y257860D03*
X913700Y242260D03*
X913787Y261760D03*
Y246160D03*
Y273460D03*
Y335860D03*
Y331960D03*
X882008Y321100D03*
X913787Y351460D03*
Y347560D03*
X853543Y518157D03*
Y528899D03*
X856189Y513114D03*
X876968Y518157D03*
Y528899D03*
X880314Y513114D03*
X870275Y518161D03*
Y528899D03*
X873621Y513114D03*
X890354Y518157D03*
Y528899D03*
X893000Y513114D03*
X913779Y518157D03*
Y528899D03*
X883661Y518157D03*
Y528899D03*
X886707Y513114D03*
X907086Y518157D03*
Y528899D03*
X910432Y513114D03*
X889200Y495900D03*
X893000Y495694D03*
X913779Y498487D03*
X882900Y498500D03*
X886500Y490800D03*
X907086Y498487D03*
X910432Y493744D03*
X856189Y534700D03*
X880314Y535100D03*
X873621D03*
X893000Y534700D03*
X886621D03*
X910432Y535100D03*
X853543Y555957D03*
X856189Y572500D03*
Y550914D03*
X853543Y566699D03*
X876968Y555957D03*
X880314Y572900D03*
X876968Y566699D03*
X880314Y550914D03*
X870275Y555961D03*
X873621Y572900D03*
Y550914D03*
X870275Y566699D03*
X893000Y572500D03*
X890354Y555957D03*
X893000Y550914D03*
X890354Y566699D03*
X913779Y555957D03*
Y566699D03*
X886621Y572500D03*
X883661Y555957D03*
X886707Y550914D03*
X883661Y566699D03*
X910432Y572900D03*
X907086Y555957D03*
X910432Y550914D03*
X907086Y566699D03*
X856189Y588714D03*
X880314D03*
X873621D03*
X893000D03*
X886707D03*
X910432D03*
X853543Y593757D03*
X856189Y610300D03*
X853543Y604499D03*
X876968Y593757D03*
X880314Y610700D03*
X876968Y604499D03*
X870275Y593761D03*
X873621Y610700D03*
X870275Y604499D03*
X893000Y610300D03*
X890354Y593757D03*
Y604499D03*
X913779Y593757D03*
Y604499D03*
X886621Y610300D03*
X883661Y593757D03*
Y604499D03*
X907086Y593757D03*
X910432Y610700D03*
X907086Y604499D03*
X917125Y34100D03*
X929811Y33700D03*
X927165Y27899D03*
X950590D03*
X923432Y33700D03*
X920472Y27899D03*
X947243Y34100D03*
X943897Y27899D03*
X917125Y-3700D03*
Y12114D03*
X929811Y-4100D03*
X927165Y17157D03*
Y-9901D03*
X929811Y12114D03*
X950590Y17157D03*
Y-9901D03*
X923432Y-4100D03*
X920472Y17157D03*
Y-9901D03*
X923518Y12114D03*
X947243Y-3700D03*
X943897Y17157D03*
Y-9901D03*
X947243Y12114D03*
X917125Y71900D03*
Y87714D03*
X929811Y71500D03*
X927165Y92757D03*
Y65699D03*
X929811Y87714D03*
X953936Y71900D03*
X950590Y92757D03*
Y65699D03*
X953936Y87714D03*
X923432Y71500D03*
X920472Y92757D03*
Y65699D03*
X923518Y87714D03*
X947243Y71900D03*
X943897Y92757D03*
Y65699D03*
X947243Y87714D03*
X917125Y49914D03*
X927165Y54957D03*
X929811Y49914D03*
X950590Y54957D03*
X920472D03*
X923518Y49914D03*
X943897Y54957D03*
X947243Y49914D03*
X917125Y107284D03*
X927165Y112327D03*
X929811Y106934D03*
X950590Y109700D03*
X953786Y107684D03*
X920472Y112327D03*
X923518Y107284D03*
X944497Y110927D03*
X947243Y105084D03*
X924227Y205210D03*
X920847Y207159D03*
X927607Y218860D03*
X930987Y216909D03*
X934367Y218860D03*
X947887Y214960D03*
X958026Y216909D03*
Y220809D03*
X944507Y216909D03*
Y220809D03*
X954647Y214960D03*
X951267Y213009D03*
X937747Y220809D03*
X951267Y216909D03*
Y220809D03*
X934367Y203260D03*
Y211060D03*
X944507Y205210D03*
Y209109D03*
X930987Y205210D03*
Y209109D03*
X941127Y203260D03*
Y211060D03*
X937747Y201309D03*
Y213009D03*
Y205210D03*
Y209109D03*
X917467D03*
X927607Y199360D03*
X924227Y201309D03*
X944507Y197409D03*
X924227Y209109D03*
X920847Y203260D03*
X930987Y228610D03*
X937747Y224709D03*
X920847Y257860D03*
X934367Y230559D03*
X937747Y228610D03*
X927607Y222760D03*
X947887D03*
X954647D03*
X920847Y242260D03*
Y261760D03*
Y246160D03*
Y250060D03*
X927607Y226660D03*
X951267Y224709D03*
X920847Y253960D03*
X917467Y248109D03*
X930987Y224709D03*
X934367Y222760D03*
X917467Y255909D03*
X974926Y238360D03*
Y246160D03*
X971546Y240309D03*
Y244209D03*
X930987Y267609D03*
X927607Y238360D03*
X930987Y236409D03*
X934367Y250060D03*
X937747Y248109D03*
X927607Y242260D03*
X934367Y238360D03*
X937747Y263709D03*
X927607Y257860D03*
X930987Y255909D03*
X934367Y269560D03*
X937747Y267609D03*
X927607Y261760D03*
X934367Y257860D03*
X930987Y248109D03*
X937747Y244209D03*
Y259809D03*
X927607Y246160D03*
X937747Y240309D03*
X927607Y265660D03*
X934367Y261760D03*
X930987Y244209D03*
X934367Y242260D03*
X930987Y263709D03*
X947887Y261760D03*
X944507Y232509D03*
X947887Y230559D03*
X951267Y244209D03*
X954647Y242260D03*
X944507Y236409D03*
X951267Y232509D03*
X961406Y230559D03*
X968166Y234460D03*
Y222760D03*
X971546Y224709D03*
X954647Y257860D03*
X961406Y234460D03*
X964786Y236409D03*
Y224709D03*
X971546Y228610D03*
X974926Y257860D03*
Y261760D03*
X944507Y252009D03*
X947887Y250060D03*
X951267Y263709D03*
X954647Y261760D03*
X944507Y255909D03*
X951267Y252009D03*
X947887Y242260D03*
X954647Y238360D03*
Y253960D03*
X944507Y240309D03*
X961406Y226660D03*
X964786Y263709D03*
X954647Y234460D03*
X971546Y232509D03*
X964786Y275409D03*
X944507Y259809D03*
X951267Y255909D03*
X947887Y238360D03*
X964786Y228610D03*
Y267609D03*
X951267Y236409D03*
X968166Y230559D03*
X964786Y271509D03*
X947887Y257860D03*
X961406Y265660D03*
Y273460D03*
X971546Y267609D03*
Y271509D03*
X958026Y267609D03*
Y271509D03*
X968166Y265660D03*
Y273460D03*
X937747Y279310D03*
X917000Y276000D03*
X920847Y277360D03*
X924227Y279310D03*
Y283209D03*
X927607Y281260D03*
X920847D03*
X916967Y279310D03*
X934367Y281260D03*
X930987Y279310D03*
Y283209D03*
X937747D03*
X944507D03*
Y279310D03*
X958026D03*
X954647Y281260D03*
X958026Y283209D03*
X951267Y279310D03*
Y283209D03*
X961406Y281260D03*
X941127D03*
X947887D03*
X917467Y271509D03*
X961406Y242260D03*
X964786Y244209D03*
X961406Y246160D03*
X964786Y248109D03*
X958026D03*
X968166Y250060D03*
X971546Y252009D03*
X944507Y267609D03*
X947887Y269560D03*
X951267Y271509D03*
X947887Y273460D03*
X941127D03*
X927607D03*
X974926Y277360D03*
X971546Y279310D03*
X944507Y271509D03*
X924227D03*
X920847Y335860D03*
Y331960D03*
Y343660D03*
Y339760D03*
X917467Y345609D03*
Y337809D03*
X937747Y333909D03*
X930987Y330009D03*
Y341709D03*
X927607Y339760D03*
X937747Y330009D03*
X934367Y328060D03*
Y339760D03*
X927607Y335860D03*
Y331960D03*
X934367Y335860D03*
X930987Y333909D03*
X937747Y337809D03*
X954647Y339760D03*
X947887Y335860D03*
X954647D03*
X951267Y333909D03*
X944507Y341709D03*
Y337809D03*
X968166Y328060D03*
Y335860D03*
X951267Y341709D03*
X947887Y339760D03*
X968166Y324160D03*
Y331960D03*
X954647Y343660D03*
X964786Y326110D03*
Y333909D03*
X974926Y328060D03*
Y331960D03*
X961406Y328060D03*
Y331960D03*
X971546Y326110D03*
Y333909D03*
X937747Y287109D03*
X920500Y304660D03*
Y300760D03*
X930987Y302709D03*
X924227D03*
X920500Y311960D03*
X927607Y304660D03*
X924227Y306609D03*
X930987D03*
Y310509D03*
X934367Y304660D03*
X924227Y310509D03*
X920500Y308560D03*
Y289060D03*
X934367Y296860D03*
X930987Y294909D03*
X920500Y296860D03*
Y292959D03*
X927607Y296860D03*
X924227Y298809D03*
X930987D03*
X920500Y285500D03*
X924227Y287109D03*
X930987D03*
X934367Y289060D03*
X924227Y291009D03*
X930987D03*
X927607Y289060D03*
X937747Y302709D03*
Y306609D03*
Y310509D03*
Y291009D03*
Y294909D03*
Y298809D03*
Y314409D03*
X924227D03*
X930987D03*
X934367Y312460D03*
X927607D03*
X920847Y324160D03*
X924227Y318309D03*
X920547Y316160D03*
X917167Y318309D03*
Y322209D03*
X917467Y326110D03*
X920847Y320260D03*
X971546Y294909D03*
X964786Y291009D03*
X951267Y287109D03*
X958026D03*
X961406Y296860D03*
X964786Y298809D03*
Y302709D03*
X971546D03*
X961406Y304660D03*
X958026Y302709D03*
X951267D03*
X968166Y308560D03*
X964786Y306609D03*
X968166Y304660D03*
X971546Y306609D03*
X974926Y304660D03*
Y308560D03*
X951267Y310509D03*
X954647Y304660D03*
X958026Y306609D03*
Y310509D03*
X951267Y306609D03*
X944507Y302709D03*
Y306609D03*
Y310509D03*
X941127Y304660D03*
X947887D03*
X944507Y294909D03*
Y287109D03*
X971546Y298809D03*
X974926Y285160D03*
Y296860D03*
Y289060D03*
X968166Y285160D03*
X964786Y287109D03*
X944507Y291009D03*
X941127Y289060D03*
Y296860D03*
X944507Y298809D03*
X947887Y289060D03*
Y296860D03*
X968166D03*
X964786Y294909D03*
X971546Y291009D03*
Y287109D03*
X968166Y289060D03*
X961406D03*
X958026Y298809D03*
X951267D03*
Y291009D03*
X958026D03*
X954647Y289060D03*
Y296860D03*
X958026Y294909D03*
X951267D03*
X944507Y314409D03*
X951267D03*
X958026D03*
X961406Y312460D03*
X954647D03*
X941127D03*
X947887D03*
X951267Y326110D03*
X958026Y322209D03*
X954647Y320260D03*
X961406D03*
X954647Y324160D03*
X951267Y322209D03*
X964786Y318309D03*
X971546D03*
X974926Y320260D03*
X968166Y316360D03*
X974926D03*
X971546Y314409D03*
X947887Y320260D03*
X941127D03*
X934367D03*
X927607Y324160D03*
X944507Y326110D03*
Y330009D03*
X971546Y341709D03*
Y345609D03*
X937747Y372909D03*
X930987Y369010D03*
Y380709D03*
X927607Y378760D03*
X937747Y369010D03*
X934367Y367060D03*
Y378760D03*
X927607Y374860D03*
X947887D03*
Y382660D03*
X958026Y376809D03*
Y380709D03*
X944507Y376809D03*
Y380709D03*
X954647Y374860D03*
Y382660D03*
X920847Y351460D03*
Y347560D03*
X934367Y374860D03*
X951267Y376809D03*
X927607Y370959D03*
X951267Y384609D03*
X937747Y376809D03*
X951267Y372909D03*
X930987D03*
X951267Y380709D03*
X974926Y351460D03*
Y359260D03*
X971546Y353409D03*
Y357309D03*
X934367Y359260D03*
X930987Y361209D03*
X937747Y349509D03*
X934367Y347560D03*
X927607Y355360D03*
Y359260D03*
X934367Y386560D03*
Y394359D03*
X944507Y388509D03*
Y392410D03*
X930987Y388509D03*
Y392410D03*
X941127Y386560D03*
Y394359D03*
X937747Y353409D03*
X930987Y349509D03*
X934367Y355360D03*
X937747Y388509D03*
X927607Y351460D03*
X937747Y396309D03*
Y357309D03*
Y384609D03*
X930987Y353409D03*
X937747Y392410D03*
X951267Y365109D03*
X947887Y367060D03*
X954647Y355360D03*
X951267Y353409D03*
X944507Y361209D03*
Y365109D03*
X968166Y363160D03*
X961406Y367060D03*
X971546Y372909D03*
X968166Y374860D03*
X964786Y361209D03*
X961406Y363160D03*
X971546Y369010D03*
X964786Y372909D03*
X947887Y347560D03*
X944507Y345609D03*
X951267D03*
X954647Y359260D03*
X947887Y355360D03*
X951267Y361209D03*
X968166Y367060D03*
X944507Y357309D03*
X961406Y370959D03*
X954647Y363160D03*
X971546Y365109D03*
X947887Y359260D03*
X964786Y369010D03*
Y349509D03*
Y353409D03*
X961406Y355360D03*
Y347560D03*
Y351460D03*
X924227Y400209D03*
X930987D03*
X920847Y394359D03*
X917467Y392410D03*
X944507Y400209D03*
X964786Y384609D03*
Y380709D03*
X920847Y398260D03*
X927607D03*
X958026Y349509D03*
X924227Y396309D03*
X917125Y513114D03*
X927165Y518157D03*
Y528899D03*
X929811Y513114D03*
X950590Y518157D03*
Y528899D03*
X953936Y513114D03*
X920472Y518157D03*
Y528899D03*
X923518Y513114D03*
X943897Y518157D03*
Y528899D03*
X947243Y513114D03*
X917192Y493919D03*
X927165Y498644D03*
X929811Y493244D03*
X950700Y493300D03*
X954000Y494700D03*
X920700Y498644D03*
X923600Y493744D03*
X944000Y493100D03*
X947443Y494944D03*
X917125Y535100D03*
X929811Y534700D03*
X953936Y535100D03*
X923432Y534700D03*
X947243Y535100D03*
X917125Y572900D03*
Y550914D03*
X929811Y572500D03*
X927165Y555957D03*
Y566699D03*
X929811Y550914D03*
X953936Y572900D03*
X950590Y555957D03*
X953936Y550914D03*
X950590Y566699D03*
X923432Y572500D03*
X920472Y555957D03*
Y566699D03*
X923518Y550914D03*
X947243Y572900D03*
X943897Y555957D03*
X947243Y550914D03*
X943897Y566699D03*
X917125Y588714D03*
X929811D03*
X923518D03*
X947243D03*
X917125Y610700D03*
X929811Y610300D03*
X927165Y593757D03*
Y604499D03*
X950590Y593757D03*
Y604499D03*
X923432Y610300D03*
X920472Y593757D03*
Y604499D03*
X947243Y610700D03*
X943897Y593757D03*
Y604499D03*
X988446Y250060D03*
X978306Y236409D03*
Y248109D03*
Y240309D03*
Y244209D03*
X985066Y240309D03*
Y244209D03*
X981686Y238360D03*
Y246160D03*
X978306Y255909D03*
Y263709D03*
X988446Y257860D03*
Y261760D03*
X985066Y255909D03*
Y263709D03*
X981686Y253960D03*
Y265660D03*
Y257860D03*
Y261760D03*
X995206Y277360D03*
Y281260D03*
X998586Y267609D03*
Y271509D03*
Y275409D03*
Y279310D03*
Y283209D03*
X1022245Y253960D03*
X1017735Y264300D03*
X1014355Y266300D03*
X1021115Y262300D03*
X1024495Y260300D03*
X1005345Y263709D03*
X1001965Y265660D03*
X1008725Y261760D03*
X1006665Y277360D03*
Y281260D03*
X1015485Y257860D03*
X1018865Y255909D03*
X1012105Y259809D03*
X981686Y222760D03*
X978306Y224709D03*
X981686Y226660D03*
X985066Y228610D03*
X978306D03*
X981686Y230559D03*
X985066Y232509D03*
X1008725Y250060D03*
X1001965D03*
X995206D03*
X1005345Y252009D03*
X998586D03*
X1008725Y253960D03*
X1001965D03*
X995206D03*
X1005345Y255909D03*
X998586D03*
X1001965Y257860D03*
X995206D03*
X998586Y259809D03*
X995206Y261760D03*
X988446Y269560D03*
X985066Y271509D03*
X978306D03*
X988446Y273460D03*
X981686D03*
X985066Y275409D03*
X978306D03*
X988446Y277360D03*
X981686D03*
X985066Y279310D03*
X978306D03*
X1015485Y250060D03*
X1012105Y252009D03*
X991826D03*
X998586Y337809D03*
X981686Y335860D03*
Y343660D03*
X991826Y337809D03*
Y341709D03*
X978306Y337809D03*
Y341709D03*
X988446Y335860D03*
Y343660D03*
X985066Y337809D03*
Y333909D03*
Y341709D03*
X995206Y296860D03*
X985066Y294909D03*
Y287109D03*
X988446Y285160D03*
X991826Y287109D03*
X978306Y298809D03*
Y287109D03*
X981686Y285160D03*
X978306Y294909D03*
X981686Y296860D03*
Y289060D03*
X978306Y291009D03*
X998586Y302709D03*
Y306609D03*
Y310509D03*
Y287109D03*
Y294909D03*
Y291009D03*
Y298809D03*
X985066Y302709D03*
X978306D03*
X988446Y304660D03*
Y308560D03*
X985066Y306609D03*
X995206Y304660D03*
Y308560D03*
X991826Y306609D03*
X978306D03*
X981686Y308560D03*
Y304660D03*
X995206Y300760D03*
X991826Y302709D03*
X995206Y292959D03*
X988446Y296860D03*
X991826Y294909D03*
X995206Y289060D03*
X988446D03*
X991826Y291009D03*
X985066D03*
X995206Y285160D03*
X985066Y298809D03*
X991826D03*
X998586Y314409D03*
X995206Y312460D03*
X998586Y318309D03*
Y322209D03*
Y326110D03*
Y330009D03*
X995206Y316360D03*
X1006665Y300760D03*
Y304660D03*
Y308560D03*
Y285160D03*
Y296860D03*
Y289060D03*
Y292959D03*
X1008725Y335860D03*
X1005345Y333909D03*
X1001965Y331960D03*
X1007595Y327609D03*
X1021115Y335409D03*
X1018865Y341709D03*
X1017735Y333460D03*
X1015485Y339760D03*
X1024495Y337360D03*
X1012105Y337809D03*
X1006665Y312460D03*
X1014355Y331509D03*
X1010975Y329560D03*
X1027875Y339309D03*
X1034635Y343209D03*
X1031255Y341260D03*
X1006665Y324160D03*
Y316360D03*
Y320260D03*
X1022245Y343660D03*
X981686Y324160D03*
X988446Y320260D03*
X985066Y322209D03*
Y318309D03*
X988446Y324160D03*
Y328060D03*
X981686D03*
X985066Y326110D03*
X981686Y320260D03*
X978306Y322209D03*
Y318309D03*
X981686Y316360D03*
X978306Y314409D03*
X985066D03*
X998586Y341709D03*
Y345609D03*
X1001965Y343660D03*
Y339760D03*
X1008725Y343660D03*
X1012105Y345609D03*
X1005345Y341709D03*
X978306Y353409D03*
Y361209D03*
Y349509D03*
Y357309D03*
X985066Y353409D03*
Y357309D03*
X981686Y351460D03*
Y359260D03*
X985066Y345609D03*
X1005345D03*
X1032385Y353409D03*
X1035765Y355360D03*
X981686Y374860D03*
X978306Y372909D03*
X981686Y370959D03*
X978306Y369010D03*
X985066D03*
X981686Y367060D03*
X985066Y365109D03*
X1029005Y351460D03*
X995206Y347560D03*
X1001965D03*
X1085721Y220096D03*
X1095861Y222047D03*
X1082341D03*
X1092481Y220096D03*
X1089101Y218147D03*
Y222047D03*
X1065242Y220096D03*
Y216196D03*
X1075582Y222047D03*
X1072202Y220096D03*
X1068822Y218147D03*
Y222047D03*
X1065242Y239596D03*
Y243496D03*
X1068822Y245447D03*
X1085721Y227896D03*
X1095861Y225947D03*
X1082341D03*
X1092481Y227896D03*
X1089101Y229847D03*
Y225947D03*
X1075582D03*
X1065242Y227896D03*
Y231797D03*
X1072202Y227896D03*
X1068822Y225947D03*
Y229847D03*
X1075582Y233746D03*
Y241547D03*
X1085721Y235696D03*
Y239596D03*
X1072202Y235696D03*
Y239596D03*
X1082341Y233746D03*
Y241547D03*
X1095861Y233746D03*
Y241547D03*
X1092481Y235696D03*
Y239596D03*
X1078962Y231797D03*
X1099241D03*
X1078962Y243496D03*
X1099241D03*
X1078962Y235696D03*
X1099241D03*
X1078962Y239596D03*
X1099241D03*
X1087971Y257800D03*
X1091351Y259600D03*
X1094731Y261500D03*
X1098111Y263400D03*
X1084591Y255497D03*
X1081212Y257600D03*
X1092481Y247396D03*
X1089101Y245447D03*
X1085721Y247396D03*
X1089101Y249347D03*
X1092481Y251296D03*
X1095861Y249347D03*
Y253247D03*
X1072202Y247396D03*
X1038015Y345160D03*
X1044774D03*
X1051534D03*
X1098111Y344597D03*
X1044256Y338341D03*
X1076435Y343595D03*
X1042524Y355360D03*
X1045904Y357309D03*
X1039145D03*
X1093601Y381947D03*
Y389747D03*
X1090221Y383896D03*
Y387796D03*
X1096981Y383896D03*
Y391696D03*
Y379996D03*
Y387796D03*
X1073322Y389747D03*
Y393647D03*
X1083462Y383896D03*
Y387796D03*
X1073322Y378047D03*
Y381947D03*
X1080082D03*
Y389747D03*
X1076702Y383896D03*
Y391696D03*
Y379996D03*
Y387796D03*
Y364396D03*
X1073322Y370247D03*
X1086841Y366347D03*
Y370247D03*
X1073322Y358547D03*
Y366347D03*
X1083462Y364396D03*
Y372197D03*
X1093601Y354647D03*
Y362447D03*
X1090221Y356596D03*
Y360496D03*
X1080082Y366347D03*
X1096981Y356596D03*
X1080082Y370247D03*
X1096981Y364396D03*
X1080082Y362447D03*
X1096981Y352696D03*
X1080082Y374146D03*
X1096981Y360496D03*
X1049284Y359260D03*
X1041395Y347109D03*
X1048154D03*
X1071072Y348497D03*
X1087971Y346546D03*
X1074452D03*
X1081212D03*
X1077832Y348497D03*
X1084591D03*
X1052664Y357309D03*
X1061039Y359351D03*
X1060694Y355360D03*
X1052664Y353409D03*
X1086841Y378047D03*
X1090221Y376096D03*
X1093601Y374146D03*
Y370247D03*
X1049284Y355360D03*
X1080082Y358547D03*
X1083462Y356596D03*
X1110520Y71500D03*
X1107874Y92757D03*
Y65699D03*
X1110520Y87714D03*
X1134645Y71900D03*
X1131299Y92757D03*
Y65699D03*
X1134645Y87714D03*
X1101181Y92757D03*
X1104141Y71500D03*
X1101181Y65699D03*
X1104227Y87714D03*
X1127952Y71900D03*
X1124606Y92757D03*
Y65699D03*
X1127952Y87714D03*
X1147331Y71500D03*
X1144685Y92757D03*
Y65699D03*
X1147331Y87714D03*
X1140952Y71500D03*
X1137992Y92757D03*
Y65699D03*
X1141038Y87714D03*
X1144535Y112357D03*
X1147331Y106964D03*
X1138242Y112357D03*
X1141038Y106964D03*
X1106001Y220096D03*
X1116141Y222047D03*
X1102621D03*
X1112761Y220096D03*
X1126280D03*
X1122900Y222047D03*
X1133040Y216196D03*
Y220096D03*
X1109381Y218147D03*
X1129660D03*
X1109381Y222047D03*
X1129660D03*
Y210346D03*
X1133040Y212296D03*
X1144300Y216196D03*
Y212296D03*
X1147680Y218147D03*
X1154440Y214247D03*
X1151060Y220096D03*
X1157820Y216196D03*
X1144300Y220096D03*
X1147680Y214247D03*
X1151060Y216196D03*
X1154440Y218147D03*
Y222047D03*
X1161200Y214247D03*
X1134160Y272747D03*
Y276646D03*
X1151060Y270796D03*
Y255196D03*
Y251296D03*
X1154440Y280547D03*
X1157820Y282496D03*
X1144300D03*
X1140920Y280547D03*
X1136420Y261047D03*
X1133040Y262996D03*
X1147680Y264947D03*
X1106001Y227896D03*
X1116141Y225947D03*
X1102621D03*
X1112761Y227896D03*
X1126280D03*
X1133040D03*
Y231797D03*
X1122900Y225947D03*
X1109381Y229847D03*
X1129660Y225947D03*
X1109381D03*
X1129660Y229847D03*
X1116141Y233746D03*
Y241547D03*
X1126280Y235696D03*
Y239596D03*
X1112761Y235696D03*
Y239596D03*
X1122900Y233746D03*
Y241547D03*
X1119521Y231797D03*
Y243496D03*
Y235696D03*
Y239596D03*
X1106001Y235696D03*
Y239596D03*
X1102621Y233746D03*
Y241547D03*
X1106001Y247396D03*
Y255196D03*
X1116141Y249347D03*
Y253247D03*
X1102621Y249347D03*
Y253247D03*
X1112761Y247396D03*
Y255196D03*
X1126280Y247396D03*
Y255196D03*
X1136420Y249347D03*
Y253247D03*
X1122900Y249347D03*
Y253247D03*
X1133040Y247396D03*
Y255196D03*
X1109381Y245447D03*
X1129660D03*
X1109381Y257147D03*
X1129660D03*
X1109381Y249347D03*
X1129660D03*
X1109381Y253247D03*
X1129660D03*
X1147680Y280547D03*
X1157820Y274696D03*
X1154440Y268847D03*
X1140920Y272747D03*
X1114340Y280560D03*
X1154440Y276647D03*
X1101491Y265400D03*
X1104871Y267300D03*
X1119521Y282496D03*
X1116141Y268847D03*
X1112761Y262996D03*
X1116141Y261047D03*
X1119521Y278596D03*
X1144300Y223996D03*
X1154440Y225947D03*
X1147680Y245447D03*
X1127400Y280547D03*
Y276646D03*
X1134160Y280547D03*
X1102336Y274819D03*
X1108125Y276799D03*
X1144300Y266896D03*
X1154440Y257147D03*
X1157820Y251296D03*
X1154440Y249347D03*
X1157820Y247396D03*
X1107600Y271900D03*
X1147680Y249347D03*
X1157820Y266896D03*
X1147680Y276647D03*
X1140920D03*
X1161200Y276646D03*
X1154440Y272747D03*
X1147680Y253247D03*
Y257147D03*
X1109381Y264947D03*
X1151060Y243496D03*
X1144300Y239596D03*
X1151060Y235696D03*
X1144300Y227896D03*
X1154440Y233746D03*
X1147680Y229847D03*
X1154440Y237647D03*
X1157820Y227896D03*
X1147680Y241547D03*
Y237647D03*
X1151060Y239596D03*
X1144300Y231797D03*
X1151060D03*
Y227896D03*
X1157820Y235696D03*
X1161200Y237647D03*
Y280547D03*
X1130780Y282496D03*
X1119521Y266896D03*
Y262996D03*
X1122900Y261047D03*
X1119521Y259096D03*
X1157820Y243496D03*
X1147680Y272747D03*
X1151060Y278596D03*
X1133040Y239596D03*
X1137540Y266896D03*
X1147680Y268847D03*
X1137540Y270796D03*
X1140920Y268847D03*
Y264947D03*
X1144300Y262996D03*
X1126280Y266896D03*
X1129660Y264947D03*
X1122900D03*
Y268847D03*
X1126280Y262996D03*
X1154440Y264947D03*
X1147680Y261047D03*
X1144300Y259096D03*
X1151060Y262996D03*
X1154440Y261047D03*
X1144300Y274696D03*
X1124021Y344896D03*
X1130780Y321496D03*
X1137540Y313696D03*
X1130780Y325396D03*
X1140920Y315647D03*
X1134160Y319547D03*
X1130780Y317596D03*
Y333196D03*
X1134160Y331247D03*
X1151060Y337096D03*
X1140920Y288347D03*
Y284447D03*
X1147680D03*
Y288347D03*
X1151060Y286396D03*
X1144300Y290296D03*
X1147680Y292247D03*
X1154440D03*
Y288347D03*
Y284447D03*
X1157820Y286396D03*
X1114839Y320075D03*
X1113132Y291702D03*
X1113500Y323400D03*
X1137540Y286396D03*
X1101491Y342646D03*
X1119521Y301996D03*
Y298096D03*
Y294196D03*
Y290296D03*
X1118391Y332897D03*
X1127400Y284447D03*
Y300047D03*
X1130780Y294196D03*
X1127400Y296147D03*
Y292247D03*
X1130780Y298096D03*
Y305896D03*
X1137540Y290296D03*
X1134160Y296147D03*
Y288347D03*
X1124021Y325396D03*
X1127400Y323446D03*
X1124021Y329296D03*
Y333196D03*
X1154440Y327347D03*
X1147680Y339047D03*
X1157820Y321496D03*
X1134160Y284447D03*
X1157820Y309797D03*
X1120641Y339047D03*
X1113881Y342947D03*
X1130780Y329296D03*
Y286396D03*
X1134160Y311747D03*
Y315647D03*
X1161200Y288347D03*
Y292247D03*
X1140920Y323446D03*
X1147680Y307847D03*
X1151060Y309797D03*
Y305896D03*
X1144300Y301996D03*
Y298096D03*
X1137540Y301996D03*
X1134160Y303947D03*
X1137540Y298096D03*
X1140920Y303947D03*
X1137540Y305896D03*
X1140920Y296147D03*
X1137540Y294196D03*
X1120641Y342947D03*
X1140920D03*
X1110501Y344896D03*
X1119521Y309797D03*
Y313696D03*
Y317596D03*
X1127400Y311747D03*
X1154440D03*
X1157820Y305896D03*
X1154440Y303947D03*
X1157820Y301996D03*
X1154440Y300047D03*
X1134160Y307847D03*
X1151060Y294196D03*
X1147680Y300047D03*
Y296147D03*
X1140920Y307847D03*
Y311747D03*
X1151060Y301996D03*
X1144300Y305896D03*
X1147680Y311747D03*
X1157820Y298096D03*
X1154440Y296147D03*
X1134160Y335147D03*
Y339047D03*
X1140920Y319547D03*
X1144300Y313696D03*
X1151060D03*
X1144300Y325396D03*
Y321496D03*
X1151060Y329296D03*
X1147680Y335147D03*
Y331247D03*
X1140920Y335147D03*
X1144300Y333196D03*
X1151060Y325396D03*
Y321496D03*
X1147680Y323446D03*
X1137540Y329296D03*
X1144300D03*
X1140920Y327347D03*
X1130780Y340996D03*
Y337096D03*
X1127400Y331247D03*
Y335147D03*
Y339047D03*
X1147680Y315647D03*
X1151060Y317596D03*
X1137540Y337096D03*
Y340996D03*
Y333196D03*
X1134160Y342947D03*
X1137540Y344896D03*
X1144300Y317596D03*
X1137540Y321496D03*
X1134160Y327347D03*
X1137540Y325396D03*
X1109200Y325100D03*
X1127400Y346847D03*
X1130780Y348796D03*
X1127400Y350747D03*
X1103741Y383896D03*
Y387796D03*
X1100361Y381947D03*
Y389747D03*
X1113881Y381947D03*
Y389747D03*
X1124021Y383896D03*
Y387796D03*
X1110501Y383896D03*
Y387796D03*
X1120641Y381947D03*
Y389747D03*
X1134160Y381947D03*
Y389747D03*
X1144300Y395597D03*
Y399496D03*
X1130780Y383896D03*
Y387796D03*
X1140920Y401447D03*
Y393647D03*
X1117261Y379996D03*
X1137540D03*
X1117261Y391696D03*
X1137540D03*
X1117261Y383896D03*
X1137540D03*
X1117261Y387796D03*
X1137540D03*
X1124021Y368296D03*
Y376096D03*
X1130780Y364396D03*
X1134160Y374146D03*
X1120641Y370247D03*
Y374146D03*
X1130780Y368296D03*
Y376096D03*
X1127400Y370247D03*
Y378047D03*
Y366347D03*
Y374146D03*
X1103741Y368296D03*
Y376096D03*
X1113881Y370247D03*
Y374146D03*
X1100361Y370247D03*
Y374146D03*
X1110501Y368296D03*
Y376096D03*
X1103741Y356596D03*
Y360496D03*
X1100361Y354647D03*
Y362447D03*
X1113881Y354647D03*
Y362447D03*
X1124021Y356596D03*
Y360496D03*
X1110501Y356596D03*
Y360496D03*
X1120641Y354647D03*
Y362447D03*
X1107121Y370247D03*
X1117261Y356596D03*
X1107121Y378047D03*
X1117261Y364396D03*
X1107121Y366347D03*
X1117261Y352696D03*
X1107121Y374146D03*
X1117261Y360496D03*
X1157820Y356596D03*
X1144300Y352696D03*
X1154440Y350747D03*
Y362447D03*
X1144300Y368296D03*
X1157820Y379996D03*
X1147680Y389747D03*
X1144300Y376096D03*
X1151060Y383896D03*
X1161200Y362447D03*
X1157820Y364396D03*
X1154440Y370246D03*
X1157820Y376096D03*
X1151060Y372196D03*
X1147680Y378047D03*
X1144300Y379996D03*
Y387796D03*
X1161200Y358547D03*
Y366347D03*
X1157820Y368296D03*
Y372196D03*
X1154440Y374146D03*
X1151060Y376096D03*
X1147680Y381947D03*
X1144300Y383896D03*
X1161200Y354647D03*
X1107121Y350747D03*
X1113881Y346847D03*
X1147680Y370247D03*
Y374146D03*
X1120641Y346847D03*
X1161200Y389747D03*
X1154440Y397546D03*
Y393647D03*
X1151060Y387796D03*
X1157820Y395597D03*
X1154440Y389747D03*
X1157820Y391696D03*
X1154440Y385847D03*
X1140920Y354647D03*
X1161201Y401447D03*
X1157820Y383896D03*
X1137540Y356596D03*
X1156699Y401447D03*
X1134160Y358547D03*
X1137540Y352696D03*
X1130780Y356596D03*
X1134160Y354647D03*
Y350747D03*
X1137540Y348796D03*
X1107874Y518157D03*
Y528899D03*
X1110520Y513114D03*
X1131299Y518157D03*
Y528899D03*
X1134645Y513114D03*
X1101181Y518157D03*
X1104227Y513114D03*
X1101181Y528899D03*
X1124606Y518157D03*
Y528899D03*
X1127952Y513114D03*
X1144685Y518157D03*
X1147331Y513114D03*
X1144685Y528899D03*
X1137992Y518157D03*
X1141038Y513114D03*
X1137992Y528899D03*
X1144385Y498487D03*
X1147331Y490894D03*
X1137992Y498487D03*
X1141038Y491144D03*
X1110520Y534700D03*
X1134645Y535100D03*
X1104141Y534700D03*
X1127952Y535100D03*
X1147331Y534700D03*
X1140952D03*
X1171456Y71900D03*
X1168110Y92757D03*
Y65699D03*
X1171456Y87714D03*
X1164763Y71900D03*
X1161417Y92757D03*
Y65699D03*
X1164763Y87714D03*
X1181496Y92757D03*
X1184142Y71500D03*
Y87714D03*
X1181496Y65699D03*
X1208267Y71900D03*
X1204921Y92757D03*
X1208267Y87714D03*
X1204921Y65699D03*
X1177763Y71500D03*
X1174803Y92757D03*
Y65699D03*
X1177849Y87714D03*
X1201574Y71900D03*
X1198228Y92757D03*
X1201574Y87714D03*
X1198228Y65699D03*
X1220953Y71500D03*
X1218307Y92757D03*
X1220953Y87714D03*
X1218307Y65699D03*
X1214574Y71500D03*
X1211614Y92757D03*
X1214874Y87374D03*
X1211614Y65699D03*
X1167925Y112357D03*
X1170721Y106964D03*
X1161632Y112357D03*
X1164428Y106964D03*
X1181496Y112357D03*
X1184142Y106964D03*
X1204921Y112357D03*
X1208267Y107314D03*
X1174742Y112357D03*
X1177849Y107314D03*
X1198228Y112357D03*
X1201574Y107314D03*
X1208519Y218147D03*
X1167960Y222047D03*
X1164580Y220096D03*
X1161200Y222047D03*
X1171339Y216196D03*
X1181479Y218147D03*
X1191619Y208397D03*
X1209033Y183907D03*
X1188239Y202247D03*
X1181479Y202547D03*
X1174719D03*
X1178099Y204496D03*
X1181479Y214247D03*
X1178099Y212296D03*
X1184859Y208397D03*
Y220096D03*
X1191619Y216196D03*
X1194999Y214247D03*
Y218147D03*
X1198379Y220096D03*
X1201759Y222047D03*
X1164580Y212296D03*
Y208397D03*
X1167960Y214247D03*
X1174719Y210346D03*
X1184859Y216196D03*
X1181479Y210346D03*
X1184859Y212296D03*
X1188239Y218147D03*
X1191619Y220096D03*
Y212296D03*
X1198379Y216196D03*
X1205139Y220096D03*
X1164580Y216196D03*
X1167960Y210346D03*
X1171339Y212296D03*
X1174719Y214247D03*
Y222047D03*
X1221767Y175858D03*
X1220580Y179810D03*
X1161200Y268847D03*
X1164580Y255196D03*
X1171339Y270796D03*
X1164580Y282496D03*
X1167960Y280547D03*
X1171339Y282496D03*
X1167960Y261047D03*
X1174719D03*
X1164580Y251296D03*
X1167960Y272747D03*
X1171339Y255196D03*
Y251296D03*
X1161200Y245447D03*
X1164580Y243496D03*
Y274696D03*
X1174719Y272747D03*
X1167960Y257147D03*
X1161200Y272747D03*
X1191619Y223996D03*
X1178099D03*
X1167960Y233746D03*
X1178099Y270796D03*
Y278596D03*
X1181479Y249347D03*
Y237647D03*
Y241547D03*
X1184859Y223996D03*
X1201759Y237647D03*
X1198379Y227896D03*
X1205139Y231797D03*
X1201759Y245447D03*
X1194999Y237647D03*
X1198379Y251296D03*
X1181479Y264947D03*
X1184859Y255196D03*
X1191619Y270796D03*
X1198379Y262996D03*
X1194999Y276646D03*
X1198379Y282496D03*
Y270796D03*
X1178099Y266896D03*
X1162300Y264947D03*
X1167960Y249347D03*
X1181479Y257147D03*
X1178099Y255196D03*
X1161200Y253247D03*
X1174719Y268847D03*
X1167960Y241547D03*
Y245447D03*
Y237647D03*
X1171339Y239596D03*
Y243496D03*
X1174719Y241547D03*
X1178099Y239596D03*
X1174719Y249347D03*
Y245447D03*
X1171339Y278596D03*
X1178099Y262996D03*
X1205139Y255196D03*
X1208519Y249347D03*
X1201759Y253247D03*
X1205139Y243496D03*
X1212199Y239596D03*
X1205139Y235696D03*
X1212199Y227896D03*
X1208519Y225947D03*
X1205139Y282496D03*
X1201759Y280547D03*
X1198379Y274696D03*
X1201759Y272747D03*
X1205139Y270796D03*
X1201759Y264947D03*
X1205139Y262996D03*
X1208519Y257147D03*
Y253247D03*
X1205139Y251296D03*
X1208519Y241547D03*
Y237647D03*
X1205139Y239596D03*
X1212199Y231797D03*
Y223996D03*
X1205139Y278596D03*
X1201759Y276646D03*
Y268847D03*
X1208519D03*
X1205139Y266896D03*
Y259096D03*
Y223996D03*
X1198379D03*
X1205139Y227896D03*
X1178099Y282496D03*
X1184859Y262996D03*
X1191619Y259096D03*
X1194999Y261047D03*
Y257147D03*
X1188239Y253247D03*
X1194999Y249347D03*
X1198379Y247396D03*
X1191619Y243496D03*
X1188239Y241547D03*
X1181479Y245447D03*
X1184859Y278596D03*
X1188239Y276646D03*
Y280547D03*
X1181479Y272747D03*
X1188239Y268847D03*
X1191619Y266896D03*
X1181479Y280547D03*
X1188239Y261047D03*
X1191619Y262996D03*
X1198379Y259096D03*
X1191619Y255196D03*
Y251296D03*
X1194999Y253247D03*
Y245447D03*
Y241547D03*
X1188239Y245447D03*
X1184859Y243496D03*
Y282496D03*
Y274696D03*
X1191619Y282496D03*
Y278596D03*
X1184859Y270796D03*
X1188239Y272747D03*
Y264947D03*
X1174719Y229847D03*
X1167960Y225947D03*
X1174719Y233746D03*
X1181479Y229847D03*
X1184859Y227896D03*
Y231797D03*
X1191619Y235696D03*
Y227896D03*
X1198379Y231797D03*
X1161200Y233746D03*
Y229847D03*
X1171339Y227896D03*
Y223996D03*
X1174719Y225947D03*
X1178099Y231797D03*
X1181479Y233746D03*
Y225947D03*
X1188239Y229847D03*
Y233746D03*
X1191619Y231797D03*
X1194999Y229847D03*
X1161200Y225947D03*
X1164580Y231797D03*
X1174719Y257147D03*
X1178099Y259096D03*
X1174719Y276646D03*
X1167960D03*
Y268847D03*
X1181479Y253247D03*
X1178099Y251296D03*
X1167960Y264947D03*
X1171339Y262996D03*
X1174719Y264947D03*
X1208519Y229847D03*
X1184859Y337096D03*
X1178099Y340996D03*
X1181479Y339047D03*
Y342947D03*
X1178099Y344896D03*
X1201759Y331247D03*
Y335147D03*
Y342947D03*
X1198379Y344896D03*
Y333196D03*
X1201759Y339047D03*
X1205139Y340996D03*
X1181479Y331247D03*
X1167960Y284447D03*
X1198379Y321496D03*
X1194999Y323446D03*
X1181479Y315647D03*
X1171339Y344896D03*
X1174719Y339047D03*
X1164580Y340996D03*
X1167960Y331247D03*
X1171339Y321496D03*
X1184859Y325396D03*
Y333196D03*
X1198379Y337096D03*
Y329296D03*
X1194999Y342947D03*
X1174719Y323446D03*
X1181479D03*
X1174719Y327347D03*
X1178099Y333196D03*
X1171339Y329296D03*
X1167960Y335147D03*
X1171339Y340996D03*
X1174719Y319547D03*
X1178099Y321496D03*
Y325396D03*
Y329296D03*
X1174719Y331247D03*
X1171339Y333196D03*
Y337096D03*
X1161200Y311747D03*
X1198379Y290296D03*
Y294196D03*
X1161200Y300047D03*
Y303947D03*
X1201759Y292247D03*
X1205439Y290296D03*
Y294196D03*
Y286596D03*
X1208819Y284447D03*
X1184859Y286396D03*
X1191619D03*
X1194999Y284447D03*
X1181479D03*
X1191619Y290296D03*
Y313696D03*
Y309797D03*
X1188239Y307847D03*
Y303947D03*
Y300047D03*
X1184859Y298096D03*
Y344896D03*
X1191619D03*
Y340996D03*
Y337096D03*
X1188239Y331247D03*
X1194999Y327347D03*
X1188239D03*
X1184859Y317596D03*
X1191619D03*
X1194999Y311747D03*
X1191619Y305896D03*
X1184859D03*
X1191619Y301996D03*
X1188239Y296147D03*
X1181479D03*
X1184859Y340996D03*
X1188239Y342947D03*
X1194999Y339047D03*
X1191619Y333196D03*
Y329296D03*
Y325396D03*
X1188239Y323446D03*
X1184859Y313696D03*
X1188239Y315647D03*
X1174719Y303947D03*
X1167960D03*
X1178099Y309797D03*
X1171339Y305896D03*
X1164580Y309797D03*
Y305896D03*
X1167960Y307847D03*
Y311747D03*
X1171339Y309797D03*
X1178099Y301996D03*
X1174719Y311747D03*
Y307847D03*
X1178099Y305896D03*
Y313696D03*
X1171339D03*
X1164580D03*
X1174719Y292247D03*
Y288347D03*
X1171339Y286396D03*
Y290296D03*
X1167960Y300047D03*
X1164580Y298096D03*
X1167960Y296147D03*
Y292247D03*
Y288347D03*
X1161200Y296147D03*
X1178099Y290296D03*
X1171339Y298096D03*
Y294196D03*
X1174719Y296147D03*
Y346847D03*
X1178099Y348796D03*
Y352696D03*
X1201759Y346847D03*
X1167960Y358547D03*
X1174719Y350747D03*
X1167960Y366347D03*
X1171339Y368296D03*
X1161200Y374146D03*
X1178099Y391696D03*
X1174719Y397546D03*
X1164580Y399496D03*
X1188239Y370247D03*
X1191619Y372197D03*
Y364396D03*
Y352696D03*
X1181479Y385847D03*
Y405347D03*
X1188239Y381947D03*
X1208819Y385847D03*
X1164580Y368296D03*
X1167960Y350747D03*
Y354647D03*
X1164580Y360496D03*
Y364396D03*
X1167960Y346847D03*
X1171339Y352696D03*
X1184859Y348796D03*
X1188239Y346847D03*
X1178099Y387796D03*
X1171339D03*
Y391696D03*
X1167960Y393647D03*
X1164580Y395597D03*
X1178099Y379996D03*
Y383896D03*
X1174719Y385847D03*
X1171339Y383896D03*
X1174719Y389747D03*
X1171339Y395596D03*
X1164580Y391696D03*
Y387796D03*
X1178099Y376096D03*
X1181479Y381947D03*
X1188239Y354647D03*
Y358547D03*
Y362447D03*
X1181479D03*
Y366347D03*
X1184859Y372197D03*
Y376096D03*
Y379996D03*
X1188239Y350747D03*
X1191619Y356596D03*
X1184859Y360496D03*
X1181479Y358547D03*
X1184859Y364396D03*
Y368296D03*
X1188239Y374146D03*
X1181479Y378047D03*
X1174719Y370247D03*
X1181479D03*
X1171339Y364396D03*
X1178099Y360496D03*
Y356596D03*
X1184859Y352696D03*
X1161200Y393647D03*
Y385847D03*
X1167960D03*
Y381947D03*
Y378047D03*
X1174719D03*
Y374146D03*
Y366347D03*
X1178099Y368296D03*
X1174719Y362447D03*
Y358547D03*
X1181479Y354647D03*
Y350747D03*
X1161200Y381947D03*
X1164580Y383896D03*
X1171339Y379996D03*
X1167960Y374146D03*
X1171339Y376096D03*
X1178099Y372197D03*
X1167960Y405347D03*
X1194999Y378047D03*
X1201759Y374146D03*
X1194999D03*
X1198379Y364396D03*
Y360496D03*
Y356596D03*
X1174719Y405347D03*
Y401447D03*
X1178099Y395596D03*
X1184859Y399496D03*
X1181479Y393647D03*
X1188239Y389747D03*
Y385847D03*
X1191619Y379996D03*
X1198379Y383896D03*
X1167960Y401447D03*
X1198379Y376096D03*
Y372197D03*
X1194999Y370247D03*
Y362447D03*
X1201759Y358547D03*
X1198379Y352696D03*
X1171339Y403396D03*
X1178099Y399496D03*
X1181479Y397546D03*
X1184859Y395596D03*
Y391696D03*
Y387796D03*
X1191619Y383896D03*
X1194999Y381947D03*
X1198379Y379996D03*
X1164580Y376096D03*
X1194999Y350747D03*
X1198379Y348796D03*
X1168110Y518157D03*
X1171456Y513114D03*
X1168110Y528899D03*
X1161417Y518157D03*
Y528899D03*
X1164763Y513114D03*
X1181496Y518157D03*
Y528899D03*
X1184142Y513114D03*
X1204921Y518157D03*
X1208267Y513114D03*
X1204921Y528899D03*
X1174803Y518157D03*
Y528899D03*
X1177849Y513114D03*
X1198228Y518157D03*
X1201574Y513114D03*
X1198228Y528899D03*
X1218307Y518157D03*
X1220953Y513114D03*
X1218307Y528899D03*
X1211614Y518157D03*
X1214874Y512774D03*
X1211614Y528899D03*
X1167510Y498487D03*
X1170656Y493844D03*
X1161417Y498487D03*
X1164363Y493744D03*
X1180400Y498387D03*
X1184142Y493394D03*
X1204400Y498487D03*
X1208267Y496144D03*
X1174203Y498387D03*
X1177799Y493544D03*
X1198100Y498400D03*
X1200974Y493344D03*
X1171456Y535100D03*
X1164763D03*
X1184142Y534700D03*
X1208267Y535100D03*
X1177763Y534700D03*
X1201574Y535100D03*
X1220953Y534700D03*
X1214574D03*
X1245078Y71900D03*
X1241732Y92757D03*
X1245078Y87714D03*
X1241732Y65699D03*
X1238385Y71900D03*
X1235039Y92757D03*
X1238385Y87714D03*
X1235039Y65699D03*
X1261811D03*
X1258464D03*
X1251771Y84757D03*
X1248425Y92657D03*
X1265157Y73857D03*
X1261811D03*
X1258464D03*
X1261811Y84757D03*
X1258464D03*
X1265157D03*
X1251771Y73857D03*
X1261811Y92599D03*
X1258464D03*
X1255118Y65699D03*
Y92599D03*
Y84757D03*
Y73857D03*
X1265157Y65699D03*
Y92599D03*
X1270350Y98300D03*
X1251344Y127925D03*
X1259950Y144650D03*
X1277100Y122670D03*
X1272100Y141603D03*
X1264550Y114670D03*
X1277100Y114800D03*
X1261030Y105350D03*
X1277600Y106200D03*
X1248616Y133817D03*
X1237704Y148423D03*
X1268576Y117788D03*
X1250200Y122900D03*
X1251980Y106960D03*
X1262569Y147201D03*
X1243948Y154916D03*
X1269810Y154398D03*
X1275470Y99390D03*
X1252000Y145300D03*
X1257800Y120800D03*
X1255400Y108000D03*
X1252437Y140192D03*
X1249025Y130460D03*
X1240000Y129500D03*
X1259200Y168350D03*
X1281799Y193190D03*
X1267800Y161800D03*
X1271400Y161900D03*
X1240309D03*
X1267050Y169800D03*
X1233902Y173337D03*
X1241381Y172040D03*
X1246655Y176395D03*
X1263300Y169450D03*
X1268404Y246304D03*
X1279393Y247602D03*
X1270478Y243490D03*
X1277504Y250346D03*
X1272761Y240220D03*
X1283720Y223870D03*
X1249230Y402022D03*
X1262700Y461804D03*
X1262900Y466504D03*
X1277978Y491571D03*
X1241732Y518157D03*
Y528899D03*
X1245078Y513114D03*
X1235039Y518157D03*
X1238385Y513114D03*
X1235039Y528899D03*
X1278573Y519596D03*
X1265157Y510157D03*
X1261811Y517999D03*
X1258464Y510157D03*
Y517999D03*
X1261811Y510157D03*
X1248425Y518057D03*
X1251771Y510157D03*
X1258464Y528899D03*
X1261811D03*
X1255120Y518000D03*
Y510158D03*
X1271300Y510600D03*
X1271105Y498516D03*
X1274576Y510235D03*
X1265157Y528876D03*
Y517999D03*
X1262843Y497553D03*
X1258140Y474540D03*
X1271571Y479000D03*
X1271662Y487326D03*
X1256320Y490660D03*
X1258126Y469540D03*
X1271640Y474420D03*
X1271647Y482500D03*
X1256350Y486080D03*
X1245078Y535100D03*
X1238385D03*
X1265157Y537057D03*
X1261811D03*
X1251771D03*
X1258464D03*
X1255120Y537034D03*
X1277200Y539100D03*
X1293600Y-17000D03*
X1287700Y-16700D03*
X1303774Y-18842D03*
X1298422Y74000D03*
X1330300Y83500D03*
X1336850Y76450D03*
X1327168Y61483D03*
X1304685Y78827D03*
X1298754Y83233D03*
X1336900Y61600D03*
X1343260Y53770D03*
X1309700Y83300D03*
X1336500Y81100D03*
X1337400Y72000D03*
X1338500Y96000D03*
X1343500Y87500D03*
X1335120Y94450D03*
X1301219Y89141D03*
X1323000Y83000D03*
X1328500Y92500D03*
X1308400Y79600D03*
X1306900Y131744D03*
X1301900Y124400D03*
X1325125Y100001D03*
X1310098Y150040D03*
X1293700Y121800D03*
X1295700Y144450D03*
X1327900Y142918D03*
X1301770Y101300D03*
X1345257Y100000D03*
X1320500Y145000D03*
X1325100D03*
X1287790Y156575D03*
X1310175Y154696D03*
X1299907Y159808D03*
X1295500Y159970D03*
X1300300Y169900D03*
X1315130Y164870D03*
X1315180Y169950D03*
X1326474Y216500D03*
X1338224Y209051D03*
X1305171Y164767D03*
X1310061Y165235D03*
X1344462Y209272D03*
X1323030Y216531D03*
X1330100Y165000D03*
Y170000D03*
X1340100Y165000D03*
X1345100D03*
Y170000D03*
X1340100D03*
X1335100D03*
Y165000D03*
X1320100D03*
X1325100D03*
X1320100Y170000D03*
X1325100D03*
X1345050Y272350D03*
X1300444Y267919D03*
X1309462Y240229D03*
X1288800Y233900D03*
X1320289Y237671D03*
X1331400Y237900D03*
X1342400D03*
X1315100Y237645D03*
X1325900Y237900D03*
X1336900D03*
X1320400Y232118D03*
X1331400D03*
X1342400D03*
X1314900D03*
X1325900D03*
X1336900D03*
X1331650Y317250D03*
X1338700Y284700D03*
X1323750Y319750D03*
X1320900Y321300D03*
X1335250Y344250D03*
X1319310Y300795D03*
X1336336Y333825D03*
X1302768Y296942D03*
X1331720Y334810D03*
X1326300Y341309D03*
X1341375Y314675D03*
Y319675D03*
X1341740Y306760D03*
X1336240D03*
X1316600Y305500D03*
X1306290Y298255D03*
X1308887Y285015D03*
X1319888Y290205D03*
X1323688D03*
X1345700Y285300D03*
X1341740Y301243D03*
X1336240D03*
X1335400Y284900D03*
X1302203Y314439D03*
X1315496Y361190D03*
X1342570Y368220D03*
X1326014Y347732D03*
X1296468Y437500D03*
X1325100Y457500D03*
Y452500D03*
X1320100Y457500D03*
Y452500D03*
X1315100D03*
X1310100D03*
X1315100Y457500D03*
X1305100D03*
Y452500D03*
X1310100Y457500D03*
X1330100D03*
Y452500D03*
X1300315Y427902D03*
X1335100Y427500D03*
Y432500D03*
X1300438Y433001D03*
X1318054Y460507D03*
X1340100Y432500D03*
X1304200Y466600D03*
Y462030D03*
X1329419Y464337D03*
X1344761Y498282D03*
X1309870Y499254D03*
X1287770Y501897D03*
X1340986Y511187D03*
X1341050Y498275D03*
X1299450Y484950D03*
X1320300Y498300D03*
X1322260Y477492D03*
X1329419Y469337D03*
X1322360Y472592D03*
X1327956Y545655D03*
X1296295Y615596D03*
X1301384Y618119D03*
X1400616Y13795D03*
X1376094Y4406D03*
X1380678Y-422D03*
X1380950Y30232D03*
X1379025Y-9799D03*
X1407422Y13139D03*
X1377009Y39753D03*
X1347500Y83000D03*
X1355500D03*
X1359500D03*
X1358500Y74500D03*
X1363500Y77400D03*
X1370975Y67225D03*
X1370849Y59349D03*
X1371910Y48800D03*
X1351500Y83000D03*
X1367700Y86450D03*
X1371500Y63200D03*
X1351488Y74000D03*
X1347000Y87500D03*
X1360700Y86550D03*
X1372300Y86400D03*
X1406546Y43116D03*
X1353500Y96959D03*
X1348615Y96239D03*
X1357000Y86640D03*
X1383171Y57549D03*
X1401300Y149600D03*
X1384600Y108500D03*
X1381359Y108496D03*
X1388100Y108500D03*
X1371500Y101000D03*
X1404200Y119200D03*
X1402500Y116300D03*
X1399100Y166900D03*
X1396933Y215763D03*
X1353569Y208960D03*
X1348569D03*
X1367789Y209216D03*
X1384671Y214832D03*
X1402020Y165561D03*
X1350100Y170000D03*
X1380100Y165000D03*
X1355100Y170000D03*
X1360100D03*
X1355100Y165000D03*
X1360100D03*
X1350100D03*
X1365100Y170000D03*
Y165000D03*
X1370100D03*
X1375100Y170000D03*
X1370100D03*
X1375100Y165000D03*
X1380100Y170000D03*
X1399852Y252353D03*
X1407274Y245652D03*
X1353400Y237900D03*
X1364400D03*
X1375400D03*
X1386400D03*
X1347900D03*
X1358900D03*
X1369900D03*
X1380900D03*
X1391900D03*
X1353400Y232118D03*
X1364400D03*
X1375400D03*
X1347900D03*
X1358900D03*
X1369900D03*
X1380900D03*
X1391900D03*
X1365246Y285931D03*
X1363700Y321600D03*
X1367200D03*
X1352400Y285000D03*
X1396470Y330014D03*
X1392400Y330800D03*
X1400400Y335400D03*
X1388450Y331250D03*
X1359200Y322200D03*
X1364260Y331619D03*
X1349134Y317436D03*
X1360294Y315025D03*
X1371090Y315395D03*
X1380904Y315947D03*
X1392226Y315658D03*
X1400558Y320157D03*
X1349134Y321145D03*
X1360294Y318825D03*
X1371090Y319195D03*
X1380904Y319747D03*
X1392226Y319458D03*
X1400558Y316357D03*
X1353142Y306760D03*
X1364044Y306690D03*
X1374840Y307130D03*
X1386048Y307310D03*
X1397635Y307630D03*
X1347642Y306760D03*
X1358544Y306690D03*
X1369340Y307130D03*
X1380548Y307310D03*
X1392135Y307630D03*
X1403037D03*
X1368200Y284000D03*
X1353672Y299605D03*
X1364014Y300815D03*
X1374820Y301219D03*
X1386101Y301465D03*
X1397635Y302051D03*
X1347892Y299741D03*
X1358514Y300815D03*
X1369320Y301219D03*
X1380601Y301465D03*
X1392135Y302051D03*
X1403037Y302046D03*
X1355300Y321675D03*
X1381431Y284259D03*
X1394370Y384230D03*
X1378207Y394568D03*
X1394260Y351170D03*
X1389500Y360500D03*
X1391845Y348325D03*
X1388300Y346200D03*
X1371600Y368700D03*
X1374300Y377885D03*
Y381485D03*
X1380872Y378098D03*
X1380900Y383164D03*
X1388900Y387800D03*
X1378200Y346900D03*
X1377028Y458125D03*
X1372028D03*
X1360100Y447500D03*
Y452500D03*
Y457500D03*
X1385100Y452500D03*
Y447500D03*
X1390100Y457500D03*
X1389900Y447400D03*
X1390100Y452500D03*
X1395100Y432500D03*
Y447500D03*
Y427500D03*
X1349800Y458200D03*
X1350100Y447500D03*
Y452500D03*
X1375100Y447500D03*
X1362560Y463478D03*
X1370100Y452500D03*
X1375100D03*
X1385100Y427500D03*
Y442500D03*
Y437500D03*
X1390100Y432500D03*
X1389900Y427400D03*
X1385100Y432500D03*
X1365100D03*
Y427500D03*
Y437500D03*
X1380100Y442500D03*
Y437500D03*
X1370100D03*
X1375100D03*
X1370100Y447500D03*
X1403027Y520231D03*
X1355800Y508500D03*
X1395242Y520301D03*
X1347546Y476897D03*
X1380741Y487489D03*
X1360863Y481673D03*
X1362841Y492823D03*
X1383263Y493673D03*
X1381041Y482575D03*
X1360741Y486523D03*
X1362880Y497556D03*
X1383241Y498595D03*
X1347081Y507919D03*
X1396035Y514863D03*
X1347196Y472941D03*
X1354462Y474141D03*
X1350500Y475100D03*
X1386241Y487323D03*
X1366341Y481823D03*
X1368441Y492723D03*
X1388741Y493623D03*
X1386241Y482623D03*
X1366309Y486618D03*
X1368441Y497523D03*
X1388719Y498745D03*
X1399721Y537509D03*
X1379053Y581864D03*
X1390595Y549328D03*
X1375961Y569473D03*
X1376000Y565700D03*
X1382000Y589500D03*
X1375600Y589700D03*
X1400216Y560128D03*
X1396158Y537595D03*
X1380890Y615820D03*
X1386921Y620689D03*
X1390851D03*
X1375961Y600673D03*
X1375861Y597073D03*
X1375961Y593473D03*
X1382100Y592800D03*
X1410600Y9100D03*
X1425081Y48412D03*
X1411546Y43116D03*
X1453700Y83750D03*
X1457000Y82000D03*
X1420337Y45477D03*
X1416837D03*
X1451021Y151626D03*
X1438348Y155908D03*
X1468700Y163100D03*
X1458569Y192143D03*
X1458908Y187699D03*
X1459548Y221731D03*
X1446331Y197285D03*
X1422281Y221479D03*
X1447999Y205645D03*
X1451366Y165296D03*
X1408247Y206270D03*
X1422196Y218052D03*
X1452728Y243306D03*
X1452200Y254500D03*
X1430365Y262624D03*
X1448500Y257700D03*
X1458318Y243000D03*
X1426905Y267045D03*
X1464150Y235550D03*
X1455600Y254826D03*
X1433057Y257388D03*
X1447154Y251710D03*
X1441750Y236800D03*
X1467040Y260357D03*
X1466006Y265300D03*
X1426658Y274252D03*
X1461348Y244350D03*
X1444850Y242730D03*
X1408250Y333000D03*
X1413387Y320033D03*
Y316233D03*
X1408537Y307630D03*
X1413720Y307634D03*
X1419333Y307598D03*
X1443500Y327900D03*
X1468399Y324930D03*
X1408537Y302046D03*
X1413720Y301983D03*
X1419220D03*
X1444311Y324366D03*
X1466970Y320235D03*
X1420075Y388402D03*
X1413735Y391302D03*
X1420075Y383375D03*
X1420515Y368585D03*
X1420075Y393402D03*
X1413735Y396302D03*
X1420075Y378375D03*
X1420515Y373585D03*
X1452699Y404060D03*
X1457300Y373600D03*
X1444400Y371600D03*
X1413400Y361300D03*
X1464400Y390800D03*
X1450400Y354300D03*
X1448000Y431500D03*
X1431900Y437100D03*
X1447700Y442500D03*
X1431900Y448000D03*
X1448000Y437000D03*
X1431900Y442600D03*
X1447500Y448000D03*
X1431900Y453500D03*
X1414107Y447267D03*
X1458300Y442675D03*
X1431690Y521530D03*
X1410486Y529792D03*
X1458060Y495020D03*
X1464553Y508872D03*
X1428500Y521000D03*
X1461267Y489790D03*
X1412941Y489523D03*
X1413193Y482532D03*
X1436600Y482900D03*
X1436541Y494423D03*
X1412741Y494223D03*
X1413041Y477423D03*
X1436396Y477691D03*
X1436441Y489323D03*
X1451533Y527867D03*
X1460661Y484891D03*
X1418241Y489523D03*
X1418441Y482523D03*
X1441842Y482924D03*
X1442041Y494423D03*
X1418341D03*
Y477323D03*
X1442141Y477623D03*
X1442041Y489223D03*
X1441252Y548631D03*
X1451150Y569900D03*
Y573200D03*
X1439822Y537382D03*
X1429026Y541026D03*
X1428281Y546119D03*
X1413600Y531300D03*
X1432560Y561160D03*
X1436160Y561200D03*
X1428791Y535512D03*
X1419600Y531500D03*
X1410950Y589670D03*
X1441409Y561117D03*
X1453533Y532667D03*
X1426870Y530800D03*
X1423800Y534800D03*
X1425243Y562260D03*
X1421560Y563455D03*
X1460200Y606200D03*
X1477100Y2400D03*
X1522600Y-6500D03*
X1504400Y20300D03*
X1481600Y5300D03*
X1501900Y-9124D03*
X1485242Y4589D03*
X1506300Y-6600D03*
X1521092Y21665D03*
X1520700Y7100D03*
X1513700Y7082D03*
X1470862Y38209D03*
X1519599Y86117D03*
X1524557Y88336D03*
X1505673Y146346D03*
X1473354Y153246D03*
X1485210Y134837D03*
X1476761Y157400D03*
X1483366Y120746D03*
Y115902D03*
X1484113Y128513D03*
X1485755Y131671D03*
X1518376Y111499D03*
X1476761Y152725D03*
X1490178Y112315D03*
X1518438Y100926D03*
X1494939Y159500D03*
X1510184Y142614D03*
X1503466Y142486D03*
X1500703Y158233D03*
X1514425Y134180D03*
X1520150Y127600D03*
X1475200Y142600D03*
X1496038Y154229D03*
X1488300Y158300D03*
X1500643Y154819D03*
X1513136Y157081D03*
X1496726Y120588D03*
X1496658Y115088D03*
X1500700Y127250D03*
X1500806Y133339D03*
X1518514Y130991D03*
X1524900Y139100D03*
X1526310Y142190D03*
X1524284Y112773D03*
X1474717Y110370D03*
X1482455Y124222D03*
X1502000Y147500D03*
X1490674Y98787D03*
X1524744Y133656D03*
X1496713Y174853D03*
X1504706Y164871D03*
X1511100Y186275D03*
X1492597Y172636D03*
X1488900Y172576D03*
X1474883Y182275D03*
X1478089Y182650D03*
X1470382Y188372D03*
X1472758Y216495D03*
X1513900Y218000D03*
X1519243Y191627D03*
X1487716Y218650D03*
X1477388Y172988D03*
X1497237Y217281D03*
X1497493Y162078D03*
X1512700Y205100D03*
X1488300Y161700D03*
X1498022Y221900D03*
X1512525Y208944D03*
X1492136Y199125D03*
X1493200Y162700D03*
X1512500Y199837D03*
X1510638Y166240D03*
X1516872Y208863D03*
X1491438Y221137D03*
X1510800Y193330D03*
X1515060Y192443D03*
X1507524Y218600D03*
X1472200Y243000D03*
X1482004Y222483D03*
X1525650Y248700D03*
X1470950Y229669D03*
X1526150Y234300D03*
X1486926Y247834D03*
X1516549Y234278D03*
X1516613Y240656D03*
X1521962Y278650D03*
X1512790Y240099D03*
X1499681Y279910D03*
X1507003Y272249D03*
X1492753Y273724D03*
X1484000Y257500D03*
X1492697Y267303D03*
X1475004Y246287D03*
X1474520Y251740D03*
X1482400Y248000D03*
X1487500Y244500D03*
X1505946Y254432D03*
X1519300Y245196D03*
X1499070Y255934D03*
X1470556Y256900D03*
X1484700Y251800D03*
X1527657Y278700D03*
X1503842Y245678D03*
X1504772Y259229D03*
X1523580Y237960D03*
X1496812Y273718D03*
X1479700Y224801D03*
X1504461Y274426D03*
X1520413Y239498D03*
X1491265Y226492D03*
X1483457Y244568D03*
X1474096Y256706D03*
X1497082Y277987D03*
X1526936Y307015D03*
X1529734Y319714D03*
X1473231Y320250D03*
X1499723Y300106D03*
X1471562Y325531D03*
X1512182Y293317D03*
X1497179Y306372D03*
X1508455Y313041D03*
X1523935Y318901D03*
X1514067Y315626D03*
X1484100Y330115D03*
X1501550Y293750D03*
X1482550Y333600D03*
X1487000Y333300D03*
X1503538Y318068D03*
X1518006Y286706D03*
X1499987Y288487D03*
X1496628Y288440D03*
X1520766Y341000D03*
X1505000Y340990D03*
X1508650Y287500D03*
X1510851Y340113D03*
X1500840Y319870D03*
X1504370Y330970D03*
X1518060Y317520D03*
X1470276Y330774D03*
X1493268Y293943D03*
X1496900Y293900D03*
X1525677Y311835D03*
X1499829Y341250D03*
X1530500Y287700D03*
X1510584Y330640D03*
X1526900Y292866D03*
X1470257Y321929D03*
X1493290Y287984D03*
X1483506Y326061D03*
X1514100Y321792D03*
X1517115Y330005D03*
X1507025Y391034D03*
X1493375Y380894D03*
X1505075D03*
X1501175Y394414D03*
X1499225Y391034D03*
Y384274D03*
X1487525Y397794D03*
X1493375Y394414D03*
X1489475D03*
X1487525Y384274D03*
X1489475Y387654D03*
X1514265Y355542D03*
X1499225Y377514D03*
X1495325Y391034D03*
X1493375Y387654D03*
X1505075Y394414D03*
X1501175Y387654D03*
X1495325Y377514D03*
X1524575Y394414D03*
X1530425Y384274D03*
X1487525Y377514D03*
X1517367Y349964D03*
X1472940Y384030D03*
X1473255Y372654D03*
X1525561Y350253D03*
X1511000Y350627D03*
X1505075Y387654D03*
Y401174D03*
X1501175D03*
X1507025Y404554D03*
X1522625Y391034D03*
X1495325Y397794D03*
X1499225D03*
Y404554D03*
X1493375Y401174D03*
X1489475D03*
X1507025Y384274D03*
X1501175Y380894D03*
X1522625Y404554D03*
X1481000Y350000D03*
X1502970Y350610D03*
X1496000Y350000D03*
X1528475Y380894D03*
X1522625Y397794D03*
X1528475Y401174D03*
Y387654D03*
X1529829Y362655D03*
X1516775Y380894D03*
X1526659Y397500D03*
X1528475Y394414D03*
X1524575Y380894D03*
X1522476Y361907D03*
X1507025Y377514D03*
X1520675Y394414D03*
X1522625Y377514D03*
X1530425D03*
X1518725Y397794D03*
Y391034D03*
Y384274D03*
X1510925Y397794D03*
X1512875Y401174D03*
Y394414D03*
X1530425Y391034D03*
X1514925Y358844D03*
X1484600Y394100D03*
X1495325Y384274D03*
X1483868Y390233D03*
X1483664Y362914D03*
X1520675Y401174D03*
X1516775D03*
Y394414D03*
X1510925Y377514D03*
X1512875Y380894D03*
X1515328Y363389D03*
X1518725Y377514D03*
X1522625Y384274D03*
X1510925Y391034D03*
X1516775Y387654D03*
X1512875D03*
X1510925Y384274D03*
X1478163Y354940D03*
X1530425Y397794D03*
X1489475Y380894D03*
X1524575Y387654D03*
X1503878Y364717D03*
X1485300Y443484D03*
X1489475Y450306D03*
X1491425Y453686D03*
X1493375Y457066D03*
X1499225Y460446D03*
X1493375Y450306D03*
X1489475Y457066D03*
X1495325Y460446D03*
X1497275Y463826D03*
X1483375Y458375D03*
X1530425Y467206D03*
X1516700Y409900D03*
X1528475Y407934D03*
X1512875Y463826D03*
X1510925Y467206D03*
X1507025D03*
X1508975Y463826D03*
X1501175Y428214D03*
X1495325Y418074D03*
X1499225Y424834D03*
X1516775Y463826D03*
X1505075D03*
X1524575D03*
X1493375Y414694D03*
X1489475D03*
X1491425Y411314D03*
X1487525D03*
X1493375Y443546D03*
X1489475D03*
X1491425Y440166D03*
X1487525D03*
X1516775Y457066D03*
X1528475Y463826D03*
X1524575Y407624D03*
X1514825Y467206D03*
X1499225Y411314D03*
X1501175Y407934D03*
X1499225Y440166D03*
X1524575Y457066D03*
X1505075D03*
X1501175Y443546D03*
X1485250Y408017D03*
X1501200Y450600D03*
X1521800Y419900D03*
X1508975Y457066D03*
X1505715Y441368D03*
X1497200Y421200D03*
X1491425Y446926D03*
X1493375Y428214D03*
X1489475D03*
X1493375Y436786D03*
X1489475D03*
X1499225Y446926D03*
Y453686D03*
X1491425Y460446D03*
X1499225Y467206D03*
X1489475Y463826D03*
X1491425Y467206D03*
X1487525Y460446D03*
X1495325Y467206D03*
X1485030Y463690D03*
X1491400Y424600D03*
X1487500D03*
X1489475Y421454D03*
X1493375D03*
X1520675Y463826D03*
X1505075Y407934D03*
X1497273Y407610D03*
X1489475Y407934D03*
X1493375D03*
X1520675Y470586D03*
X1503400Y524663D03*
X1524575Y470586D03*
X1520675Y477346D03*
X1512875Y470586D03*
X1472500Y509810D03*
X1474400Y517200D03*
X1482200Y477800D03*
X1497275Y470586D03*
Y477346D03*
X1489475D03*
X1499225Y473966D03*
X1493375Y470586D03*
X1495325Y473966D03*
X1493375Y477346D03*
X1491425Y480726D03*
X1501175Y477346D03*
X1530425Y487486D03*
X1528475Y484106D03*
X1520675D03*
X1524575Y477346D03*
X1512875D03*
X1497275Y484106D03*
X1499225Y487486D03*
X1503125Y473966D03*
X1507025D03*
X1501175Y484106D03*
X1505075D03*
X1503125Y480726D03*
X1505075Y477346D03*
X1508975Y484106D03*
X1507025Y480726D03*
X1510925Y487486D03*
X1512875Y484106D03*
X1493375D03*
X1491425Y487486D03*
X1495325Y480726D03*
Y487486D03*
X1526525Y480726D03*
X1530425D03*
X1524575Y484106D03*
X1522625Y480726D03*
X1516775Y477346D03*
X1472250Y485100D03*
X1470643Y495299D03*
X1482958Y486118D03*
X1485100Y469900D03*
X1487525Y480726D03*
X1478700Y533700D03*
X1500445Y619956D03*
X1523450Y612900D03*
X1519850Y613000D03*
X1487912Y611632D03*
X1484312Y611732D03*
X1549600Y-10800D03*
X1538520Y11911D03*
X1590431Y-6702D03*
X1544882Y-6900D03*
X1592829Y24460D03*
X1589623Y24528D03*
X1543500Y3400D03*
X1540000D03*
X1581947Y-6702D03*
X1545111Y24172D03*
X1580398Y-600D03*
Y5400D03*
X1571500Y-1406D03*
X1556200Y94800D03*
X1545572Y38188D03*
X1579100Y69000D03*
X1577269Y95344D03*
X1535300Y78490D03*
X1590949Y97850D03*
X1583374Y81319D03*
X1574780Y90992D03*
X1587359Y84348D03*
X1545250Y88360D03*
X1546370Y84180D03*
X1592715Y70817D03*
X1575018Y71213D03*
X1556810Y71760D03*
X1541413Y155259D03*
X1541765Y114000D03*
X1541421Y106742D03*
X1580275Y101041D03*
X1553500Y157000D03*
X1552171Y133000D03*
X1563108Y126423D03*
X1582500Y109900D03*
X1577700Y140149D03*
X1567520Y133354D03*
X1549000Y115571D03*
X1549187Y104713D03*
X1589200Y121800D03*
X1589622Y112876D03*
X1557981Y141470D03*
X1541390Y136498D03*
X1573153Y103721D03*
X1576606Y104392D03*
X1588500Y106788D03*
X1588000Y100500D03*
X1542685Y133321D03*
X1574197Y127915D03*
X1531726Y123800D03*
X1576506Y143416D03*
X1572395Y110754D03*
X1558100Y128926D03*
X1554627Y100877D03*
X1558136D03*
X1558100Y138025D03*
Y133526D03*
X1541434Y139871D03*
X1542000Y126246D03*
X1591800Y164900D03*
X1566486Y181270D03*
X1535065Y164300D03*
X1552051Y172053D03*
X1571501Y180031D03*
X1568488Y164058D03*
X1562150Y160700D03*
X1583874Y217746D03*
X1582249Y191716D03*
X1572817Y169910D03*
X1570294Y167384D03*
X1535425Y188016D03*
X1535000Y207200D03*
X1557979Y188844D03*
X1543100Y184128D03*
X1553500Y165400D03*
X1548178Y190880D03*
X1558000Y205100D03*
X1545023Y161675D03*
X1561925Y192675D03*
X1566858Y175192D03*
X1549693Y196707D03*
X1552063Y202031D03*
X1558042Y172448D03*
X1593218Y191776D03*
X1557787Y192236D03*
X1561538Y174649D03*
X1587549Y192000D03*
X1582699Y252646D03*
X1561104Y234255D03*
X1537972Y236000D03*
X1532237Y247801D03*
X1567000Y259560D03*
X1552900Y281700D03*
X1579867Y265445D03*
X1563157Y258164D03*
X1533596Y273504D03*
X1542751Y240477D03*
X1542690Y236050D03*
X1531935Y224160D03*
X1541325Y245090D03*
X1568120Y251710D03*
X1545802Y233529D03*
X1584568Y281339D03*
X1571876Y255800D03*
X1558700Y252000D03*
X1568365Y247761D03*
X1551404Y309376D03*
X1533228Y325000D03*
X1550619Y303087D03*
X1534400Y296029D03*
X1587800Y308200D03*
X1538450Y314300D03*
X1578790Y290920D03*
X1550800Y296200D03*
X1577486Y307621D03*
X1532850Y303950D03*
X1548024Y322145D03*
X1585479Y316610D03*
X1570574Y341776D03*
X1554932Y332171D03*
X1538406Y330157D03*
X1573950Y338050D03*
X1537500Y292800D03*
X1581834Y318591D03*
X1559800Y285300D03*
X1559500Y290300D03*
X1575645Y320664D03*
X1588551Y341410D03*
X1548334Y325497D03*
X1581940Y295820D03*
X1582800Y312100D03*
X1548273Y313227D03*
X1565000Y290500D03*
X1543864Y311399D03*
X1590212Y315425D03*
X1551250Y320303D03*
X1590176Y331844D03*
X1554775Y295328D03*
X1548100Y342200D03*
X1534833Y309798D03*
X1560500Y350000D03*
X1553825Y377514D03*
X1557534Y353400D03*
X1533589Y366361D03*
X1553825Y391034D03*
X1546025D03*
X1532367Y356530D03*
X1581822Y365770D03*
X1569584Y378002D03*
X1563575Y394414D03*
X1557725Y397794D03*
X1571375Y387654D03*
X1569425Y397794D03*
X1550639Y350200D03*
X1563575Y401174D03*
X1569425Y391034D03*
X1553825Y397794D03*
X1542300Y376717D03*
X1546025Y397794D03*
X1551875Y394414D03*
Y387654D03*
X1549950Y404490D03*
X1565525Y384274D03*
X1587684Y362653D03*
X1590154Y354762D03*
X1557725Y377514D03*
X1586500Y354900D03*
X1559675Y401174D03*
X1542125Y397794D03*
X1583208Y404941D03*
X1565525Y391034D03*
X1547975Y394414D03*
X1540175Y387654D03*
Y380894D03*
Y401174D03*
X1542932Y355740D03*
X1547975Y387654D03*
X1571450Y359650D03*
X1536275Y401174D03*
Y387654D03*
X1534325Y384274D03*
X1536275Y380894D03*
X1534325Y397794D03*
X1540175Y394414D03*
X1534325Y391034D03*
X1582600Y389300D03*
X1559675Y387654D03*
Y394414D03*
X1551875Y380894D03*
X1557725Y391034D03*
X1536275Y394414D03*
X1557725Y404554D03*
X1563575Y387654D03*
X1567475Y401174D03*
X1566922Y359681D03*
X1567121Y363217D03*
X1551875Y401174D03*
X1565525Y397794D03*
Y377514D03*
X1559675Y380894D03*
X1571375Y394414D03*
X1532375Y401174D03*
X1563575Y380894D03*
X1546182Y355446D03*
X1534325Y377514D03*
X1542125Y460446D03*
X1538225D03*
X1549925Y467206D03*
X1557725D03*
X1569425Y453686D03*
X1559675Y407934D03*
X1561625Y446926D03*
X1551875Y450306D03*
X1536275Y463826D03*
X1532375D03*
X1534325Y467206D03*
X1538225D03*
X1585560Y421324D03*
X1583773Y436137D03*
X1544075Y463826D03*
X1543850Y451400D03*
X1553825Y411314D03*
X1544150Y409900D03*
X1553825Y440166D03*
Y446926D03*
X1549926Y411312D03*
X1540175Y407934D03*
X1536275D03*
X1532375D03*
X1555775D03*
Y414694D03*
X1565525Y418074D03*
X1561625D03*
Y411314D03*
X1565525D03*
X1561625Y440166D03*
X1557725D03*
X1565525Y424834D03*
X1569425D03*
X1536300Y455200D03*
X1553825Y453686D03*
X1547000Y435650D03*
X1551875Y436786D03*
X1549925Y440166D03*
X1540653Y454588D03*
X1532349Y455200D03*
X1549925Y460446D03*
X1583208Y416752D03*
X1591350Y445300D03*
X1542125Y467206D03*
X1559595Y450631D03*
X1569425Y446926D03*
X1591430Y409440D03*
X1565525Y453686D03*
X1551875Y443546D03*
X1571375Y436786D03*
X1587573Y445300D03*
X1587550Y456550D03*
X1565525Y467206D03*
X1561625D03*
X1567475Y463826D03*
X1569425Y467206D03*
X1553825Y460446D03*
X1567475Y443546D03*
X1571375D03*
X1563575Y450306D03*
X1567475Y436786D03*
X1569425Y440166D03*
X1565525Y460446D03*
X1563575Y463826D03*
X1582300Y446100D03*
X1565525Y446926D03*
X1559675Y457066D03*
X1546025Y460446D03*
X1557725D03*
X1551875Y470586D03*
X1549925Y480726D03*
X1551875Y477346D03*
X1546025Y473966D03*
X1547975Y477346D03*
X1559675Y470586D03*
X1533595Y505530D03*
X1559675Y484106D03*
X1561625Y480726D03*
X1557725Y487486D03*
X1561625D03*
X1567475Y484106D03*
X1563575D03*
X1559675Y477346D03*
X1565525Y487486D03*
X1563575Y477346D03*
X1571375D03*
X1590580Y472370D03*
X1536275Y477346D03*
X1534325Y480726D03*
Y473966D03*
X1538225Y480726D03*
X1532375Y484106D03*
Y477346D03*
X1540175Y470586D03*
X1563575D03*
X1561625Y473966D03*
X1565525D03*
X1567475Y477346D03*
X1584970Y472370D03*
X1542125Y487486D03*
X1540175Y484106D03*
X1546025Y487486D03*
X1551875Y484106D03*
X1538225Y487486D03*
X1542125Y480726D03*
X1544075Y484106D03*
X1547975D03*
X1550990Y586588D03*
X1554358Y587258D03*
X1592934Y592396D03*
X1587610Y579550D03*
X1585155Y538574D03*
X1581730Y537170D03*
X1565389Y585721D03*
X1535565Y591658D03*
X1579900Y606050D03*
X1586700Y620100D03*
X1540477Y620308D03*
X1540700Y613700D03*
X1545407Y598393D03*
X1541384Y601262D03*
X1546075Y618145D03*
X1544050Y615296D03*
X1579680Y610279D03*
X1534968Y597268D03*
X1573500Y619500D03*
X1577000D03*
X1572950Y593950D03*
X1601650Y24160D03*
X1617500Y-14500D03*
X1597800Y24300D03*
X1637482Y21623D03*
X1653100Y11500D03*
X1638550Y7200D03*
X1623900Y4600D03*
X1598602Y3437D03*
X1599000Y61500D03*
X1596050Y75400D03*
X1632006Y94500D03*
X1640900Y66900D03*
X1630826Y88087D03*
X1614997Y84403D03*
X1625075Y80182D03*
X1597867Y93900D03*
X1597987Y79500D03*
X1619000Y38500D03*
X1606579Y86726D03*
X1614169Y95004D03*
X1617347Y94581D03*
X1599500Y75000D03*
X1649900Y78600D03*
X1653000Y77600D03*
X1643500Y80400D03*
X1635337Y73500D03*
X1627489Y74960D03*
X1632020Y97871D03*
X1632000Y73500D03*
X1628788Y97800D03*
X1621100Y69600D03*
X1620900Y81300D03*
X1593241Y134295D03*
X1598300Y116477D03*
X1598449Y120760D03*
X1600000Y104243D03*
X1648000Y100597D03*
X1594452Y111377D03*
X1654685Y121790D03*
X1613741Y112341D03*
X1593756Y129048D03*
X1647852Y197374D03*
X1651000Y178628D03*
X1603300Y185100D03*
X1627326Y182759D03*
X1654015Y217239D03*
X1615362Y213507D03*
X1650600Y186300D03*
X1648349Y182276D03*
X1645700Y214050D03*
X1602185Y180709D03*
X1635351Y185444D03*
X1598006Y192421D03*
X1595291Y166423D03*
X1644290Y196383D03*
X1635621Y208259D03*
X1601870Y270470D03*
X1643106Y233913D03*
X1600810Y266006D03*
X1636914Y270900D03*
X1596300Y250320D03*
X1627024Y253387D03*
X1631300Y280400D03*
X1637281Y260922D03*
X1597201Y238188D03*
X1643775Y246137D03*
X1637281Y254322D03*
X1617498Y273433D03*
X1632128Y225472D03*
X1637269Y264421D03*
X1622000Y279495D03*
X1627043Y256900D03*
X1636684Y283141D03*
X1610290Y265352D03*
X1638216Y246021D03*
X1604222Y268107D03*
X1608764Y322440D03*
X1608850Y343835D03*
X1638086Y319664D03*
X1625400Y327667D03*
X1602776Y331304D03*
X1652991Y321341D03*
X1620159Y332004D03*
X1638063Y326504D03*
X1631015Y328350D03*
X1635355Y324228D03*
X1639040Y316343D03*
X1625846Y286154D03*
X1609172Y339630D03*
X1636800Y287956D03*
X1602215Y363981D03*
X1610140Y358350D03*
X1609271Y348166D03*
X1621727Y395374D03*
X1612825Y405438D03*
X1622100Y400600D03*
X1630400Y391800D03*
X1629300Y385400D03*
X1630750Y404800D03*
X1613452Y387098D03*
X1638991Y352037D03*
X1621800Y381500D03*
Y386300D03*
X1595800Y405900D03*
X1639750Y445477D03*
X1630219Y446000D03*
X1621000Y440500D03*
X1621044Y433364D03*
X1621182Y427091D03*
X1603719Y412000D03*
X1611638Y454809D03*
X1612100Y446000D03*
X1646480Y443880D03*
X1611642Y461877D03*
X1630150Y427663D03*
X1593400Y432200D03*
X1639774Y439486D03*
X1623705Y467855D03*
X1639822Y453140D03*
X1647200Y430450D03*
X1640625Y429460D03*
X1621226Y445026D03*
X1615061Y463157D03*
X1596500Y455500D03*
X1617900Y409900D03*
X1595200Y412700D03*
X1651754Y488025D03*
X1626518Y528029D03*
X1627622Y524928D03*
X1631975Y527700D03*
X1597380Y495416D03*
X1600780D03*
X1617300Y519000D03*
X1625485Y494188D03*
X1623551Y525015D03*
X1621783Y498617D03*
X1620030Y525066D03*
X1594280Y472370D03*
X1645969Y514870D03*
X1617700Y475957D03*
X1614000Y475970D03*
X1639271Y491135D03*
X1639391Y513065D03*
X1629778Y507294D03*
X1642670Y514939D03*
X1629500Y491500D03*
X1649336Y511502D03*
X1641470Y506403D03*
X1644651Y505500D03*
X1649545Y515215D03*
X1601540Y588793D03*
X1622330Y592325D03*
X1594110Y611510D03*
X1619700Y617300D03*
X1617600Y619800D03*
X1680033Y-16711D03*
X1666500Y10500D03*
X1680034Y2863D03*
X1697300Y73296D03*
X1689250Y86000D03*
X1692300Y56900D03*
X1658600Y44700D03*
X1667000Y88000D03*
X1693900Y73300D03*
X1708610Y85121D03*
X1713900Y87900D03*
X1696870Y86093D03*
X1711000Y55525D03*
X1712600Y46100D03*
X1707268Y77668D03*
X1669000Y92000D03*
X1709184Y88811D03*
X1678627Y54616D03*
X1684248Y56746D03*
X1690500Y73950D03*
X1715100Y70500D03*
X1659000Y88000D03*
X1661900Y92400D03*
X1704824Y90049D03*
X1664500Y99000D03*
X1672200Y112200D03*
X1696907Y99077D03*
X1664135Y131239D03*
X1657835D03*
Y156436D03*
X1678400Y103000D03*
X1674800Y103100D03*
X1659643Y213505D03*
X1687550Y213751D03*
X1674912Y183000D03*
X1673530Y209974D03*
X1708350Y175050D03*
X1660800Y181900D03*
X1663400Y179475D03*
X1667140Y182300D03*
X1669849Y193067D03*
X1702400Y193450D03*
X1664321Y195244D03*
X1658082Y195298D03*
X1655978Y207827D03*
X1705666Y198055D03*
X1671688Y182925D03*
X1688046Y174447D03*
X1664390Y201163D03*
X1660440Y200789D03*
X1667356Y213096D03*
X1691439Y174354D03*
X1713000Y185000D03*
X1674019Y175990D03*
X1713596Y175795D03*
X1676750Y206050D03*
X1681116Y238614D03*
X1657500Y259700D03*
X1657567Y264600D03*
X1657498Y269700D03*
Y274700D03*
Y279900D03*
X1715837Y246178D03*
X1715078Y250231D03*
X1657494Y292816D03*
X1657498Y284900D03*
X1664453Y308557D03*
X1660972Y401447D03*
X1660834Y404934D03*
X1660890Y397300D03*
X1673074Y453185D03*
X1675120Y439731D03*
X1679145Y461950D03*
X1667588Y434149D03*
X1668100Y418700D03*
X1678303Y442765D03*
X1667946Y412987D03*
X1673550Y442696D03*
X1714530Y519900D03*
X1710594D03*
X1676800Y483800D03*
X1681650Y510673D03*
X1687606Y500938D03*
X1672265Y473600D03*
X1681115Y525218D03*
X1716490Y506970D03*
X1681500Y482000D03*
X1671050Y487000D03*
Y490850D03*
X1672159Y494042D03*
X1655790Y476593D03*
X1705767Y482434D03*
X1698354Y486873D03*
X1701617Y482706D03*
X1680133Y535489D03*
X1710389Y577787D03*
X1699600Y578100D03*
X1710000Y604500D03*
Y600000D03*
X1701291Y602268D03*
X1741544Y9151D03*
X1749085Y9177D03*
X1744900Y9100D03*
X1725474Y69250D03*
X1746328Y59011D03*
X1760016Y65774D03*
X1771707Y86500D03*
X1767250Y94500D03*
Y89500D03*
X1766333Y59116D03*
X1775000Y53500D03*
X1750400Y47400D03*
X1720100Y46100D03*
X1720500Y52440D03*
X1757998Y73637D03*
X1731350Y92140D03*
X1757772Y90174D03*
X1765015Y119100D03*
X1776828Y155211D03*
X1748425Y119190D03*
X1768886Y156173D03*
X1719000Y190500D03*
X1719080Y236152D03*
X1718820Y249032D03*
X1727896Y246175D03*
X1719080Y232852D03*
X1720651Y246141D03*
X1749462Y232955D03*
X1746900Y249804D03*
X1751900Y249700D03*
X1722251Y250532D03*
X1724181Y246159D03*
X1730996Y442804D03*
X1737150Y450850D03*
X1719089Y472104D03*
X1728700Y470200D03*
X1719560Y501770D03*
X1766100Y521124D03*
X1722347Y471811D03*
X1750800Y516100D03*
X1762715Y521085D03*
X1753807Y548183D03*
X1757478Y548192D03*
X1767529Y566200D03*
X1764300Y570900D03*
X1742200Y552863D03*
X1724899Y584748D03*
X1733000Y557000D03*
X1767141Y555500D03*
X1756578Y586743D03*
X1724250Y588250D03*
X1743000Y574500D03*
X1730759Y548162D03*
X1722500Y562000D03*
X1754897Y578750D03*
X1742381Y588530D03*
X1767500Y559800D03*
X1738498Y554255D03*
X1750399Y603201D03*
X1739714Y604967D03*
X1716950Y603450D03*
X1735000Y621002D03*
X1764823Y613600D03*
X1725133Y614896D03*
X1766400Y599400D03*
X1770600Y600800D03*
X1764912Y618718D03*
X1728341Y614851D03*
X1819800Y2100D03*
X1813913Y2287D03*
X1799462Y8830D03*
X1804462D03*
X1790078Y11860D03*
X1795078Y11900D03*
X1792700Y36871D03*
X1797700Y36804D03*
X1831000Y-16300D03*
X1828874Y-13520D03*
X1815150Y26650D03*
X1779750Y36530D03*
X1791500Y26918D03*
X1808100Y21800D03*
X1813795Y12165D03*
X1819837Y21700D03*
X1786865Y22375D03*
X1823600Y8800D03*
X1797700Y21018D03*
X1837500Y35700D03*
X1838850Y13160D03*
X1836700Y-18900D03*
X1804800Y-1500D03*
X1816723Y9781D03*
X1826414Y35486D03*
X1835600Y3900D03*
X1824240Y83680D03*
X1802119Y56581D03*
X1799438Y44328D03*
X1827000Y94550D03*
X1827150Y97800D03*
X1827100Y81600D03*
X1798454Y82256D03*
X1788216Y59197D03*
X1821350Y98270D03*
X1803300Y39900D03*
X1808363Y40033D03*
X1812352Y36949D03*
X1838500Y40400D03*
X1820457Y39128D03*
X1829580Y38620D03*
X1810100Y114700D03*
X1808226Y136171D03*
X1803509Y128500D03*
X1807818Y124179D03*
X1813118Y127976D03*
X1815026Y121478D03*
X1788000Y129000D03*
X1815883Y133277D03*
X1808313Y111705D03*
X1807509Y128500D03*
X1814900Y116900D03*
X1783252Y109044D03*
X1796500Y120000D03*
X1815348Y143437D03*
X1803058Y143733D03*
X1830316Y102163D03*
X1827500Y144900D03*
X1837090Y149830D03*
X1839667Y151994D03*
X1809810Y155858D03*
X1800792Y122691D03*
X1824990Y103620D03*
X1787373Y120188D03*
X1816418Y127976D03*
X1807166Y147401D03*
X1800420Y148240D03*
X1821261Y170012D03*
X1824200Y176900D03*
X1830415Y196567D03*
X1785500Y164000D03*
X1836100Y179700D03*
X1836900Y165800D03*
X1787000Y175500D03*
X1778900Y165800D03*
X1834103Y176021D03*
X1833629Y170807D03*
X1836932Y170486D03*
X1816125Y169492D03*
X1834400Y216900D03*
X1785500Y168000D03*
X1822877Y235852D03*
X1826085Y236034D03*
X1822638Y232106D03*
X1826662Y232191D03*
X1784440Y232938D03*
X1804388Y249904D03*
X1831700Y252272D03*
X1837857Y468630D03*
X1834100Y523900D03*
X1814852Y519901D03*
X1810350Y525650D03*
X1809700Y506875D03*
X1820400Y501100D03*
X1837200Y525700D03*
X1813500Y526500D03*
X1816584Y530542D03*
X1810200Y513300D03*
X1837300Y472276D03*
X1825900Y523500D03*
X1815200Y501500D03*
X1794100Y521900D03*
X1798250Y529200D03*
X1803900Y491500D03*
X1795200Y525700D03*
X1836600Y521600D03*
X1831600Y529000D03*
X1833700Y497300D03*
X1781300Y537800D03*
X1837475Y573835D03*
X1829051Y591299D03*
X1809600Y582800D03*
X1793660Y560570D03*
X1811100Y586800D03*
X1816458Y587480D03*
X1829300Y572900D03*
X1793100Y578500D03*
X1816020Y571448D03*
X1812802Y578693D03*
X1780394Y561076D03*
X1837534Y579322D03*
X1792805Y574675D03*
X1832500Y539500D03*
X1829000Y536315D03*
X1832200Y567760D03*
X1791349Y589122D03*
X1788300Y585100D03*
X1810863Y560637D03*
X1816175Y567669D03*
X1838224Y586650D03*
X1783700Y576400D03*
X1785050Y584550D03*
X1792100Y566900D03*
X1816330Y545260D03*
X1816100Y576200D03*
X1829176Y584287D03*
X1809309Y555713D03*
X1839126Y583354D03*
X1831500Y544500D03*
Y548000D03*
X1831800Y552300D03*
X1837000Y534900D03*
X1782300Y555900D03*
X1778675Y592224D03*
X1794500Y612500D03*
X1791500Y606500D03*
X1782700Y610900D03*
X1795000Y599600D03*
X1791323Y594030D03*
X1805000Y606500D03*
X1788290Y612006D03*
X1787500Y600500D03*
X1784200Y593924D03*
X1900256Y-14760D03*
X1841060Y35540D03*
X1882999Y7383D03*
X1883041Y15814D03*
X1893094Y-12642D03*
X1876792Y18461D03*
X1878000Y73950D03*
X1843107Y97988D03*
X1848208Y49427D03*
X1889218Y51030D03*
Y46030D03*
Y61030D03*
Y56030D03*
X1842250Y84000D03*
Y90750D03*
X1858600Y74300D03*
X1849426Y90700D03*
Y95500D03*
X1883200Y76600D03*
X1850600Y41348D03*
X1875600Y156300D03*
X1857110Y113600D03*
X1881324Y153250D03*
X1890974Y105600D03*
X1898102Y107325D03*
X1885700Y141200D03*
X1897536Y114600D03*
Y120510D03*
X1887497Y105444D03*
X1878753Y139893D03*
X1867280Y135406D03*
X1881165Y105561D03*
X1885102Y101134D03*
X1866606Y109967D03*
X1857849Y148079D03*
X1872254Y138618D03*
X1872400Y144619D03*
X1871521Y153593D03*
X1888639Y147042D03*
X1893640D03*
X1894855Y142122D03*
X1899855D03*
X1861932Y146431D03*
X1857919Y156123D03*
X1869668Y146750D03*
X1864904Y114735D03*
X1895060Y136099D03*
X1897507Y124450D03*
X1895673Y151800D03*
X1868843Y207920D03*
X1874236Y213800D03*
X1893238Y208042D03*
X1863650Y189750D03*
X1877880Y203780D03*
X1847200Y202050D03*
X1884340Y217866D03*
X1840900Y179700D03*
X1845700D03*
X1896710Y194380D03*
X1882452Y195888D03*
X1901100Y194200D03*
X1889400Y191200D03*
X1886200Y161000D03*
X1875700Y184800D03*
X1864637Y201861D03*
X1876700Y207600D03*
X1872100Y207900D03*
X1861243Y183100D03*
X1862000Y177500D03*
X1884000Y188100D03*
X1884400Y183700D03*
X1858686Y180377D03*
X1858500Y200100D03*
X1864000Y184900D03*
X1878789Y213663D03*
X1891880Y204370D03*
X1856874Y219443D03*
X1864464Y198466D03*
X1885465Y166285D03*
X1855000Y167100D03*
X1850723Y219250D03*
X1865100Y174600D03*
X1877517Y217988D03*
X1840149Y244425D03*
X1843449D03*
X1885000Y227500D03*
X1899816Y235035D03*
X1844444Y224035D03*
X1854374Y248790D03*
X1854720Y253700D03*
X1846517Y253500D03*
X1850220D03*
X1896529Y235080D03*
X1892274D03*
X1842857Y468630D03*
X1878100Y450200D03*
X1868167Y467855D03*
X1863137Y452710D03*
X1859059Y448076D03*
X1858633Y452803D03*
X1901574Y454422D03*
X1875900Y453600D03*
X1867500Y447900D03*
X1859530Y516430D03*
X1842400Y516800D03*
X1841900Y498800D03*
X1900890Y477200D03*
X1864339Y509560D03*
X1863000Y480000D03*
X1859600Y476200D03*
X1852719Y487575D03*
Y492575D03*
X1876945Y471316D03*
X1877407Y479046D03*
X1857450Y473654D03*
X1855206Y471112D03*
X1847000Y487500D03*
X1860000Y495500D03*
X1842764Y528136D03*
X1869914Y517225D03*
X1866688Y517128D03*
X1870100Y561150D03*
X1844018Y586482D03*
X1868200Y590939D03*
X1858528Y544528D03*
X1875850Y567200D03*
X1840690Y557190D03*
X1878500Y553500D03*
X1858500Y540000D03*
X1852250Y547900D03*
X1858681Y568087D03*
X1879862Y581862D03*
X1896899Y557790D03*
X1900729Y569557D03*
X1864580Y537060D03*
X1878736Y533040D03*
X1868110Y536000D03*
X1845407Y533178D03*
X1900250Y533700D03*
X1856573Y576534D03*
X1895523Y586365D03*
X1857812Y557245D03*
X1866800Y588000D03*
X1869800Y557100D03*
X1878875Y565475D03*
X1847070Y537610D03*
X1882300Y565550D03*
X1885100Y584300D03*
X1848900Y590750D03*
X1845000Y590800D03*
X1873510Y541710D03*
X1875600Y588500D03*
X1840700Y563800D03*
X1854530Y533132D03*
X1896358Y595255D03*
X1916078Y-16368D03*
X1918352Y89300D03*
X1923300Y94300D03*
X1920300Y68300D03*
X1917600Y66000D03*
X1948472Y80362D03*
X1933914Y96040D03*
X1946500Y104974D03*
X1940700Y136300D03*
X1908327Y149353D03*
X1904215Y142812D03*
X1909216D03*
X1943752Y137548D03*
X1947078Y139300D03*
X1963400Y141100D03*
X1921264Y153000D03*
X1937900Y153600D03*
X1923800Y151000D03*
X1927000Y152200D03*
X1934256Y99459D03*
X1934544Y127957D03*
X1929000Y158600D03*
X1926952Y156049D03*
X1952726Y102950D03*
X1914500Y113300D03*
X1940500Y157600D03*
X1932998Y119438D03*
X1923329Y99475D03*
X1947000Y142600D03*
X1923837Y118800D03*
X1937728Y99441D03*
X1925358Y140685D03*
X1903150Y217250D03*
X1910123Y217349D03*
X1957334Y201269D03*
X1939300Y204300D03*
X1917568Y201215D03*
X1917024Y193600D03*
X1929700Y163400D03*
X1921500Y193600D03*
X1940240Y169970D03*
X1939550Y165600D03*
X1931483Y199350D03*
X1940647Y161600D03*
X1909421Y208805D03*
X1909438Y204307D03*
X1904042Y204895D03*
X1903917Y201472D03*
X1925400Y196300D03*
X1929090Y193190D03*
X1939400Y198400D03*
X1934100Y193400D03*
X1935600Y176300D03*
X1932837Y186700D03*
X1925000Y192000D03*
X1918489Y212513D03*
X1943500Y209500D03*
X1930500Y209464D03*
X1918143Y219848D03*
X1927064Y207564D03*
X1938400Y178200D03*
X1939200Y194300D03*
X1935600Y198700D03*
X1950981Y191218D03*
X1963300Y191000D03*
X1952717Y198614D03*
X1943217Y221154D03*
Y217645D03*
X1942000Y440500D03*
X1937430Y464785D03*
X1904724Y447930D03*
X1939845Y445055D03*
X1947550Y485350D03*
X1956500Y507470D03*
X1938300Y486250D03*
X1957250Y512050D03*
X1937300Y508900D03*
X1919230Y483430D03*
X1919000Y487210D03*
X1919510Y475100D03*
Y479200D03*
X1939000Y476600D03*
X1956606Y526671D03*
X1957212Y479521D03*
X1957063Y474769D03*
X1945000Y474000D03*
X1948200Y474300D03*
X1928620Y482710D03*
X1956300Y515900D03*
X1959300Y518000D03*
X1908300Y514500D03*
X1942328Y508712D03*
X1963000Y573000D03*
X1921244Y533750D03*
X1951900Y534900D03*
X1963097Y551000D03*
X1934200Y573700D03*
X1935400Y583000D03*
X1940800Y537300D03*
X1945900Y549900D03*
X1923500Y579500D03*
X1948100Y538700D03*
X1923400Y583000D03*
X1923600Y575500D03*
X1926600Y559500D03*
X1923600Y565100D03*
X1923000Y568700D03*
X1959120Y547050D03*
X1958940Y538890D03*
X1961715Y555639D03*
X1918880Y586460D03*
X1961771Y591744D03*
X1962950Y566600D03*
X1956191Y548700D03*
X1962500Y578500D03*
X1958500Y535000D03*
X1907500Y545600D03*
X1907200Y551600D03*
X1932390Y590100D03*
X1959400Y601100D03*
X1934350Y609250D03*
X1923504Y592500D03*
X1911750Y592800D03*
X1927000Y614500D03*
X1914700Y594600D03*
X1963300Y612800D03*
X1938130Y601480D03*
X1967580Y104721D03*
X1972598Y165236D03*
X1967200Y521600D03*
X1964270Y511410D03*
X1968375Y509375D03*
X1964890Y534940D03*
X1965400Y619500D03*
X1456000Y360700D03*
X1460400Y353000D03*
X1459111Y356353D03*
X1467597Y363000D03*
X1463870Y367869D03*
X1453900Y353350D03*
X1453251Y356676D03*
X1552500Y358500D03*
X1550417Y362607D03*
G54D65*
X1854501Y195587D03*
X1859854Y501441D03*
X1952756Y589960D03*
X1944882Y582086D03*
X1952756D03*
X1944882Y574212D03*
X1952756D03*
X1944882Y566338D03*
X1952756D03*
X1944882Y558464D03*
Y589960D03*
X1952756Y558464D03*
X1944882Y605708D03*
X1952756D03*
X1944882Y597834D03*
X1952756D03*
G54D59*
X1638131Y475946D03*
G54D45*
X-4488Y425472D03*
X99980Y136909D03*
X1472000Y-5000D03*
Y-15000D03*
X1462000Y-5000D03*
Y-15000D03*
X1452000Y-5000D03*
Y-15000D03*
X1442000Y-5000D03*
Y-15000D03*
X1525000D03*
X1515000D03*
X1505000D03*
X1482000D03*
X1492000Y-5000D03*
Y-15000D03*
X1482000Y-5000D03*
X1575000Y-15000D03*
X1565000D03*
X1555000D03*
X1545000D03*
X1535000D03*
X1713503Y-5000D03*
Y-15000D03*
X1703503Y-5000D03*
Y-15000D03*
X1743503D03*
X1733503Y-5000D03*
Y-15000D03*
X1743503Y-5000D03*
X1779504D03*
X1769504D03*
Y-15000D03*
X1809504D03*
X1799504Y-5000D03*
Y-15000D03*
X1789504Y-5000D03*
Y-15000D03*
X1819504Y-5000D03*
Y-15000D03*
X1809504Y-5000D03*
G54D25*
X40500Y-42250D03*
Y-52250D03*
X60500Y-42250D03*
X80500D03*
X100500D03*
X60500Y-52250D03*
X80500D03*
X100500D03*
X120500Y-42250D03*
X140500D03*
X120500Y-52250D03*
X140500D03*
X467246Y-52301D03*
Y-42301D03*
X487246Y-52301D03*
Y-42301D03*
X507246Y-52301D03*
Y-42301D03*
X527246Y-52301D03*
Y-42301D03*
X547246Y-52301D03*
Y-42301D03*
X567246Y-52301D03*
Y-42301D03*
X798984Y-52057D03*
Y-42057D03*
X818984Y-52057D03*
Y-42057D03*
X838984Y-52057D03*
Y-42057D03*
X858984Y-52057D03*
Y-42057D03*
X878984Y-52057D03*
Y-42057D03*
X898984Y-52057D03*
Y-42057D03*
X1135583Y-52285D03*
Y-42285D03*
X1155583Y-52285D03*
Y-42285D03*
X1392258Y-52257D03*
Y-42257D03*
X1412258Y-52257D03*
Y-42257D03*
X1432258Y-52257D03*
Y-42257D03*
X1452258Y-52257D03*
Y-42257D03*
G54D68*
X1922248Y518328D03*
G54D63*
X1724807Y451179D03*
X1851250Y584622D03*
Y576748D03*
Y568874D03*
G54D61*
X1674921Y528523D03*
X1773347D03*
Y545059D03*
G54D56*
X1526871Y23968D03*
G54D52*
X638541Y171945D03*
Y454425D03*
X752641Y159945D03*
X1288068Y171945D03*
Y454425D03*
X1402168Y159945D03*
Y442425D03*
G54D42*
X40512Y458744D03*
G54D36*
X-15748Y116969D03*
Y132717D03*
X787D03*
X28740Y124843D03*
Y140591D03*
G54D29*
X60512Y467244D03*
G54D44*
X30512D03*
X40512D03*
G54D64*
X1809665Y618663D03*
X1819665D03*
X1829665D03*
G54D47*
X63093Y202300D03*
X72936D03*
X82779D03*
X1914911Y495775D03*
X1934597D03*
X1924754D03*
G54D39*
X-14488Y434094D03*
X-4488D03*
X5512D03*
X15512D03*
X89980Y145531D03*
X99980D03*
X109980D03*
X119980D03*
G54D54*
X1401516Y23976D03*
G54D35*
X1753503Y-15000D03*
Y-5000D03*
X1723503Y-15000D03*
Y-5000D03*
G54D32*
X1466694Y375787D03*
G54D34*
X1705772Y567874D03*
G54D49*
X94683Y514079D03*
X637793Y-5822D03*
Y13078D03*
Y69778D03*
Y50878D03*
Y88678D03*
Y532955D03*
Y514079D03*
Y570755D03*
Y589679D03*
Y551879D03*
Y608555D03*
X744293Y-5822D03*
Y31978D03*
Y13078D03*
Y69778D03*
Y88678D03*
Y50878D03*
Y532955D03*
Y514079D03*
Y570755D03*
Y589679D03*
Y551879D03*
Y608555D03*
X1287403Y69778D03*
Y88678D03*
Y532955D03*
Y514079D03*
G54D37*
X-7874Y216181D03*
Y325315D03*
G54D41*
X18228Y178386D03*
X-1969D03*
G54D28*
X1866923Y235400D03*
G54D24*
X-3937Y-43307D03*
X1956693D03*
X-13780Y598560D03*
X-3937Y646063D03*
X1956693D03*
G54D33*
X1611283Y615236D03*
G54D27*
X1955506Y454297D03*
X1699600D03*
Y235400D03*
G54D30*
X133563Y183126D03*
Y419626D03*
X783171Y183126D03*
Y419626D03*
G54D31*
X1454685Y338189D03*
X1600355Y527165D03*
G54D50*
X224410Y301378D03*
X500000Y163582D03*
Y439173D03*
X602362Y214764D03*
Y387992D03*
X874016Y301378D03*
X1149606Y163582D03*
Y439173D03*
X1251969Y214764D03*
Y387992D03*
%LPD*%
G75*
G36*
G01X9076Y235806D02*
Y264624D01*
X13927Y269474D01*
Y336827D01*
X16300Y339200D01*
X38700D01*
X39600Y338300D01*
Y274715D01*
G03Y274579I1400J-68D01*
G01Y265418D01*
G03Y265282I1400J-68D01*
G01Y199500D01*
X37200Y197100D01*
X13400D01*
X12200Y198300D01*
Y232682D01*
X9076Y235806D01*
G37*
G36*
G01X104550Y-12500D02*
X100250Y-8200D01*
X100299Y-8077D01*
G03X92428Y-206I-5616J2255D01*
G01X92305Y-255D01*
X83100Y8950D01*
X83107Y9042D01*
G03X81493Y10656I-1497J117D01*
G01X81401Y10649D01*
X80430Y11620D01*
X80486Y11746D01*
G03X78501Y13731I-1370J615D01*
G01X78375Y13675D01*
X66451Y25599D01*
X66472Y25704D01*
G03X64704Y27472I-1472J296D01*
G01X64599Y27451D01*
X63503Y28547D01*
X63497Y28620D01*
G03X62120Y29997I-1497J-120D01*
G01X62047Y30003D01*
X59480Y32570D01*
Y42071D01*
X59600Y42123D01*
G03X59923Y44685I-600J1377D01*
G02Y45315I246J315D01*
G03Y47685I-923J1185D01*
G02Y48315I246J315D01*
G03X59600Y50877I-923J1185D01*
G01X59480Y50929D01*
Y54571D01*
X59600Y54623D01*
G03X60132Y56987I-600J1377D01*
G02Y57513I302J263D01*
G03Y59487I-1132J987D01*
G02Y60013I302J263D01*
G03X59600Y62377I-1132J987D01*
G01X59480Y62429D01*
Y78472D01*
X61157Y80149D01*
X61185Y80163D01*
G03X61487Y80368I-686J1336D01*
G02X62013I263J-302D01*
G03X64319Y80782I987J1132D01*
G01X78621D01*
G03X80379I879J1218D01*
G01X111713D01*
X120108Y72387D01*
Y68780D01*
X122218Y66670D01*
Y65629D01*
X122225Y65558D01*
G03X123479Y64304I1395J141D01*
G01X123550Y64297D01*
X124153Y63694D01*
X302146D01*
X302214Y63762D01*
X303626D01*
X306804Y66940D01*
X306946Y66802D01*
G03X308912Y68801I982J1000D01*
G01X308911D01*
X308769Y68943D01*
X309285Y69459D01*
Y69818D01*
X309299Y69893D01*
G03Y70908I-1307J508D01*
G01X309285Y70943D01*
Y76201D01*
X308117Y77369D01*
Y85539D01*
X307864Y85792D01*
X308067Y85995D01*
G03X308299Y88790I99J1399D01*
G02X308055Y89471I38J398D01*
G01X308117Y89533D01*
Y91320D01*
X308211Y91361D01*
G03X308237Y93941I-536J1296D01*
G01X308117Y93994D01*
Y98751D01*
X313588Y104222D01*
X313668Y104223D01*
G03X313906Y107203I-30J1502D01*
G01X313742Y107233D01*
Y115850D01*
X333000Y135108D01*
Y157090D01*
G03X334296Y168516I-6229J6493D01*
G01X334207Y168652D01*
X335092Y169537D01*
Y173176D01*
X335053Y173215D01*
Y197908D01*
G03X335563Y198443I-724J1201D01*
G01X336477Y199357D01*
Y215946D01*
G03Y217872I-1019J963D01*
G01Y219846D01*
G03Y221772I-1019J963D01*
G01Y223746D01*
G03X336860Y224710I-1019J963D01*
G01Y224793D01*
X339086Y227019D01*
Y229172D01*
X339216Y229210D01*
G03X339637Y231712I-378J1350D01*
G01Y233308D01*
G03X339811Y233450I-797J1154D01*
G03X339875Y235404I-973J1010D01*
G01Y237416D01*
G03Y239304I-1037J944D01*
G01Y240633D01*
X339872Y240636D01*
Y241313D01*
G03Y243207I-1034J947D01*
G01Y245080D01*
X340692Y245900D01*
X344212D01*
X344255Y245757D01*
G03X346941I1343J403D01*
G01X346984Y245900D01*
X350971D01*
X351014Y245757D01*
G03X353700I1343J403D01*
G01X353743Y245900D01*
X357731D01*
X357774Y245757D01*
G03X360460I1343J403D01*
G01X360503Y245900D01*
X364491D01*
X364534Y245757D01*
G03X367220I1343J403D01*
G01X367263Y245900D01*
X368942D01*
X369910Y246868D01*
X369935Y246882D01*
G03X370484Y247431I-678J1227D01*
G01X370498Y247456D01*
X371457Y248415D01*
Y248436D01*
G02X372030Y248796I400J-1D01*
G03X373435Y251213I609J1263D01*
G03X373164Y251359I-796J-1154D01*
G02X373050Y252005I169J363D01*
G01X373118Y252073D01*
X374604D01*
X374620Y251890D01*
G03X376626Y250746I1397J119D01*
G03X376838Y253146I-609J1263D01*
G02X376792Y253750I237J322D01*
G01X379569Y256527D01*
G02X380250Y256279I283J-283D01*
G03X381768Y257797I1397J121D01*
G02X381520Y258478I35J398D01*
G01X389475Y266433D01*
X400702D01*
X400718Y266418D01*
X427005D01*
X427779Y265644D01*
Y263600D01*
X426879Y262700D01*
X423500D01*
X423200Y262400D01*
Y258468D01*
X422600Y257868D01*
X418042D01*
X409701Y249527D01*
Y199027D01*
X414335Y194393D01*
Y132357D01*
X448360Y98332D01*
Y91269D01*
X448254Y91232D01*
G03X448226Y88578I438J-1332D01*
G01X448360Y88531D01*
Y86684D01*
X448216Y86642D01*
G03Y83950I394J-1346D01*
G01X448360Y83908D01*
Y74979D01*
X448241Y74944D01*
G03X447198Y73526I358J-1356D01*
G03X447688Y72523I1401J63D01*
G02X447699Y71926I-260J-303D01*
G03X447562Y70013I952J-1030D01*
G03X447768Y69807I1089J883D01*
G02Y69198I-260J-305D01*
G03X448218Y66749I859J-1108D01*
G01X448360Y66706D01*
Y65635D01*
X448289Y65564D01*
Y56107D01*
G03Y53659I684J-1224D01*
G01Y52396D01*
X448139Y52357D01*
G03Y49643I353J-1357D01*
G01X448289Y49604D01*
Y48367D01*
X448142Y48326D01*
G03Y45624I375J-1351D01*
G01X448289Y45583D01*
Y37167D01*
X448130Y37134D01*
G03Y34388I284J-1373D01*
G01X448289Y34355D01*
Y33313D01*
X448114Y33291D01*
G03X447077Y32599I179J-1391D01*
G03X448705Y30560I1215J-699D01*
G01X448801Y30588D01*
X449200Y30189D01*
Y29808D01*
G02X448673Y29429I-400J0D01*
G03Y26771I-447J-1329D01*
G02X449200Y26392I127J-379D01*
G01Y26011D01*
X448289Y25100D01*
Y18266D01*
G03Y15734I603J-1266D01*
G01Y15113D01*
X448114Y15091D01*
G03X447296Y12713I178J-1391D01*
G02X447281Y12136I-284J-281D01*
G03X448036Y9711I945J-1036D01*
G01X448108Y9701D01*
X448289Y9504D01*
Y-5384D01*
G02X447873Y-5784I-400J0D01*
G03Y-8576I-129J-1396D01*
G02X448289Y-8976I16J-400D01*
G01Y-11517D01*
X447306Y-12500D01*
X381576D01*
G02X381278Y-11834I0J400D01*
G03X379212Y-9938I-1046J934D01*
G02X378626Y-9933I-291J275D01*
G03X376969Y-9624I-1034J-947D01*
G03X376531Y-9963I622J-1256D01*
G02X375935Y-9964I-298J266D01*
G03X373731Y-10115I-1043J-936D01*
G03X373128Y-11933I670J-1231D01*
G02X372764Y-12500I-364J-167D01*
G01X104550D01*
G37*
G36*
G01X53000Y223300D02*
X51800Y224500D01*
Y258900D01*
X59984Y267084D01*
X72912D01*
X74529Y265467D01*
Y265408D01*
X74988Y264949D01*
Y224634D01*
X73654Y223300D01*
X53000D01*
G37*
G36*
G01X394310Y336640D02*
X392920Y338030D01*
Y338060D01*
X383343Y347637D01*
G02X383438Y348272I283J282D01*
G03X381413Y349834I-661J1237D01*
G01X381377Y349680D01*
X380556D01*
G02X380299Y350386I0J400D01*
G03X378495I-902J1074D01*
G02X378238Y349680I-257J-306D01*
G01X377418D01*
X377381Y349834D01*
G03X375179Y350633I-1363J-324D01*
G03X374935Y350400I839J-1123D01*
G01X374314D01*
G02X373942Y350946I0J400D01*
G03X371332I-1305J514D01*
G02X370960Y350400I-372J-146D01*
G01X370339D01*
G03X368175I-1082J-891D01*
G01X367554D01*
G02X367182Y350946I0J400D01*
G03X364572I-1305J514D01*
G02X364200Y350400I-372J-146D01*
G01X363579D01*
G03X361415I-1082J-891D01*
G01X360794D01*
G02X360422Y350946I0J400D01*
G03X357812I-1305J514D01*
G02X357440Y350400I-372J-146D01*
G01X356819D01*
G03X354655I-1082J-891D01*
G01X354034D01*
G02X353662Y350946I0J400D01*
G03X351052I-1305J514D01*
G02X350680Y350400I-372J-146D01*
G01X350060D01*
G03X347896I-1082J-891D01*
G01X347275D01*
G02X346903Y350946I0J400D01*
G03X344293I-1305J514D01*
G02X343921Y350400I-372J-146D01*
G01X343300D01*
G03X343208Y350502I-1086J-887D01*
G03X343136Y350569I-991J-992D01*
G03X343106Y350594I-912J-1064D01*
G01X340372Y353328D01*
Y359487D01*
X340175Y359684D01*
X340160Y359727D01*
G03X339465Y360514I-1322J-467D01*
G01Y361906D01*
G03X339617Y364326I-627J1254D01*
G01Y366003D01*
X338800Y366820D01*
Y367410D01*
X339617Y368227D01*
Y369793D01*
G03X339465Y372213I-778J1166D01*
G01Y372676D01*
X339233Y372908D01*
G02X339366Y373561I283J282D01*
G03X338263Y376139I-528J1299D01*
G02X337699Y376503I-164J365D01*
G01Y377117D01*
G02X338263Y377481I400J-1D01*
G03Y380039I575J1279D01*
G02X337699Y380403I-164J365D01*
G01Y396200D01*
X336194Y397705D01*
Y423100D01*
X336000Y423294D01*
Y469492D01*
X335954Y469538D01*
Y472717D01*
X310218Y498453D01*
Y508358D01*
G02X310693Y508751I400J0D01*
G03Y511477I328J1363D01*
G02X310218Y511870I-75J393D01*
G01Y518663D01*
X309150Y519731D01*
Y527834D01*
G03Y529892I-952J1029D01*
G01Y532310D01*
G03Y533890I-1158J790D01*
G01Y537408D01*
X308873Y537685D01*
G03X308403Y538155I-1198J-728D01*
G01X308201Y538357D01*
X307745D01*
G03X307605I-70J-1400D01*
G01X306733D01*
X303847Y541243D01*
X94693D01*
X91687Y538237D01*
X91664Y538223D01*
G03X89438Y535997I3019J-5245D01*
G01X89424Y535974D01*
X89000Y535550D01*
X72000D01*
X67650Y539900D01*
Y553534D01*
G03Y555466I-1150J966D01*
G01Y556534D01*
G03Y558466I-1150J966D01*
G01Y560534D01*
G03Y562466I-1150J966D01*
G01Y595034D01*
G03Y596966I-1150J966D01*
G01Y598034D01*
G03Y599966I-1150J966D01*
G01Y601034D01*
G03Y602966I-1150J966D01*
G01Y614100D01*
X70200Y616650D01*
X87629D01*
X89500Y614779D01*
Y611703D01*
G03X88633Y608394I5182J-3126D01*
G03X99762Y605263I6050J161D01*
G01X99773Y605281D01*
X105366Y610874D01*
X116261D01*
X117852Y612465D01*
G02X118525Y612271I283J-283D01*
G03X120969Y613481I1367J312D01*
G02X121276Y614137I307J256D01*
G01X122223D01*
G02X122533Y613484I0J-400D01*
G03X124707I1087J-885D01*
G02X125017Y614137I310J253D01*
G01X128877D01*
G02X129195Y613496I-1J-400D01*
G03X131431I1118J-847D01*
G02X131749Y614137I319J241D01*
G01X135383D01*
G02X135693Y613484I0J-400D01*
G03X135809Y611588I1087J-885D01*
G02Y611010I-277J-289D01*
G03X135840Y608959I971J-1011D01*
G02X135845Y608371I-269J-296D01*
G03X135835Y606339I961J-1021D01*
G02Y605761I-277J-289D01*
G03X137777I971J-1011D01*
G02Y606339I277J289D01*
G03X137746Y608390I-971J1011D01*
G02X137741Y608978I269J296D01*
G03X137751Y611010I-961J1021D01*
G02Y611588I277J289D01*
G03X137867Y613484I-971J1011D01*
G02X138177Y614137I310J253D01*
G01X140756D01*
G02X141011Y613429I0J-400D01*
G03X140926Y611348I895J-1079D01*
G02X140920Y610771I-280J-286D01*
G03X140913Y608734I960J-1022D01*
G02Y608155I-276J-290D01*
G03X140916Y606122I967J-1015D01*
G02X140919Y605544I-275J-290D01*
G03X142857Y605554I974J-1008D01*
G02X142854Y606132I275J290D01*
G03X142847Y608155I-974J1008D01*
G02Y608734I276J289D01*
G03X142860Y610751I-967J1015D01*
G02X142866Y611328I280J286D01*
G03X142801Y613429I-960J1022D01*
G02X143056Y614137I255J308D01*
G01X145609D01*
G02X145927Y613496I-1J-400D01*
G03X148163I1118J-847D01*
G02X148481Y614137I319J241D01*
G01X152302D01*
G02X152620Y613496I-1J-400D01*
G03X154856I1118J-847D01*
G02X155174Y614137I319J241D01*
G01X159034D01*
G02X159344Y613484I0J-400D01*
G03X161518I1087J-885D01*
G02X161828Y614137I310J253D01*
G01X165538D01*
G02X165856Y613496I-1J-400D01*
G03X168092I1118J-847D01*
G02X168410Y614137I319J241D01*
G01X172194D01*
G02X172504Y613484I0J-400D01*
G03X172620Y611588I1087J-885D01*
G02Y611010I-277J-289D01*
G03X172651Y608959I971J-1011D01*
G02X172656Y608371I-269J-296D01*
G03X172646Y606339I961J-1021D01*
G02Y605761I-277J-289D01*
G03X174588I971J-1011D01*
G02Y606339I277J289D01*
G03X174557Y608390I-971J1011D01*
G02X174552Y608978I269J296D01*
G03X174562Y611010I-961J1021D01*
G02Y611588I277J289D01*
G03X174678Y613484I-971J1011D01*
G02X174988Y614137I310J253D01*
G01X177567D01*
G02X177822Y613429I0J-400D01*
G03X177737Y611348I895J-1079D01*
G02X177731Y610771I-280J-286D01*
G03X177724Y608734I960J-1022D01*
G02Y608155I-276J-290D01*
G03X177727Y606122I967J-1015D01*
G02X177730Y605544I-275J-290D01*
G03X179668Y605554I974J-1008D01*
G02X179665Y606132I275J290D01*
G03X179658Y608155I-974J1008D01*
G02Y608734I276J289D01*
G03X179671Y610751I-967J1015D01*
G02X179677Y611328I280J286D01*
G03X179612Y613429I-960J1022D01*
G02X179867Y614137I255J308D01*
G01X182420D01*
G02X182738Y613496I-1J-400D01*
G03X184974I1118J-847D01*
G02X185292Y614137I319J241D01*
G01X189113D01*
G02X189431Y613496I-1J-400D01*
G03X191667I1118J-847D01*
G02X191985Y614137I319J241D01*
G01X195845D01*
G02X196155Y613484I0J-400D01*
G03X198329I1087J-885D01*
G02X198639Y614137I310J253D01*
G01X202499D01*
G02X202817Y613496I-1J-400D01*
G03X205053I1118J-847D01*
G02X205371Y614137I319J241D01*
G01X209005D01*
G02X209315Y613484I0J-400D01*
G03X209431Y611588I1087J-885D01*
G02Y611010I-277J-289D01*
G03X209462Y608959I971J-1011D01*
G02X209467Y608371I-269J-296D01*
G03X209457Y606339I961J-1021D01*
G02Y605761I-277J-289D01*
G03X211399I971J-1011D01*
G02Y606339I277J289D01*
G03X211368Y608390I-971J1011D01*
G02X211363Y608978I269J296D01*
G03X211373Y611010I-961J1021D01*
G02Y611588I277J289D01*
G03X211489Y613484I-971J1011D01*
G02X211799Y614137I310J253D01*
G01X214378D01*
G02X214633Y613429I0J-400D01*
G03X214548Y611348I895J-1079D01*
G02X214542Y610771I-280J-286D01*
G03X214535Y608734I960J-1022D01*
G02Y608155I-276J-290D01*
G03X214538Y606122I967J-1015D01*
G02X214541Y605544I-275J-290D01*
G03X216479Y605554I974J-1008D01*
G02X216476Y606132I275J290D01*
G03X216469Y608155I-974J1008D01*
G02Y608734I276J289D01*
G03X216482Y610751I-967J1015D01*
G02X216488Y611328I280J286D01*
G03X216423Y613429I-960J1022D01*
G02X216678Y614137I255J308D01*
G01X219231D01*
G02X219549Y613496I-1J-400D01*
G03X221785I1118J-847D01*
G02X222103Y614137I319J241D01*
G01X225924D01*
G02X226242Y613496I-1J-400D01*
G03X228478I1118J-847D01*
G02X228796Y614137I319J241D01*
G01X232656D01*
G02X232966Y613484I0J-400D01*
G03X235140I1087J-885D01*
G02X235450Y614137I310J253D01*
G01X239310D01*
G02X239628Y613496I-1J-400D01*
G03X241864I1118J-847D01*
G02X242182Y614137I319J241D01*
G01X245816D01*
G02X246126Y613484I0J-400D01*
G03X246242Y611588I1087J-885D01*
G02Y611010I-277J-289D01*
G03X246273Y608959I971J-1011D01*
G02X246278Y608371I-269J-296D01*
G03X246268Y606339I961J-1021D01*
G02Y605761I-277J-289D01*
G03X248210I971J-1011D01*
G02Y606339I277J289D01*
G03X248179Y608390I-971J1011D01*
G02X248174Y608978I269J296D01*
G03X248184Y611010I-961J1021D01*
G02Y611588I277J289D01*
G03X248300Y613484I-971J1011D01*
G02X248610Y614137I310J253D01*
G01X251189D01*
G02X251444Y613429I0J-400D01*
G03X251359Y611348I895J-1079D01*
G02X251353Y610771I-280J-286D01*
G03X251346Y608734I960J-1022D01*
G02Y608155I-276J-290D01*
G03X251349Y606122I967J-1015D01*
G02X251352Y605544I-275J-290D01*
G03X253290Y605554I974J-1008D01*
G02X253287Y606132I275J290D01*
G03X253280Y608155I-974J1008D01*
G02Y608734I276J289D01*
G03X253293Y610751I-967J1015D01*
G02X253299Y611328I280J286D01*
G03X253234Y613429I-960J1022D01*
G02X253489Y614137I255J308D01*
G01X256042D01*
G02X256360Y613496I-1J-400D01*
G03X258596I1118J-847D01*
G02X258914Y614137I319J241D01*
G01X262911D01*
G02X263191Y613451I0J-400D01*
G03X265151I980J-1002D01*
G02X265431Y614137I280J286D01*
G01X269657D01*
G02X269925Y613440I0J-400D01*
G03X271803I939J-1041D01*
G02X272071Y614137I268J297D01*
G01X276147D01*
G02X276427Y613451I0J-400D01*
G03X278387I980J-1002D01*
G02X278667Y614137I280J286D01*
G01X282627D01*
G02X282937Y613484I0J-400D01*
G03X283053Y611588I1087J-885D01*
G02Y611010I-277J-289D01*
G03X283084Y608959I971J-1011D01*
G02X283089Y608371I-269J-296D01*
G03X283079Y606339I961J-1021D01*
G02Y605761I-277J-289D01*
G03X285021I971J-1011D01*
G02Y606339I277J289D01*
G03X284990Y608390I-971J1011D01*
G02X284985Y608978I269J296D01*
G03X284995Y611010I-961J1021D01*
G02Y611588I277J289D01*
G03X285111Y613484I-971J1011D01*
G02X285421Y614137I310J253D01*
G01X288000D01*
G02X288255Y613429I0J-400D01*
G03X288170Y611348I895J-1079D01*
G02X288164Y610771I-280J-286D01*
G03X288157Y608734I960J-1022D01*
G02Y608155I-276J-290D01*
G03X288160Y606122I967J-1015D01*
G02X288163Y605544I-275J-290D01*
G03X290101Y605554I974J-1008D01*
G02X290098Y606132I275J290D01*
G03X290091Y608155I-974J1008D01*
G02Y608734I276J289D01*
G03X290104Y610751I-967J1015D01*
G02X290110Y611328I280J286D01*
G03X290045Y613429I-960J1022D01*
G02X290300Y614137I255J308D01*
G01X326486D01*
G02X326767Y613453I0J-400D01*
G03X328741I987J-996D01*
G02X329022Y614137I281J284D01*
G01X333179D01*
G02X333460Y613453I0J-400D01*
G03X335434I987J-996D01*
G02X335715Y614137I281J284D01*
G01X346674D01*
G02X346931Y613431I0J-400D01*
G03X348735I902J-1074D01*
G02X348992Y614137I257J306D01*
G01X353365D01*
G02X353623Y613431I0J-400D01*
G03X355427I902J-1073D01*
G02X355685Y614137I258J306D01*
G01X360018D01*
X363739Y617858D01*
X375292D01*
X382650Y610500D01*
X384300D01*
X384500Y610300D01*
Y609286D01*
X384586Y609200D01*
Y606105D01*
G03X391788I3601J0D01*
G01Y611005D01*
G03X391787Y611093I-3601J3D01*
G03X390823Y613482I-3601J-64D01*
G02X391116Y614154I293J272D01*
G01X393253D01*
G02X393570Y613511I-1J-400D01*
G03X395794I1112J-854D01*
G02X396111Y614154I318J243D01*
G01X399946D01*
G02X400263Y613511I0J-400D01*
G03X402489I1113J-853D01*
G02X402806Y614154I317J243D01*
G01X413332D01*
G02X413649Y613511I-1J-400D01*
G03X415873I1112J-854D01*
G02X416190Y614154I318J243D01*
G01X420025D01*
G02X420342Y613511I-1J-400D01*
G03X420053Y612607I1112J-854D01*
G03X422855I1401J-47D01*
G03X422566Y613511I-1401J50D01*
G02X422883Y614154I318J243D01*
G01X426718D01*
G02X427035Y613511I-1J-400D01*
G03X429259I1112J-854D01*
G02X429576Y614154I318J243D01*
G01X433411D01*
G02X433728Y613511I-1J-400D01*
G03X435952I1112J-854D01*
G02X436269Y614154I318J243D01*
G01X444261D01*
X449818Y608597D01*
Y592549D01*
G02X449264Y592180I-400J0D01*
G03X447661Y591850I-572J-1280D01*
G03X447445Y590259I1031J-950D01*
G02X447237Y589705I-356J-182D01*
G03X447156Y587117I498J-1311D01*
G03X448982Y589035I579J1277D01*
G02X449190Y589589I356J182D01*
G03X449264Y589620I-505J1308D01*
G02X449818Y589251I154J-369D01*
G01Y576179D01*
G02X449168Y575867I-400J0D01*
G03Y573679I-877J-1094D01*
G02X449818Y573367I250J-312D01*
G01Y570551D01*
G02X449168Y570239I-400J0D01*
G03Y568161I-942J-1039D01*
G02X449818Y567849I250J-312D01*
G01Y554749D01*
G02X449264Y554380I-400J0D01*
G03Y551820I-572J-1280D01*
G02X449818Y551451I154J-369D01*
G01Y551399D01*
G02X449227Y551048I-400J0D01*
G03X447113Y549726I-717J-1205D01*
G03X449480Y548830I1397J117D01*
G01X449538Y548885D01*
X449818D01*
Y548565D01*
X449610Y548357D01*
X449606D01*
X447892Y546643D01*
Y538956D01*
X447147Y538211D01*
Y537286D01*
X447132Y537250D01*
G03Y536196I1300J-527D01*
G01X447147Y536160D01*
Y531766D01*
X447130Y531727D01*
G03Y530585I1280J-571D01*
G01X447147Y530546D01*
Y529557D01*
X447430Y529274D01*
Y515912D01*
X447413Y515873D01*
G03Y514727I1279J-573D01*
G01X447430Y514688D01*
Y514170D01*
X447293Y514125D01*
G03X447954Y511409I441J-1331D01*
G02X448417Y511014I63J-395D01*
G01Y503025D01*
X414036Y468644D01*
Y430956D01*
X414018Y430937D01*
Y379400D01*
X413169Y378551D01*
G02X412487Y378818I-282J283D01*
G03X411028Y377359I-1401J-58D01*
G02X411295Y376677I-16J-400D01*
G01X410864Y376246D01*
X410805Y376233D01*
G03X409849Y375520I280J-1373D01*
G03X409692Y374707I1237J-660D01*
G03X409900Y374112I1394J153D01*
G01Y368980D01*
X407360Y366440D01*
Y358670D01*
X403870Y355180D01*
X402490D01*
X401520Y354210D01*
Y352000D01*
X403850Y349670D01*
X418270D01*
X420630Y347310D01*
Y344827D01*
X421384Y344073D01*
X421396D01*
X421988Y343481D01*
X431412D01*
X431897Y342996D01*
Y337611D01*
X430926Y336640D01*
X394310D01*
G37*
G36*
G01X1309000Y-18500D02*
X1308023Y-17523D01*
X1308078Y-17399D01*
G03X1306101Y-15422I-1378J599D01*
G01X1305977Y-15477D01*
X1304020Y-13520D01*
X1295229D01*
X1295206Y-13347D01*
G03X1292426I-1390J-186D01*
G01X1292403Y-13520D01*
X1285838D01*
G03X1284181Y-13297I-979J-1004D01*
G01X1284049Y-13369D01*
X1279509Y-8829D01*
X1274971D01*
X1271300Y-12500D01*
X1031184D01*
G02X1030886Y-11834I0J400D01*
G03X1031126Y-10341I-1046J934D01*
G02X1031197Y-10096I184J80D01*
G03X1030373Y-7536I-790J1158D01*
G02X1029981Y-7021I-9J400D01*
G03X1028673Y-8017I-1342J406D01*
G02X1029065Y-8532I9J-400D01*
G03X1029121Y-9497I1342J-406D01*
G02X1029050Y-9741I-183J-79D01*
G03X1028820Y-9938I792J-1157D01*
G02X1028234Y-9933I-291J275D01*
G03X1026143Y-9959I-1034J-947D01*
G02X1025543Y-9964I-302J262D01*
G03X1023454Y-11834I-1043J-936D01*
G02X1023156Y-12500I-298J-266D01*
G01X955374D01*
Y-8286D01*
X955382Y-8259D01*
G03Y-7443I-1446J408D01*
G01X955374Y-7416D01*
Y-4135D01*
X955382Y-4108D01*
G03Y-3292I-1446J408D01*
G01X955374Y-3265D01*
Y29514D01*
X955382Y29541D01*
G03Y30357I-1446J408D01*
G01X955374Y30384D01*
Y33665D01*
X955382Y33692D01*
G03Y34508I-1446J408D01*
G01X955374Y34535D01*
Y49479D01*
X955382Y49506D01*
G03Y50322I-1446J408D01*
G01X955374Y50349D01*
Y52179D01*
X955382Y52206D01*
G03Y53022I-1446J408D01*
G01X955374Y53049D01*
Y67314D01*
X955382Y67341D01*
G03Y68157I-1446J408D01*
G01X955374Y68184D01*
Y68450D01*
X955751D01*
G02X956147Y67995I0J-400D01*
G03X958401Y68906I1389J-193D01*
G02X958505Y69329I378J131D01*
G03X958253Y71641I-905J1071D01*
G01X958146Y71697D01*
Y72765D01*
G03X957792Y75071I-946J1035D01*
G01X957677Y75125D01*
Y85795D01*
G02X957864Y85995I200J0D01*
G03Y88793I-90J1399D01*
G02X957677Y88993I13J200D01*
G01Y91305D01*
X957803Y91355D01*
G03Y93959I-520J1302D01*
G01X957677Y94009D01*
Y98703D01*
X963196Y104222D01*
X963276Y104223D01*
G03X963514Y107203I-30J1502D01*
G01X963350Y107233D01*
Y115850D01*
X984000Y136500D01*
Y158800D01*
G03Y168366I-7621J4783D01*
G01Y195300D01*
X985050Y196350D01*
Y198000D01*
X985400Y198350D01*
Y199900D01*
X985050Y200250D01*
Y201811D01*
X984961Y201900D01*
Y214000D01*
X984200Y214761D01*
Y215169D01*
G02X984693Y215558I400J0D01*
G03X986444Y216653I373J1351D01*
G03X985044Y218311I-1378J256D01*
G02X984755Y218994I-7J400D01*
G01X984961Y219200D01*
Y219210D01*
X985147Y219407D01*
X985220Y219415D01*
G03Y222203I-154J1394D01*
G01X985147Y222211D01*
X984961Y222408D01*
Y223110D01*
X985147Y223307D01*
X985220Y223315D01*
G03X986147Y223816I-154J1394D01*
G03X986465Y224794I-1081J892D01*
G01X986460Y224884D01*
X988665Y227089D01*
Y229167D01*
X988795Y229202D01*
G03X989265Y229422I-349J1358D01*
G03X989078Y231812I-819J1138D01*
G01X988968Y231868D01*
Y233152D01*
X989078Y233208D01*
G03Y235712I-632J1252D01*
G01X988968Y235768D01*
Y237052D01*
X989078Y237108D01*
G03Y239612I-632J1252D01*
G01X988968Y239668D01*
Y240952D01*
X989078Y241008D01*
G03Y243512I-632J1252D01*
G01X988968Y243568D01*
Y244568D01*
X990300Y245900D01*
X993820D01*
X993863Y245757D01*
G03X996549I1343J403D01*
G01X996592Y245900D01*
X1000579D01*
X1000622Y245757D01*
G03X1003308I1343J403D01*
G01X1003351Y245900D01*
X1007339D01*
X1007382Y245757D01*
G03X1010068I1343J403D01*
G01X1010111Y245900D01*
X1014099D01*
X1014142Y245757D01*
G03X1016828I1343J403D01*
G01X1016871Y245900D01*
X1018550D01*
X1019518Y246868D01*
X1019543Y246882D01*
G03X1020092Y247431I-678J1227D01*
G01X1020106Y247456D01*
X1021508Y248858D01*
X1021636Y248797D01*
G03X1023508Y250669I609J1263D01*
G01X1023447Y250797D01*
X1023884Y251234D01*
G02X1024488Y251188I282J-283D01*
G03X1026446Y253146I1137J821D01*
G02X1026400Y253750I237J322D01*
G01X1029177Y256527D01*
G02X1029858Y256279I283J-283D01*
G03X1031376Y257797I1397J121D01*
G02X1031128Y258478I35J398D01*
G01X1039083Y266433D01*
X1050310D01*
X1050322Y266422D01*
X1076908D01*
X1077625Y265705D01*
Y264900D01*
X1068077Y255352D01*
X1067972Y255374D01*
G03X1066318Y253720I-280J-1374D01*
G01X1066340Y253615D01*
X1061374Y248649D01*
Y226000D01*
X1060000Y224626D01*
Y204374D01*
X1061374Y203000D01*
Y196962D01*
X1063943Y194393D01*
Y132357D01*
X1098055Y98245D01*
Y91289D01*
X1097911Y91247D01*
G03Y88553I389J-1347D01*
G01X1098055Y88511D01*
Y86698D01*
X1097900Y86662D01*
G03Y83930I318J-1366D01*
G01X1098055Y83894D01*
Y74992D01*
X1097899Y74957D01*
G03X1097296Y72523I308J-1368D01*
G02X1097307Y71926I-260J-303D01*
G03X1097170Y70013I952J-1030D01*
G03X1097376Y69807I1089J883D01*
G02Y69198I-260J-305D01*
G03X1097250Y67092I859J-1108D01*
G03X1097902Y66728I985J998D01*
G01X1098055Y66691D01*
Y60088D01*
X1099143Y59000D01*
X1266398D01*
G02X1266778Y58476I0J-400D01*
G03X1269444I1333J-436D01*
G02X1269824Y59000I380J124D01*
G01X1316645D01*
X1317732Y57913D01*
X1319464D01*
X1320551Y59000D01*
X1324000D01*
X1326455Y56545D01*
X1326346Y56406D01*
G03X1327343Y54146I1106J-862D01*
G03X1328237Y54014I656J1351D01*
G02X1328700Y53619I63J-395D01*
G01Y53402D01*
G02X1328300Y53002I-400J0D01*
G03X1327800Y52916I1J-1503D01*
G03X1326230Y52141I-300J-1369D01*
G02X1325742Y51930I-363J169D01*
G03X1324955Y51959I-443J-1330D01*
G03X1324472Y49468I-828J-1132D01*
G03X1326570Y50006I828J1132D01*
G02X1327058Y50216I362J-169D01*
G03X1327638Y50152I440J1331D01*
G03X1328300Y49998I662J1347D01*
G02X1328700Y49598I0J-400D01*
G01Y4007D01*
X1328557Y3964D01*
G03Y1086I430J-1439D01*
G01X1328700Y1043D01*
Y-11192D01*
X1328535Y-11222D01*
G03X1327923Y-13920I265J-1478D01*
G02X1327973Y-14527I-233J-325D01*
G01X1326988Y-15512D01*
X1326871Y-15474D01*
G03X1324974Y-17371I-471J-1426D01*
G01X1325012Y-17488D01*
X1324000Y-18500D01*
X1309000D01*
G37*
G36*
G01X1029455Y356693D02*
X1029345Y356720D01*
G03X1027645Y355020I-340J-1360D01*
G01X1027672Y354910D01*
X1024136Y351374D01*
X1023657D01*
X1023643Y351560D01*
G03X1020847I-1398J-100D01*
G01X1020833Y351374D01*
X1016897D01*
X1016883Y351560D01*
G03X1014276Y350750I-1398J-100D01*
G02X1013931Y350148I-345J-202D01*
G01X1013353D01*
G03X1010857I-1248J-639D01*
G01X1010279D01*
G02X1009934Y350750I0J400D01*
G03X1007330Y351319I-1209J710D01*
G02X1006649Y350996I-398J-41D01*
G01X1006342Y351303D01*
X1004836D01*
X1003681Y350148D01*
X1003519D01*
G02X1003174Y350750I0J400D01*
G03X1000756I-1209J710D01*
G02X1000411Y350148I-345J-202D01*
G01X999834D01*
G03X997338I-1248J-639D01*
G01X996760D01*
G02X996415Y350750I0J400D01*
G03X993997I-1209J710D01*
G02X993652Y350148I-345J-202D01*
G01X993074D01*
G03X992349Y350810I-1248J-639D01*
G03X991697Y350905I-522J-1301D01*
G01X991604Y350896D01*
X988776Y353724D01*
Y353990D01*
X988910Y354037D01*
G03Y356683I-464J1323D01*
G01X988776Y356730D01*
Y357890D01*
X988910Y357937D01*
G03Y360583I-464J1323D01*
G01X988776Y360630D01*
Y361790D01*
X988910Y361837D01*
G03Y364483I-464J1323D01*
G01X988776Y364530D01*
Y366164D01*
X988390Y366550D01*
Y367570D01*
X988776Y367956D01*
Y369589D01*
X988910Y369636D01*
G03X988523Y372359I-464J1323D01*
G01X988447Y372363D01*
X988030Y372780D01*
G02X988333Y373463I283J283D01*
G03X987384Y375775I113J1397D01*
G02X986689Y376045I-295J270D01*
G01Y377575D01*
G02X987384Y377845I400J0D01*
G03Y379675I1062J915D01*
G02X986689Y379945I-295J270D01*
G01Y385918D01*
X985500Y387107D01*
Y426063D01*
X984282Y427282D01*
X984200Y427364D01*
Y434716D01*
G03Y443630I-7821J4457D01*
G01Y474348D01*
X959350Y499198D01*
Y508541D01*
G02X959945Y508890I400J0D01*
G03Y511338I684J1224D01*
G02X959350Y511687I-195J349D01*
G01Y535442D01*
G02X959782Y535840I400J-1D01*
G03Y538074I847J1117D01*
G02X959350Y538472I-32J399D01*
G01Y546399D01*
G02X959782Y546797I400J-1D01*
G03Y549031I847J1117D01*
G02X959350Y549429I-32J399D01*
G01Y573242D01*
G02X959782Y573640I400J-1D01*
G03X959379Y575393I847J1117D01*
G02X958895Y575455I-202J345D01*
G01X956000Y578350D01*
Y586874D01*
G02X956634Y587198I400J0D01*
G03X958416Y589356I823J1135D01*
G02X958426Y589947I274J291D01*
G03X958325Y592134I-926J1053D01*
G02X958179Y592578I235J323D01*
G03X956432Y594772I-896J1079D01*
G02X956000Y595170I-32J398D01*
G01Y606044D01*
G02X956696Y606313I400J0D01*
G03Y608127I1069J907D01*
G02X956000Y608396I-296J269D01*
G01Y609162D01*
X957052Y610214D01*
X957146Y610205D01*
G03X958646Y611927I137J1395D01*
G03X958686Y612021I-1361J635D01*
G01X958701Y612061D01*
X960077Y613437D01*
X975656D01*
G02X976040Y612924I0J-400D01*
G03X978684I1322J-467D01*
G02X979068Y613437I384J113D01*
G01X982349D01*
G02X982733Y612924I0J-400D01*
G03X985377I1322J-467D01*
G02X985761Y613437I384J113D01*
G01X995773D01*
G02X996148Y612900I-1J-400D01*
G03X998734I1293J-543D01*
G02X999109Y613437I376J137D01*
G01X1002464D01*
G02X1002834Y612886I0J-400D01*
G03X1005432I1299J-528D01*
G02X1005802Y613437I370J151D01*
G01X1007481D01*
X1011944Y617900D01*
X1025000D01*
X1028578Y614322D01*
X1028516Y614194D01*
G03X1030390Y612320I1261J-613D01*
G01X1030518Y612382D01*
X1034194Y608706D01*
Y606128D01*
G03X1034202Y605882I3601J-6D01*
G03X1041398Y606105I3595J223D01*
G01Y611005D01*
G03X1041396Y611136I-3601J11D01*
G01Y612196D01*
X1042525Y613325D01*
X1042959D01*
Y613095D01*
X1042950Y613067D01*
G03X1044973Y611433I1341J-409D01*
G03X1045678Y612866I-682J1225D01*
G02X1046073Y613325I395J59D01*
G01X1049202D01*
G02X1049597Y612866I0J-400D01*
G03X1052371I1387J-208D01*
G02X1052766Y613325I395J59D01*
G01X1062588D01*
G02X1062985Y612880I-1J-400D01*
G03X1065753I1384J-223D01*
G02X1066150Y613325I398J45D01*
G01X1069281D01*
G02X1069676Y612866I-1J-400D01*
G03X1069661Y612613I1386J-209D01*
G03X1072463I1401J-53D01*
G03X1072448Y612866I-1401J44D01*
G02X1072843Y613325I396J59D01*
G01X1075974D01*
G02X1076371Y612880I-1J-400D01*
G03X1079139I1384J-223D01*
G02X1079536Y613325I398J45D01*
G01X1082667D01*
G02X1083064Y612880I-1J-400D01*
G03X1085832I1384J-223D01*
G02X1086229Y613325I398J45D01*
G01X1095592D01*
G02X1095987Y612866I0J-400D01*
G03X1098761I1387J-207D01*
G02X1099156Y613325I395J59D01*
G01X1099409D01*
G02X1099802Y612853I0J-400D01*
G03X1102560I1379J-254D01*
G02X1102953Y613325I393J72D01*
G01X1106094D01*
G02X1106491Y612879I0J-400D01*
G03X1109257I1383J-230D01*
G02X1109654Y613325I397J46D01*
G01X1112568D01*
G02X1112961Y612853I0J-400D01*
G03X1112991Y612219I1379J-252D01*
G03X1113378Y611579I1350J379D01*
G02Y611019I-286J-280D01*
G03X1113407Y608953I962J-1020D01*
G02X1113405Y608371I-276J-290D01*
G03X1113005Y607685I961J-1020D01*
G03X1113404Y606330I1361J-335D01*
G02Y605770I-286J-280D01*
G03X1115328I962J-1020D01*
G02Y606330I286J280D01*
G03X1115299Y608396I-962J1020D01*
G02X1115301Y608978I276J290D01*
G03X1115701Y609664I-961J1020D01*
G03X1115302Y611019I-1361J335D01*
G02Y611579I286J280D01*
G03X1115689Y612219I-963J1019D01*
G03X1115719Y612853I-1349J382D01*
G02X1116112Y613325I393J72D01*
G01X1117758D01*
G02X1118137Y612797I0J-400D01*
G03X1118064Y612381I1329J-448D01*
G03X1118497Y611337I1402J-30D01*
G02X1118480Y610771I-291J-275D01*
G03X1118067Y609467I960J-1021D01*
G03X1118479Y608729I1373J282D01*
G02Y608160I-282J-285D01*
G03X1118397Y606203I961J-1020D01*
G03X1118476Y606122I1042J938D01*
G02X1118489Y605554I-275J-290D01*
G03X1119656Y603149I964J-1018D01*
G03X1120417Y605554I-203J1387D01*
G02X1120404Y606122I275J290D01*
G03X1120401Y608160I-964J1018D01*
G02Y608729I282J284D01*
G03X1120409Y610762I-961J1020D01*
G02X1120426Y611328I291J275D01*
G03X1120795Y612797I-960J1022D01*
G02X1121174Y613325I379J128D01*
G01X1122826D01*
G02X1123223Y612879I0J-400D01*
G03X1125989I1383J-230D01*
G02X1126386Y613325I397J46D01*
G01X1129519D01*
G02X1129916Y612879I0J-400D01*
G03X1132682I1383J-230D01*
G02X1133079Y613325I397J46D01*
G01X1136220D01*
G02X1136613Y612853I0J-400D01*
G03X1139371I1379J-254D01*
G02X1139764Y613325I393J72D01*
G01X1140041D01*
G02X1140327Y612646I0J-400D01*
G03X1142337I1005J-978D01*
G02X1142623Y613325I286J279D01*
G01X1142905D01*
G02X1143302Y612879I0J-400D01*
G03X1146068I1383J-230D01*
G02X1146465Y613325I397J46D01*
G01X1149380D01*
G02X1149773Y612853I0J-400D01*
G03X1149803Y612219I1379J-252D01*
G03X1150190Y611579I1350J379D01*
G02Y611019I-286J-280D01*
G03X1150219Y608953I962J-1020D01*
G02X1150217Y608371I-276J-290D01*
G03X1149817Y607685I961J-1020D01*
G03X1150216Y606330I1361J-335D01*
G02Y605770I-286J-280D01*
G03X1152140I962J-1020D01*
G02Y606330I286J280D01*
G03X1152111Y608396I-962J1020D01*
G02X1152113Y608978I276J290D01*
G03X1152513Y609664I-961J1020D01*
G03X1152114Y611019I-1361J335D01*
G02Y611579I286J280D01*
G03X1152501Y612219I-963J1019D01*
G03X1152531Y612853I-1349J382D01*
G02X1152924Y613325I393J72D01*
G01X1154570D01*
G02X1154949Y612797I0J-400D01*
G03X1154876Y612381I1329J-448D01*
G03X1155309Y611337I1402J-30D01*
G02X1155292Y610771I-291J-275D01*
G03X1154879Y609467I960J-1021D01*
G03X1155291Y608729I1373J282D01*
G02Y608160I-282J-285D01*
G03X1155209Y606203I961J-1020D01*
G03X1155288Y606122I1042J938D01*
G02X1155301Y605554I-275J-290D01*
G03X1156468Y603149I964J-1018D01*
G03X1157229Y605554I-203J1387D01*
G02X1157216Y606122I275J290D01*
G03X1157213Y608160I-964J1018D01*
G02Y608729I282J284D01*
G03X1157221Y610762I-961J1020D01*
G02X1157238Y611328I291J275D01*
G03X1157607Y612797I-960J1022D01*
G02X1157986Y613325I379J128D01*
G01X1159637D01*
G02X1160034Y612879I0J-400D01*
G03X1162800I1383J-230D01*
G02X1163197Y613325I397J46D01*
G01X1166330D01*
G02X1166727Y612879I0J-400D01*
G03X1169493I1383J-230D01*
G02X1169890Y613325I397J46D01*
G01X1173031D01*
G02X1173424Y612853I0J-400D01*
G03X1176182I1379J-254D01*
G02X1176575Y613325I393J72D01*
G01X1179716D01*
G02X1180113Y612879I0J-400D01*
G03X1182879I1383J-230D01*
G02X1183276Y613325I397J46D01*
G01X1186191D01*
G02X1186584Y612853I0J-400D01*
G03X1186614Y612219I1379J-252D01*
G03X1187001Y611579I1350J379D01*
G02Y611019I-286J-280D01*
G03X1187030Y608953I962J-1020D01*
G02X1187028Y608371I-276J-290D01*
G03X1186628Y607685I961J-1020D01*
G03X1187027Y606330I1361J-335D01*
G02Y605770I-286J-280D01*
G03X1188951I962J-1020D01*
G02Y606330I286J280D01*
G03X1188922Y608396I-962J1020D01*
G02X1188924Y608978I276J290D01*
G03X1189324Y609664I-961J1020D01*
G03X1188925Y611019I-1361J335D01*
G02Y611579I286J280D01*
G03X1189312Y612219I-963J1019D01*
G03X1189342Y612853I-1349J382D01*
G02X1189735Y613325I393J72D01*
G01X1191381D01*
G02X1191760Y612797I0J-400D01*
G03X1191687Y612381I1329J-448D01*
G03X1192120Y611337I1402J-30D01*
G02X1192103Y610771I-291J-275D01*
G03X1191690Y609467I960J-1021D01*
G03X1192102Y608729I1373J282D01*
G02Y608160I-282J-285D01*
G03X1192020Y606203I961J-1020D01*
G03X1192099Y606122I1042J938D01*
G02X1192112Y605554I-275J-290D01*
G03X1193279Y603149I964J-1018D01*
G03X1194040Y605554I-203J1387D01*
G02X1194027Y606122I275J290D01*
G03X1194024Y608160I-964J1018D01*
G02Y608729I282J284D01*
G03X1194032Y610762I-961J1020D01*
G02X1194049Y611328I291J275D01*
G03X1194418Y612797I-960J1022D01*
G02X1194797Y613325I379J128D01*
G01X1196448D01*
G02X1196845Y612879I0J-400D01*
G03X1199611I1383J-230D01*
G02X1200008Y613325I397J46D01*
G01X1203141D01*
G02X1203538Y612879I0J-400D01*
G03X1206304I1383J-230D01*
G02X1206701Y613325I397J46D01*
G01X1209842D01*
G02X1210235Y612853I0J-400D01*
G03X1212993I1379J-254D01*
G02X1213386Y613325I393J72D01*
G01X1216527D01*
G02X1216924Y612879I0J-400D01*
G03X1219690I1383J-230D01*
G02X1220087Y613325I397J46D01*
G01X1223002D01*
G02X1223395Y612853I0J-400D01*
G03X1223425Y612219I1379J-252D01*
G03X1223812Y611579I1350J379D01*
G02Y611019I-286J-280D01*
G03X1223841Y608953I962J-1020D01*
G02X1223839Y608371I-276J-290D01*
G03X1223439Y607685I961J-1020D01*
G03X1223838Y606330I1361J-335D01*
G02Y605770I-286J-280D01*
G03X1225762I962J-1020D01*
G02Y606330I286J280D01*
G03X1225733Y608396I-962J1020D01*
G02X1225735Y608978I276J290D01*
G03X1226135Y609664I-961J1020D01*
G03X1225736Y611019I-1361J335D01*
G02Y611579I286J280D01*
G03X1226123Y612219I-963J1019D01*
G03X1226153Y612853I-1349J382D01*
G02X1226546Y613325I393J72D01*
G01X1228192D01*
G02X1228571Y612797I0J-400D01*
G03X1228498Y612381I1329J-448D01*
G03X1228931Y611337I1402J-30D01*
G02X1228914Y610771I-291J-275D01*
G03X1228501Y609467I960J-1021D01*
G03X1228913Y608729I1373J282D01*
G02Y608160I-282J-285D01*
G03X1228831Y606203I961J-1020D01*
G03X1228910Y606122I1042J938D01*
G02X1228923Y605554I-275J-290D01*
G03X1230090Y603149I964J-1018D01*
G03X1230851Y605554I-203J1387D01*
G02X1230838Y606122I275J290D01*
G03X1230835Y608160I-964J1018D01*
G02Y608729I282J284D01*
G03X1230843Y610762I-961J1020D01*
G02X1230860Y611328I291J275D01*
G03X1231229Y612797I-960J1022D01*
G02X1231608Y613325I379J128D01*
G01X1233259D01*
G02X1233656Y612879I0J-400D01*
G03X1236422I1383J-230D01*
G02X1236819Y613325I397J46D01*
G01X1239952D01*
G02X1240349Y612879I0J-400D01*
G03X1243115I1383J-230D01*
G02X1243512Y613325I397J46D01*
G01X1246645D01*
G02X1247042Y612879I0J-400D01*
G03X1249808I1383J-230D01*
G02X1250205Y613325I397J46D01*
G01X1250439D01*
Y613095D01*
X1250430Y613067D01*
G03X1251768Y611255I1341J-410D01*
G03X1253155Y612880I3J1402D01*
G02X1253552Y613325I398J45D01*
G01X1253786D01*
Y613095D01*
X1253777Y613067D01*
G03X1253724Y612506I1341J-410D01*
G03X1256514Y612787I1396J128D01*
G03X1256504Y612866I-1395J-137D01*
G02X1256899Y613325I396J59D01*
G01X1257132D01*
Y613095D01*
X1257123Y613067D01*
G03X1258462Y611255I1341J-410D01*
G03X1259848Y612880I2J1402D01*
G02X1260245Y613325I398J45D01*
G01X1260479D01*
Y613095D01*
X1260470Y613067D01*
G03X1261808Y611255I1341J-410D01*
G03X1263195Y612880I3J1402D01*
G02X1263592Y613325I398J45D01*
G01X1263825D01*
Y613095D01*
X1263816Y613067D01*
G03X1265154Y611255I1341J-410D01*
G03X1266541Y612880I3J1402D01*
G02X1266938Y613325I398J45D01*
G01X1282633D01*
G02X1282929Y612656I0J-400D01*
G03X1281377Y607996I4472J-4078D01*
G03X1293435Y609044I6026J559D01*
G03X1291873Y612656I-6034J-466D01*
G02X1292169Y613325I296J269D01*
G01X1293150D01*
X1295475Y611000D01*
X1324700D01*
X1326050Y609650D01*
Y574650D01*
X1324279Y572879D01*
X1324182Y572891D01*
G03X1322897Y570381I-182J-1491D01*
G01X1322950Y570323D01*
Y569977D01*
X1322897Y569919D01*
G03Y567881I1103J-1019D01*
G01X1322950Y567823D01*
Y567401D01*
G03Y564889I824J-1256D01*
G01Y564401D01*
G03Y561889I824J-1256D01*
G01Y559803D01*
X1322838Y559748D01*
G03X1322577Y557215I662J-1348D01*
G02Y556585I-246J-315D01*
G03Y554215I923J-1185D01*
G02Y553585I-246J-315D01*
G03X1322838Y551052I923J-1185D01*
G01X1322950Y550997D01*
Y547650D01*
X1317575Y542275D01*
X1317208D01*
Y542539D01*
X1317245Y542590D01*
G03X1314816Y542836I-1145J810D01*
G02X1314450Y542275I-366J-161D01*
G01X1309650D01*
G02X1309251Y542692I1J400D01*
G03X1306824Y543705I-1401J58D01*
G02X1306302Y543650I-293J273D01*
G03X1304349Y543300I-802J-1150D01*
G01X1275000D01*
X1273200Y541500D01*
X1099610D01*
X1098000Y539890D01*
Y538135D01*
X1097850Y538112D01*
G03X1097279Y535546I190J-1389D01*
G02X1097290Y534909I-237J-323D01*
G03X1096759Y533872I870J-1100D01*
G03X1097170Y532816I1401J-63D01*
G02X1097127Y532239I-297J-268D01*
G03X1096622Y531028I891J-1082D01*
G03X1097414Y529891I1396J128D01*
G01X1097500Y529847D01*
Y518700D01*
X1098000Y518200D01*
Y516677D01*
X1097862Y516632D01*
G03X1097053Y514659I438J-1332D01*
G02X1096845Y514105I-356J-182D01*
G03X1096723Y514052I497J-1311D01*
G03X1097543Y511406I619J-1258D01*
G02X1098000Y511010I57J-396D01*
G01Y503000D01*
X1063644Y468644D01*
Y430956D01*
X1063626Y430937D01*
Y369226D01*
X1056990Y362590D01*
X1052906D01*
X1052890Y362593D01*
G03X1052438I-226J-1384D01*
G01X1052422Y362590D01*
X1051078D01*
G02X1050680Y363028I0J400D01*
G03X1047888I-1396J132D01*
G02X1047490Y362590I-398J-38D01*
G01X1046146D01*
X1046130Y362593D01*
G03X1045678I-226J-1384D01*
G01X1045662Y362590D01*
X1044318D01*
G02X1043920Y363028I0J400D01*
G03X1041128I-1396J132D01*
G02X1040730Y362590I-398J-38D01*
G01X1039387D01*
X1039371Y362593D01*
G03X1038919I-226J-1384D01*
G01X1038903Y362590D01*
X1037559D01*
G02X1037161Y363028I0J400D01*
G03X1034720Y362225I-1396J132D01*
G01X1034846Y362084D01*
X1034346Y361584D01*
G02X1033690Y361720I-284J282D01*
G03X1031874Y359904I-1305J-511D01*
G02X1032010Y359248I-146J-372D01*
G01X1029455Y356693D01*
G37*
%LPC*%
G75*
G36*
G01X325676Y104251D02*
G03X326253Y104144I338J214D01*
G02X325908Y102270I839J-1123D01*
G03X325331Y102377I-338J-214D01*
G02X325676Y104251I-839J1123D01*
G37*
G36*
G01X364145Y86617D02*
G03X363524I-311J-252D01*
G02Y88383I-1089J883D01*
G03X364145I310J252D01*
G02Y86617I1089J-883D01*
G37*
G36*
G01X376347Y85404D02*
G03Y84850I288J-277D01*
G02X374327I-1010J-973D01*
G03Y85404I-288J277D01*
G02X376347I1010J973D01*
G37*
G36*
G01X358743Y69924D02*
G03Y69346I277J-289D01*
G02X356801I-971J-1011D01*
G03Y69924I-277J289D01*
G02X358743I971J1011D01*
G37*
G36*
G01X305257Y51564D02*
G03Y50964I265J-300D01*
G02X303399I-929J-1050D01*
G03Y51564I-265J300D01*
G02X305257I929J1050D01*
G37*
G36*
G01X298564D02*
G03Y50964I265J-300D01*
G02X296706I-929J-1050D01*
G03Y51564I-265J300D01*
G02X298564I929J1050D01*
G37*
G36*
G01X281132D02*
G03Y50964I265J-300D01*
G02X279274I-929J-1050D01*
G03Y51564I-265J300D01*
G02X281132I929J1050D01*
G37*
G36*
G01X268446D02*
G03Y50964I265J-300D01*
G02X266588I-929J-1050D01*
G03Y51564I-265J300D01*
G02X268446I929J1050D01*
G37*
G36*
G01X261753D02*
G03Y50964I265J-300D01*
G02X259895I-929J-1050D01*
G03Y51564I-265J300D01*
G02X261753I929J1050D01*
G37*
G36*
G01X244321D02*
G03Y50964I265J-300D01*
G02X242463I-929J-1050D01*
G03Y51564I-265J300D01*
G02X244321I929J1050D01*
G37*
G36*
G01X238039Y51521D02*
G03X238050Y50944I282J-283D01*
G02X236109Y50907I-951J-1030D01*
G03X236098Y51484I-282J283D01*
G02X238039Y51521I951J1030D01*
G37*
G36*
G01X231635Y51564D02*
G03Y50964I265J-300D01*
G02X229777I-929J-1050D01*
G03Y51564I-265J300D01*
G02X231635I929J1050D01*
G37*
G36*
G01X224942D02*
G03Y50964I265J-300D01*
G02X223084I-929J-1050D01*
G03Y51564I-265J300D01*
G02X224942I929J1050D01*
G37*
G36*
G01X207510D02*
G03Y50964I265J-300D01*
G02X205652I-929J-1050D01*
G03Y51564I-265J300D01*
G02X207510I929J1050D01*
G37*
G36*
G01X201228Y51521D02*
G03X201239Y50944I282J-283D01*
G02X199298Y50907I-951J-1030D01*
G03X199287Y51484I-282J283D01*
G02X201228Y51521I951J1030D01*
G37*
G36*
G01X194824Y51564D02*
G03Y50964I265J-300D01*
G02X192966I-929J-1050D01*
G03Y51564I-265J300D01*
G02X194824I929J1050D01*
G37*
G36*
G01X188131D02*
G03Y50964I265J-300D01*
G02X186273I-929J-1050D01*
G03Y51564I-265J300D01*
G02X188131I929J1050D01*
G37*
G36*
G01X170699D02*
G03Y50964I265J-300D01*
G02X168841I-929J-1050D01*
G03Y51564I-265J300D01*
G02X170699I929J1050D01*
G37*
G36*
G01X164417Y51521D02*
G03X164428Y50944I282J-283D01*
G02X162487Y50907I-951J-1030D01*
G03X162476Y51484I-282J283D01*
G02X164417Y51521I951J1030D01*
G37*
G36*
G01X158013Y51564D02*
G03Y50964I265J-300D01*
G02X156155I-929J-1050D01*
G03Y51564I-265J300D01*
G02X158013I929J1050D01*
G37*
G36*
G01X151320D02*
G03Y50964I265J-300D01*
G02X149462I-929J-1050D01*
G03Y51564I-265J300D01*
G02X151320I929J1050D01*
G37*
G36*
G01X133888D02*
G03Y50964I265J-300D01*
G02X132030I-929J-1050D01*
G03Y51564I-265J300D01*
G02X133888I929J1050D01*
G37*
G36*
G01X127606Y51521D02*
G03X127617Y50944I282J-283D01*
G02X125676Y50907I-951J-1030D01*
G03X125665Y51484I-282J283D01*
G02X127606Y51521I951J1030D01*
G37*
G36*
G01X358702Y51293D02*
G03Y50699I268J-297D01*
G02X356822I-940J-1040D01*
G03Y51293I-268J297D01*
G02X358702I940J1040D01*
G37*
G36*
G01X363196Y46006D02*
G03X362587I-305J-258D01*
G02Y47822I-1069J908D01*
G03X363196I305J258D01*
G02Y46006I1069J-908D01*
G37*
G36*
G01X284994Y48488D02*
G03Y47910I277J-289D01*
G02X283054I-970J-1012D01*
G03Y48488I-277J289D01*
G02X283053Y50511I970J1012D01*
G03Y51089I-277J289D01*
G02X283044Y53102I971J1011D01*
G03X283039Y53680I-279J287D01*
G02X284980Y53698I961J1020D01*
G03X284985Y53120I279J-287D01*
G02X284995Y51089I-961J-1020D01*
G03Y50511I277J-289D01*
G02X284994Y48488I-971J-1011D01*
G37*
G36*
G01X248183D02*
G03Y47910I277J-289D01*
G02X246243I-970J-1012D01*
G03Y48488I-277J289D01*
G02X246242Y50511I970J1012D01*
G03Y51089I-277J289D01*
G02X246233Y53102I971J1011D01*
G03X246228Y53680I-279J287D01*
G02X248169Y53698I961J1020D01*
G03X248174Y53120I279J-287D01*
G02X248184Y51089I-961J-1020D01*
G03Y50511I277J-289D01*
G02X248183Y48488I-971J-1011D01*
G37*
G36*
G01X211372D02*
G03Y47910I277J-289D01*
G02X209432I-970J-1012D01*
G03Y48488I-277J289D01*
G02X209431Y50511I970J1012D01*
G03Y51089I-277J289D01*
G02X209422Y53102I971J1011D01*
G03X209417Y53680I-279J287D01*
G02X211358Y53698I961J1020D01*
G03X211363Y53120I279J-287D01*
G02X211373Y51089I-961J-1020D01*
G03Y50511I277J-289D01*
G02X211372Y48488I-971J-1011D01*
G37*
G36*
G01X174561D02*
G03Y47910I277J-289D01*
G02X172621I-970J-1012D01*
G03Y48488I-277J289D01*
G02X172620Y50511I970J1012D01*
G03Y51089I-277J289D01*
G02X172611Y53102I971J1011D01*
G03X172606Y53680I-279J287D01*
G02X174547Y53698I961J1020D01*
G03X174552Y53120I279J-287D01*
G02X174562Y51089I-961J-1020D01*
G03Y50511I277J-289D01*
G02X174561Y48488I-971J-1011D01*
G37*
G36*
G01X137750D02*
G03Y47910I277J-289D01*
G02X135810I-970J-1012D01*
G03Y48488I-277J289D01*
G02X135809Y50511I970J1012D01*
G03Y51089I-277J289D01*
G02X135800Y53102I971J1011D01*
G03X135795Y53680I-279J287D01*
G02X137736Y53698I961J1020D01*
G03X137741Y53120I279J-287D01*
G02X137751Y51089I-961J-1020D01*
G03Y50511I277J-289D01*
G02X137750Y48488I-971J-1011D01*
G37*
G36*
G01X359577Y32318D02*
G03X359571Y31740I273J-292D01*
G02X357634Y31760I-979J-1004D01*
G03X357640Y32338I-273J292D01*
G02X359577Y32318I979J1004D01*
G37*
G36*
G01X285021Y29739D02*
G03Y29161I277J-289D01*
G02X283079I-971J-1011D01*
G03Y29739I-277J289D01*
G02X283089Y31771I971J1011D01*
G03X283084Y32359I-274J292D01*
G02X283053Y34410I940J1040D01*
G03Y34988I-277J289D01*
G02X284995I971J1011D01*
G03Y34410I277J-289D01*
G02X284985Y32378I-971J-1011D01*
G03X284990Y31790I274J-292D01*
G02X285021Y29739I-940J-1040D01*
G37*
G36*
G01X248210D02*
G03Y29161I277J-289D01*
G02X246268I-971J-1011D01*
G03Y29739I-277J289D01*
G02X246278Y31771I971J1011D01*
G03X246273Y32359I-274J292D01*
G02X246242Y34410I940J1040D01*
G03Y34988I-277J289D01*
G02X248184I971J1011D01*
G03Y34410I277J-289D01*
G02X248174Y32378I-971J-1011D01*
G03X248179Y31790I274J-292D01*
G02X248210Y29739I-940J-1040D01*
G37*
G36*
G01X211399D02*
G03Y29161I277J-289D01*
G02X209457I-971J-1011D01*
G03Y29739I-277J289D01*
G02X209467Y31771I971J1011D01*
G03X209462Y32359I-274J292D01*
G02X209431Y34410I940J1040D01*
G03Y34988I-277J289D01*
G02X211373I971J1011D01*
G03Y34410I277J-289D01*
G02X211363Y32378I-971J-1011D01*
G03X211368Y31790I274J-292D01*
G02X211399Y29739I-940J-1040D01*
G37*
G36*
G01X174588D02*
G03Y29161I277J-289D01*
G02X172646I-971J-1011D01*
G03Y29739I-277J289D01*
G02X172656Y31771I971J1011D01*
G03X172651Y32359I-274J292D01*
G02X172620Y34410I940J1040D01*
G03Y34988I-277J289D01*
G02X174562I971J1011D01*
G03Y34410I277J-289D01*
G02X174552Y32378I-971J-1011D01*
G03X174557Y31790I274J-292D01*
G02X174588Y29739I-940J-1040D01*
G37*
G36*
G01X137777D02*
G03Y29161I277J-289D01*
G02X135835I-971J-1011D01*
G03Y29739I-277J289D01*
G02X135845Y31771I971J1011D01*
G03X135840Y32359I-274J292D01*
G02X135809Y34410I940J1040D01*
G03Y34988I-277J289D01*
G02X137751I971J1011D01*
G03Y34410I277J-289D01*
G02X137741Y32378I-971J-1011D01*
G03X137746Y31790I274J-292D01*
G02X137777Y29739I-940J-1040D01*
G37*
G36*
G01X290098Y29532D02*
G03X290101Y28954I278J-288D01*
G02X288163Y28944I-964J-1018D01*
G03X288160Y29522I-278J288D01*
G02X288157Y31555I964J1018D01*
G03Y32134I-276J289D01*
G02X288164Y34171I967J1015D01*
G03X288170Y34748I-274J291D01*
G02X290110Y34728I980J1002D01*
G03X290104Y34151I274J-291D01*
G02X290091Y32134I-980J-1002D01*
G03Y31555I276J-289D01*
G02X290098Y29532I-967J-1015D01*
G37*
G36*
G01X253287D02*
G03X253290Y28954I278J-288D01*
G02X251352Y28944I-964J-1018D01*
G03X251349Y29522I-278J288D01*
G02X251346Y31555I964J1018D01*
G03Y32134I-276J289D01*
G02X251353Y34171I967J1015D01*
G03X251359Y34748I-274J291D01*
G02X253299Y34728I980J1002D01*
G03X253293Y34151I274J-291D01*
G02X253280Y32134I-980J-1002D01*
G03Y31555I276J-289D01*
G02X253287Y29532I-967J-1015D01*
G37*
G36*
G01X216476D02*
G03X216479Y28954I278J-288D01*
G02X214541Y28944I-964J-1018D01*
G03X214538Y29522I-278J288D01*
G02X214535Y31555I964J1018D01*
G03Y32134I-276J289D01*
G02X214542Y34171I967J1015D01*
G03X214548Y34748I-274J291D01*
G02X216488Y34728I980J1002D01*
G03X216482Y34151I274J-291D01*
G02X216469Y32134I-980J-1002D01*
G03Y31555I276J-289D01*
G02X216476Y29532I-967J-1015D01*
G37*
G36*
G01X179665D02*
G03X179668Y28954I278J-288D01*
G02X177730Y28944I-964J-1018D01*
G03X177727Y29522I-278J288D01*
G02X177724Y31555I964J1018D01*
G03Y32134I-276J289D01*
G02X177731Y34171I967J1015D01*
G03X177737Y34748I-274J291D01*
G02X179677Y34728I980J1002D01*
G03X179671Y34151I274J-291D01*
G02X179658Y32134I-980J-1002D01*
G03Y31555I276J-289D01*
G02X179665Y29532I-967J-1015D01*
G37*
G36*
G01X142854D02*
G03X142857Y28954I278J-288D01*
G02X140919Y28944I-964J-1018D01*
G03X140916Y29522I-278J288D01*
G02X140913Y31555I964J1018D01*
G03Y32134I-276J289D01*
G02X140920Y34171I967J1015D01*
G03X140926Y34748I-274J291D01*
G02X142866Y34728I980J1002D01*
G03X142860Y34151I274J-291D01*
G02X142847Y32134I-980J-1002D01*
G03Y31555I276J-289D01*
G02X142854Y29532I-967J-1015D01*
G37*
G36*
G01X373192Y18898D02*
G03X373437Y19395I-136J376D01*
G02X375251Y18501I1336J424D01*
G03X375006Y18004I136J-376D01*
G02X373192Y18898I-1336J-424D01*
G37*
G36*
G01X364291Y16081D02*
G03X363703Y16074I-291J-275D01*
G02X363682Y17975I-1041J939D01*
G03X364270Y17982I291J275D01*
G02X364291Y16081I1041J-939D01*
G37*
G36*
G01X305257Y13764D02*
G03Y13164I265J-300D01*
G02X303399I-929J-1050D01*
G03Y13764I-265J300D01*
G02X305257I929J1050D01*
G37*
G36*
G01X298564D02*
G03Y13164I265J-300D01*
G02X296706I-929J-1050D01*
G03Y13764I-265J300D01*
G02X298564I929J1050D01*
G37*
G36*
G01X281132D02*
G03Y13164I265J-300D01*
G02X279274I-929J-1050D01*
G03Y13764I-265J300D01*
G02X281132I929J1050D01*
G37*
G36*
G01X274850Y13721D02*
G03X274861Y13144I282J-283D01*
G02X272920Y13107I-951J-1030D01*
G03X272909Y13684I-282J283D01*
G02X274850Y13721I951J1030D01*
G37*
G36*
G01X268446Y13764D02*
G03Y13164I265J-300D01*
G02X266588I-929J-1050D01*
G03Y13764I-265J300D01*
G02X268446I929J1050D01*
G37*
G36*
G01X261753D02*
G03Y13164I265J-300D01*
G02X259895I-929J-1050D01*
G03Y13764I-265J300D01*
G02X261753I929J1050D01*
G37*
G36*
G01X244321D02*
G03Y13164I265J-300D01*
G02X242463I-929J-1050D01*
G03Y13764I-265J300D01*
G02X244321I929J1050D01*
G37*
G36*
G01X238039Y13721D02*
G03X238050Y13144I282J-283D01*
G02X236109Y13107I-951J-1030D01*
G03X236098Y13684I-282J283D01*
G02X238039Y13721I951J1030D01*
G37*
G36*
G01X231635Y13764D02*
G03Y13164I265J-300D01*
G02X229777I-929J-1050D01*
G03Y13764I-265J300D01*
G02X231635I929J1050D01*
G37*
G36*
G01X224942D02*
G03Y13164I265J-300D01*
G02X223084I-929J-1050D01*
G03Y13764I-265J300D01*
G02X224942I929J1050D01*
G37*
G36*
G01X207510D02*
G03Y13164I265J-300D01*
G02X205652I-929J-1050D01*
G03Y13764I-265J300D01*
G02X207510I929J1050D01*
G37*
G36*
G01X201228Y13721D02*
G03X201239Y13144I282J-283D01*
G02X199298Y13107I-951J-1030D01*
G03X199287Y13684I-282J283D01*
G02X201228Y13721I951J1030D01*
G37*
G36*
G01X194824Y13764D02*
G03Y13164I265J-300D01*
G02X192966I-929J-1050D01*
G03Y13764I-265J300D01*
G02X194824I929J1050D01*
G37*
G36*
G01X188131D02*
G03Y13164I265J-300D01*
G02X186273I-929J-1050D01*
G03Y13764I-265J300D01*
G02X188131I929J1050D01*
G37*
G36*
G01X170699D02*
G03Y13164I265J-300D01*
G02X168841I-929J-1050D01*
G03Y13764I-265J300D01*
G02X170699I929J1050D01*
G37*
G36*
G01X164417Y13721D02*
G03X164428Y13144I282J-283D01*
G02X162487Y13107I-951J-1030D01*
G03X162476Y13684I-282J283D01*
G02X164417Y13721I951J1030D01*
G37*
G36*
G01X158013Y13764D02*
G03Y13164I265J-300D01*
G02X156155I-929J-1050D01*
G03Y13764I-265J300D01*
G02X158013I929J1050D01*
G37*
G36*
G01X151320D02*
G03Y13164I265J-300D01*
G02X149462I-929J-1050D01*
G03Y13764I-265J300D01*
G02X151320I929J1050D01*
G37*
G36*
G01X133888D02*
G03Y13164I265J-300D01*
G02X132030I-929J-1050D01*
G03Y13764I-265J300D01*
G02X133888I929J1050D01*
G37*
G36*
G01X127606Y13721D02*
G03X127617Y13144I282J-283D01*
G02X125676Y13107I-951J-1030D01*
G03X125665Y13684I-282J283D01*
G02X127606Y13721I951J1030D01*
G37*
G36*
G01X358463Y13303D02*
G03Y12725I277J-289D01*
G02X356521I-971J-1011D01*
G03Y13303I-277J289D01*
G02X358463I971J1011D01*
G37*
G36*
G01X284994Y10688D02*
G03Y10110I277J-289D01*
G02X283054I-970J-1012D01*
G03Y10688I-277J289D01*
G02X283053Y12711I970J1012D01*
G03Y13289I-277J289D01*
G02X283044Y15302I971J1011D01*
G03X283039Y15880I-279J287D01*
G02X284980Y15898I961J1020D01*
G03X284985Y15320I279J-287D01*
G02X284995Y13289I-961J-1020D01*
G03Y12711I277J-289D01*
G02X284994Y10688I-971J-1011D01*
G37*
G36*
G01X248183D02*
G03Y10110I277J-289D01*
G02X246243I-970J-1012D01*
G03Y10688I-277J289D01*
G02X246242Y12711I970J1012D01*
G03Y13289I-277J289D01*
G02X246233Y15302I971J1011D01*
G03X246228Y15880I-279J287D01*
G02X248169Y15898I961J1020D01*
G03X248174Y15320I279J-287D01*
G02X248184Y13289I-961J-1020D01*
G03Y12711I277J-289D01*
G02X248183Y10688I-971J-1011D01*
G37*
G36*
G01X211372D02*
G03Y10110I277J-289D01*
G02X209432I-970J-1012D01*
G03Y10688I-277J289D01*
G02X209431Y12711I970J1012D01*
G03Y13289I-277J289D01*
G02X209422Y15302I971J1011D01*
G03X209417Y15880I-279J287D01*
G02X211358Y15898I961J1020D01*
G03X211363Y15320I279J-287D01*
G02X211373Y13289I-961J-1020D01*
G03Y12711I277J-289D01*
G02X211372Y10688I-971J-1011D01*
G37*
G36*
G01X174561D02*
G03Y10110I277J-289D01*
G02X172621I-970J-1012D01*
G03Y10688I-277J289D01*
G02X172620Y12711I970J1012D01*
G03Y13289I-277J289D01*
G02X172611Y15302I971J1011D01*
G03X172606Y15880I-279J287D01*
G02X174547Y15898I961J1020D01*
G03X174552Y15320I279J-287D01*
G02X174562Y13289I-961J-1020D01*
G03Y12711I277J-289D01*
G02X174561Y10688I-971J-1011D01*
G37*
G36*
G01X137750D02*
G03Y10110I277J-289D01*
G02X135810I-970J-1012D01*
G03Y10688I-277J289D01*
G02X135809Y12711I970J1012D01*
G03Y13289I-277J289D01*
G02X135800Y15302I971J1011D01*
G03X135795Y15880I-279J287D01*
G02X137736Y15898I961J1020D01*
G03X137741Y15320I279J-287D01*
G02X137751Y13289I-961J-1020D01*
G03Y12711I277J-289D01*
G02X137750Y10688I-971J-1011D01*
G37*
G36*
G01X115022Y5064D02*
G03X115000Y4483I263J-301D01*
G02X113078Y4556I-1000J-983D01*
G03X113100Y5137I-263J301D01*
G02X115022Y5064I1000J983D01*
G37*
G36*
G01X285021Y-8061D02*
G03Y-8639I277J-289D01*
G02X283079I-971J-1011D01*
G03Y-8061I-277J289D01*
G02X283089Y-6029I971J1011D01*
G03X283084Y-5441I-274J292D01*
G02X283053Y-3390I940J1040D01*
G03Y-2812I-277J289D01*
G02X284995I971J1011D01*
G03Y-3390I277J-289D01*
G02X284985Y-5422I-971J-1011D01*
G03X284990Y-6010I274J-292D01*
G02X285021Y-8061I-940J-1040D01*
G37*
G36*
G01X248210D02*
G03Y-8639I277J-289D01*
G02X246268I-971J-1011D01*
G03Y-8061I-277J289D01*
G02X246278Y-6029I971J1011D01*
G03X246273Y-5441I-274J292D01*
G02X246242Y-3390I940J1040D01*
G03Y-2812I-277J289D01*
G02X248184I971J1011D01*
G03Y-3390I277J-289D01*
G02X248174Y-5422I-971J-1011D01*
G03X248179Y-6010I274J-292D01*
G02X248210Y-8061I-940J-1040D01*
G37*
G36*
G01X211399D02*
G03Y-8639I277J-289D01*
G02X209457I-971J-1011D01*
G03Y-8061I-277J289D01*
G02X209467Y-6029I971J1011D01*
G03X209462Y-5441I-274J292D01*
G02X209431Y-3390I940J1040D01*
G03Y-2812I-277J289D01*
G02X211373I971J1011D01*
G03Y-3390I277J-289D01*
G02X211363Y-5422I-971J-1011D01*
G03X211368Y-6010I274J-292D01*
G02X211399Y-8061I-940J-1040D01*
G37*
G36*
G01X174588D02*
G03Y-8639I277J-289D01*
G02X172646I-971J-1011D01*
G03Y-8061I-277J289D01*
G02X172656Y-6029I971J1011D01*
G03X172651Y-5441I-274J292D01*
G02X172620Y-3390I940J1040D01*
G03Y-2812I-277J289D01*
G02X174562I971J1011D01*
G03Y-3390I277J-289D01*
G02X174552Y-5422I-971J-1011D01*
G03X174557Y-6010I274J-292D01*
G02X174588Y-8061I-940J-1040D01*
G37*
G36*
G01X137777D02*
G03Y-8639I277J-289D01*
G02X135835I-971J-1011D01*
G03Y-8061I-277J289D01*
G02X135845Y-6029I971J1011D01*
G03X135840Y-5441I-274J292D01*
G02X135809Y-3390I940J1040D01*
G03Y-2812I-277J289D01*
G02X137751I971J1011D01*
G03Y-3390I277J-289D01*
G02X137741Y-5422I-971J-1011D01*
G03X137746Y-6010I274J-292D01*
G02X137777Y-8061I-940J-1040D01*
G37*
G36*
G01X290098Y-8268D02*
G03X290101Y-8846I278J-288D01*
G02X288163Y-8856I-964J-1018D01*
G03X288160Y-8278I-278J288D01*
G02X288157Y-6245I964J1018D01*
G03Y-5666I-276J290D01*
G02X288164Y-3629I967J1015D01*
G03X288170Y-3052I-274J291D01*
G02X290110Y-3072I980J1002D01*
G03X290104Y-3649I274J-291D01*
G02X290091Y-5666I-980J-1002D01*
G03Y-6245I276J-290D01*
G02X290098Y-8268I-967J-1015D01*
G37*
G36*
G01X253287D02*
G03X253290Y-8846I278J-288D01*
G02X251352Y-8856I-964J-1018D01*
G03X251349Y-8278I-278J288D01*
G02X251346Y-6245I964J1018D01*
G03Y-5666I-276J290D01*
G02X251353Y-3629I967J1015D01*
G03X251359Y-3052I-274J291D01*
G02X253299Y-3072I980J1002D01*
G03X253293Y-3649I274J-291D01*
G02X253280Y-5666I-980J-1002D01*
G03Y-6245I276J-290D01*
G02X253287Y-8268I-967J-1015D01*
G37*
G36*
G01X216476D02*
G03X216479Y-8846I278J-288D01*
G02X214541Y-8856I-964J-1018D01*
G03X214538Y-8278I-278J288D01*
G02X214535Y-6245I964J1018D01*
G03Y-5666I-276J290D01*
G02X214542Y-3629I967J1015D01*
G03X214548Y-3052I-274J291D01*
G02X216488Y-3072I980J1002D01*
G03X216482Y-3649I274J-291D01*
G02X216469Y-5666I-980J-1002D01*
G03Y-6245I276J-290D01*
G02X216476Y-8268I-967J-1015D01*
G37*
G36*
G01X179665D02*
G03X179668Y-8846I278J-288D01*
G02X177730Y-8856I-964J-1018D01*
G03X177727Y-8278I-278J288D01*
G02X177724Y-6245I964J1018D01*
G03Y-5666I-276J290D01*
G02X177731Y-3629I967J1015D01*
G03X177737Y-3052I-274J291D01*
G02X179677Y-3072I980J1002D01*
G03X179671Y-3649I274J-291D01*
G02X179658Y-5666I-980J-1002D01*
G03Y-6245I276J-290D01*
G02X179665Y-8268I-967J-1015D01*
G37*
G36*
G01X142854D02*
G03X142857Y-8846I278J-288D01*
G02X140919Y-8856I-964J-1018D01*
G03X140916Y-8278I-278J288D01*
G02X140913Y-6245I964J1018D01*
G03Y-5666I-276J290D01*
G02X140920Y-3629I967J1015D01*
G03X140926Y-3052I-274J291D01*
G02X142866Y-3072I980J1002D01*
G03X142860Y-3649I274J-291D01*
G02X142847Y-5666I-980J-1002D01*
G03Y-6245I276J-290D01*
G02X142854Y-8268I-967J-1015D01*
G37*
G36*
G01X363887Y91625D02*
G02Y93375I-1095J875D01*
G03X364512I313J250D01*
G02Y91625I1095J-875D01*
G03X363887I-312J-250D01*
G37*
G36*
G01X96484Y77755D02*
G02X93632Y77689I-1443J696D01*
G03X92932Y77695I-352J-191D01*
G02X92945Y79243I-1396J786D01*
G03X93645Y79237I352J191D01*
G02X96472Y79171I1396J-786D01*
G03X97190Y79177I358J179D01*
G02X97202Y77761I1443J-696D01*
G03X96484Y77755I-358J-179D01*
G37*
G36*
G01X375007Y75306D02*
G02X373577I-715J-1206D01*
G03Y75994I-204J344D01*
G02X375007I715J1206D01*
G03Y75306I204J-344D01*
G37*
G36*
G01X381727Y61396D02*
G02X380164Y61350I-747J-1186D01*
G03X380145Y62014I-233J326D01*
G02X381708Y62060I747J1186D01*
G03X381727Y61396I233J-326D01*
G37*
G36*
G01X289985Y47987D02*
G02X288233Y48002I-885J-1087D01*
G03X288239Y48627I-247J315D01*
G02X288153Y50725I885J1087D01*
G03Y51303I-277J289D01*
G02Y53325I971J1011D01*
G03Y53903I-277J289D01*
G02X290095I971J1011D01*
G03Y53325I277J-289D01*
G02Y51303I-971J-1011D01*
G03Y50725I277J-289D01*
G02X289991Y48612I-971J-1011D01*
G03X289985Y47987I247J-315D01*
G37*
G36*
G01X253174D02*
G02X251422Y48002I-885J-1087D01*
G03X251428Y48627I-247J315D01*
G02X251342Y50725I885J1087D01*
G03Y51303I-277J289D01*
G02Y53325I971J1011D01*
G03Y53903I-277J289D01*
G02X253284I971J1011D01*
G03Y53325I277J-289D01*
G02Y51303I-971J-1011D01*
G03Y50725I277J-289D01*
G02X253180Y48612I-971J-1011D01*
G03X253174Y47987I247J-315D01*
G37*
G36*
G01X216363D02*
G02X214611Y48002I-885J-1087D01*
G03X214617Y48627I-247J315D01*
G02X214531Y50725I885J1087D01*
G03Y51303I-277J289D01*
G02Y53325I971J1011D01*
G03Y53903I-277J289D01*
G02X216473I971J1011D01*
G03Y53325I277J-289D01*
G02Y51303I-971J-1011D01*
G03Y50725I277J-289D01*
G02X216369Y48612I-971J-1011D01*
G03X216363Y47987I247J-315D01*
G37*
G36*
G01X179552D02*
G02X177800Y48002I-885J-1087D01*
G03X177806Y48627I-247J315D01*
G02X177720Y50725I885J1087D01*
G03Y51303I-277J289D01*
G02Y53325I971J1011D01*
G03Y53903I-277J289D01*
G02X179662I971J1011D01*
G03Y53325I277J-289D01*
G02Y51303I-971J-1011D01*
G03Y50725I277J-289D01*
G02X179558Y48612I-971J-1011D01*
G03X179552Y47987I247J-315D01*
G37*
G36*
G01X142741D02*
G02X140989Y48002I-885J-1087D01*
G03X140995Y48627I-247J315D01*
G02X140909Y50725I885J1087D01*
G03Y51303I-277J289D01*
G02Y53325I971J1011D01*
G03Y53903I-277J289D01*
G02X142851I971J1011D01*
G03Y53325I277J-289D01*
G02Y51303I-971J-1011D01*
G03Y50725I277J-289D01*
G02X142747Y48612I-971J-1011D01*
G03X142741Y47987I247J-315D01*
G37*
G36*
G01X381635Y26053D02*
G02X379949I-843J-1120D01*
G03Y26692I-241J320D01*
G02X381635I843J1120D01*
G03Y26053I241J-320D01*
G37*
G36*
G01X289985Y10187D02*
G02X288233Y10202I-885J-1087D01*
G03X288239Y10827I-247J315D01*
G02X288153Y12925I885J1087D01*
G03Y13503I-277J289D01*
G02Y15525I971J1011D01*
G03Y16103I-277J289D01*
G02X290095I971J1011D01*
G03Y15525I277J-289D01*
G02Y13503I-971J-1011D01*
G03Y12925I277J-289D01*
G02X289991Y10812I-971J-1011D01*
G03X289985Y10187I247J-315D01*
G37*
G36*
G01X253174D02*
G02X251422Y10202I-885J-1087D01*
G03X251428Y10827I-247J315D01*
G02X251342Y12925I885J1087D01*
G03Y13503I-277J289D01*
G02Y15525I971J1011D01*
G03Y16103I-277J289D01*
G02X253284I971J1011D01*
G03Y15525I277J-289D01*
G02Y13503I-971J-1011D01*
G03Y12925I277J-289D01*
G02X253180Y10812I-971J-1011D01*
G03X253174Y10187I247J-315D01*
G37*
G36*
G01X216363D02*
G02X214611Y10202I-885J-1087D01*
G03X214617Y10827I-247J315D01*
G02X214531Y12925I885J1087D01*
G03Y13503I-277J289D01*
G02Y15525I971J1011D01*
G03Y16103I-277J289D01*
G02X216473I971J1011D01*
G03Y15525I277J-289D01*
G02Y13503I-971J-1011D01*
G03Y12925I277J-289D01*
G02X216369Y10812I-971J-1011D01*
G03X216363Y10187I247J-315D01*
G37*
G36*
G01X179552D02*
G02X177800Y10202I-885J-1087D01*
G03X177806Y10827I-247J315D01*
G02X177720Y12925I885J1087D01*
G03Y13503I-277J289D01*
G02Y15525I971J1011D01*
G03Y16103I-277J289D01*
G02X179662I971J1011D01*
G03Y15525I277J-289D01*
G02Y13503I-971J-1011D01*
G03Y12925I277J-289D01*
G02X179558Y10812I-971J-1011D01*
G03X179552Y10187I247J-315D01*
G37*
G36*
G01X142741D02*
G02X140989Y10202I-885J-1087D01*
G03X140995Y10827I-247J315D01*
G02X140909Y12925I885J1087D01*
G03Y13503I-277J289D01*
G02Y15525I971J1011D01*
G03Y16103I-277J289D01*
G02X142851I971J1011D01*
G03Y15525I277J-289D01*
G02Y13503I-971J-1011D01*
G03Y12925I277J-289D01*
G02X142747Y10812I-971J-1011D01*
G03X142741Y10187I247J-315D01*
G37*
G36*
G01X376959Y5723D02*
G02Y7277I-1167J777D01*
G03X377625I333J222D01*
G02Y5723I1167J-777D01*
G03X376959I-333J-222D01*
G37*
G36*
G01X58175Y255329D02*
G02X56785Y255306I-675J-1229D01*
G03X56753Y256011I-204J344D01*
G02X58183Y256034I692J1445D01*
G03X58175Y255329I184J-355D01*
G37*
G36*
G01X116085Y591769D02*
G03X116070Y592390I-259J304D01*
G02X117834Y592431I857J1110D01*
G03X117849Y591810I259J-304D01*
G02X116085Y591769I-857J-1110D01*
G37*
G36*
G01X305226Y590381D02*
G03X305237Y589782I270J-295D01*
G02X303380Y589747I-909J-1068D01*
G03X303369Y590346I-270J295D01*
G02X305226Y590381I909J1068D01*
G37*
G36*
G01X298564Y590364D02*
G03Y589764I265J-300D01*
G02X296706I-929J-1050D01*
G03Y590364I-265J300D01*
G02X298564I929J1050D01*
G37*
G36*
G01X281132D02*
G03Y589764I265J-300D01*
G02X279274I-929J-1050D01*
G03Y590364I-265J300D01*
G02X281132I929J1050D01*
G37*
G36*
G01X274850Y590321D02*
G03X274861Y589744I282J-283D01*
G02X272920Y589707I-951J-1030D01*
G03X272909Y590284I-282J283D01*
G02X274850Y590321I951J1030D01*
G37*
G36*
G01X268446Y590364D02*
G03Y589764I265J-300D01*
G02X266588I-929J-1050D01*
G03Y590364I-265J300D01*
G02X268446I929J1050D01*
G37*
G36*
G01X261753D02*
G03Y589764I265J-300D01*
G02X259895I-929J-1050D01*
G03Y590364I-265J300D01*
G02X261753I929J1050D01*
G37*
G36*
G01X244321D02*
G03Y589764I265J-300D01*
G02X242463I-929J-1050D01*
G03Y590364I-265J300D01*
G02X244321I929J1050D01*
G37*
G36*
G01X238039Y590321D02*
G03X238050Y589744I282J-283D01*
G02X236109Y589707I-951J-1030D01*
G03X236098Y590284I-282J283D01*
G02X238039Y590321I951J1030D01*
G37*
G36*
G01X231635Y590364D02*
G03Y589764I265J-300D01*
G02X229777I-929J-1050D01*
G03Y590364I-265J300D01*
G02X231635I929J1050D01*
G37*
G36*
G01X224942D02*
G03Y589764I265J-300D01*
G02X223084I-929J-1050D01*
G03Y590364I-265J300D01*
G02X224942I929J1050D01*
G37*
G36*
G01X207510D02*
G03Y589764I265J-300D01*
G02X205652I-929J-1050D01*
G03Y590364I-265J300D01*
G02X207510I929J1050D01*
G37*
G36*
G01X201228Y590321D02*
G03X201239Y589744I282J-283D01*
G02X199298Y589707I-951J-1030D01*
G03X199287Y590284I-282J283D01*
G02X201228Y590321I951J1030D01*
G37*
G36*
G01X194824Y590364D02*
G03Y589764I265J-300D01*
G02X192966I-929J-1050D01*
G03Y590364I-265J300D01*
G02X194824I929J1050D01*
G37*
G36*
G01X188131D02*
G03Y589764I265J-300D01*
G02X186273I-929J-1050D01*
G03Y590364I-265J300D01*
G02X188131I929J1050D01*
G37*
G36*
G01X170720Y590333D02*
G03Y589745I271J-294D01*
G02X168820I-950J-1031D01*
G03Y590333I-271J294D01*
G02X170720I950J1031D01*
G37*
G36*
G01X164417Y590321D02*
G03X164428Y589744I282J-283D01*
G02X162487Y589707I-951J-1030D01*
G03X162476Y590284I-282J283D01*
G02X164417Y590321I951J1030D01*
G37*
G36*
G01X158013Y590364D02*
G03Y589764I265J-300D01*
G02X156155I-929J-1050D01*
G03Y590364I-265J300D01*
G02X158013I929J1050D01*
G37*
G36*
G01X151320D02*
G03Y589764I265J-300D01*
G02X149462I-929J-1050D01*
G03Y590364I-265J300D01*
G02X151320I929J1050D01*
G37*
G36*
G01X133888D02*
G03Y589764I265J-300D01*
G02X132030I-929J-1050D01*
G03Y590364I-265J300D01*
G02X133888I929J1050D01*
G37*
G36*
G01X127606Y590321D02*
G03X127617Y589744I282J-283D01*
G02X125676Y589707I-951J-1030D01*
G03X125665Y590284I-282J283D01*
G02X127606Y590321I951J1030D01*
G37*
G36*
G01X357780Y589938D02*
G03Y589367I280J-286D01*
G02X355816I-982J-1001D01*
G03Y589938I-280J285D01*
G02X357780I982J1001D01*
G37*
G36*
G01X308818Y589947D02*
G03X308808Y589356I264J-300D01*
G02X306922Y589387I-960J-1022D01*
G03X306932Y589978I-264J300D01*
G02X306867Y591957I960J1022D01*
G03X306819Y592547I-292J273D01*
G02X308700Y592700I856J1110D01*
G03X308748Y592110I292J-273D01*
G02X308818Y589947I-856J-1110D01*
G37*
G36*
G01X363196Y584806D02*
G03X362587I-305J-258D01*
G02Y586622I-1069J908D01*
G03X363196I305J258D01*
G02Y584806I1069J-908D01*
G37*
G36*
G01X283053Y589311D02*
G03Y589889I-277J289D01*
G02X283044Y591902I971J1011D01*
G03X283039Y592480I-279J287D01*
G02X284980Y592498I961J1020D01*
G03X284985Y591920I279J-287D01*
G02X284995Y589889I-961J-1020D01*
G03Y589311I277J-289D01*
G02X284994Y587288I-971J-1011D01*
G03Y586710I277J-289D01*
G02X283054I-970J-1012D01*
G03Y587288I-277J289D01*
G02X283053Y589311I970J1012D01*
G37*
G36*
G01X246242D02*
G03Y589889I-277J289D01*
G02X246233Y591902I971J1011D01*
G03X246228Y592480I-279J287D01*
G02X248169Y592498I961J1020D01*
G03X248174Y591920I279J-287D01*
G02X248184Y589889I-961J-1020D01*
G03Y589311I277J-289D01*
G02X248183Y587288I-971J-1011D01*
G03Y586710I277J-289D01*
G02X246243I-970J-1012D01*
G03Y587288I-277J289D01*
G02X246242Y589311I970J1012D01*
G37*
G36*
G01X209431D02*
G03Y589889I-277J289D01*
G02X209422Y591902I971J1011D01*
G03X209417Y592480I-279J287D01*
G02X211358Y592498I961J1020D01*
G03X211363Y591920I279J-287D01*
G02X211373Y589889I-961J-1020D01*
G03Y589311I277J-289D01*
G02X211372Y587288I-971J-1011D01*
G03Y586710I277J-289D01*
G02X209432I-970J-1012D01*
G03Y587288I-277J289D01*
G02X209431Y589311I970J1012D01*
G37*
G36*
G01X172620D02*
G03Y589889I-277J289D01*
G02X172611Y591902I971J1011D01*
G03X172606Y592480I-279J287D01*
G02X174547Y592498I961J1020D01*
G03X174552Y591920I279J-287D01*
G02X174562Y589889I-961J-1020D01*
G03Y589311I277J-289D01*
G02X174561Y587288I-971J-1011D01*
G03Y586710I277J-289D01*
G02X172621I-970J-1012D01*
G03Y587288I-277J289D01*
G02X172620Y589311I970J1012D01*
G37*
G36*
G01X135809D02*
G03Y589889I-277J289D01*
G02X135800Y591902I971J1011D01*
G03X135795Y592480I-279J287D01*
G02X137736Y592498I961J1020D01*
G03X137741Y591920I279J-287D01*
G02X137751Y589889I-961J-1020D01*
G03Y589311I277J-289D01*
G02X137750Y587288I-971J-1011D01*
G03Y586710I277J-289D01*
G02X135810I-970J-1012D01*
G03Y587288I-277J289D01*
G02X135809Y589311I970J1012D01*
G37*
G36*
G01X358734Y571001D02*
G03Y570446I288J-278D01*
G02X356714I-1010J-972D01*
G03Y571001I-288J277D01*
G02X358734I1010J972D01*
G37*
G36*
G01X283079Y567961D02*
G03Y568539I-277J289D01*
G02X283089Y570571I971J1011D01*
G03X283084Y571159I-274J292D01*
G02X283053Y573210I940J1040D01*
G03Y573788I-277J289D01*
G02X284995I971J1011D01*
G03Y573210I277J-289D01*
G02X284985Y571178I-971J-1011D01*
G03X284990Y570590I274J-292D01*
G02X285021Y568539I-940J-1040D01*
G03Y567961I277J-289D01*
G02X283079I-971J-1011D01*
G37*
G36*
G01X246268D02*
G03Y568539I-277J289D01*
G02X246278Y570571I971J1011D01*
G03X246273Y571159I-274J292D01*
G02X246242Y573210I940J1040D01*
G03Y573788I-277J289D01*
G02X248184I971J1011D01*
G03Y573210I277J-289D01*
G02X248174Y571178I-971J-1011D01*
G03X248179Y570590I274J-292D01*
G02X248210Y568539I-940J-1040D01*
G03Y567961I277J-289D01*
G02X246268I-971J-1011D01*
G37*
G36*
G01X209457D02*
G03Y568539I-277J289D01*
G02X209467Y570571I971J1011D01*
G03X209462Y571159I-274J292D01*
G02X209431Y573210I940J1040D01*
G03Y573788I-277J289D01*
G02X211373I971J1011D01*
G03Y573210I277J-289D01*
G02X211363Y571178I-971J-1011D01*
G03X211368Y570590I274J-292D01*
G02X211399Y568539I-940J-1040D01*
G03Y567961I277J-289D01*
G02X209457I-971J-1011D01*
G37*
G36*
G01X172646D02*
G03Y568539I-277J289D01*
G02X172656Y570571I971J1011D01*
G03X172651Y571159I-274J292D01*
G02X172620Y573210I940J1040D01*
G03Y573788I-277J289D01*
G02X174562I971J1011D01*
G03Y573210I277J-289D01*
G02X174552Y571178I-971J-1011D01*
G03X174557Y570590I274J-292D01*
G02X174588Y568539I-940J-1040D01*
G03Y567961I277J-289D01*
G02X172646I-971J-1011D01*
G37*
G36*
G01X135845Y570571D02*
G03X135840Y571159I-274J292D01*
G02X135809Y573210I940J1040D01*
G03Y573788I-277J289D01*
G02X137751I971J1011D01*
G03Y573210I277J-289D01*
G02X137741Y571178I-971J-1011D01*
G03X137746Y570590I274J-292D01*
G02X137777Y568539I-940J-1040D01*
G03Y567961I277J-289D01*
G02X135835I-971J-1011D01*
G03Y568539I-277J289D01*
G02X135845Y570571I971J1011D01*
G37*
G36*
G01X288157Y570355D02*
G03Y570934I-276J289D01*
G02X288164Y572971I967J1015D01*
G03X288170Y573548I-274J291D01*
G02X290110Y573528I980J1002D01*
G03X290104Y572951I274J-291D01*
G02X290091Y570934I-980J-1002D01*
G03Y570355I276J-290D01*
G02X290098Y568332I-967J-1015D01*
G03X290101Y567754I278J-288D01*
G02X288163Y567744I-964J-1018D01*
G03X288160Y568322I-278J288D01*
G02X288157Y570355I964J1018D01*
G37*
G36*
G01X251346D02*
G03Y570934I-276J289D01*
G02X251353Y572971I967J1015D01*
G03X251359Y573548I-274J291D01*
G02X253299Y573528I980J1002D01*
G03X253293Y572951I274J-291D01*
G02X253280Y570934I-980J-1002D01*
G03Y570355I276J-290D01*
G02X253287Y568332I-967J-1015D01*
G03X253290Y567754I278J-288D01*
G02X251352Y567744I-964J-1018D01*
G03X251349Y568322I-278J288D01*
G02X251346Y570355I964J1018D01*
G37*
G36*
G01X214535D02*
G03Y570934I-276J289D01*
G02X214542Y572971I967J1015D01*
G03X214548Y573548I-274J291D01*
G02X216488Y573528I980J1002D01*
G03X216482Y572951I274J-291D01*
G02X216469Y570934I-980J-1002D01*
G03Y570355I276J-290D01*
G02X216476Y568332I-967J-1015D01*
G03X216479Y567754I278J-288D01*
G02X214541Y567744I-964J-1018D01*
G03X214538Y568322I-278J288D01*
G02X214535Y570355I964J1018D01*
G37*
G36*
G01X177724D02*
G03Y570934I-276J289D01*
G02X177731Y572971I967J1015D01*
G03X177737Y573548I-274J291D01*
G02X179677Y573528I980J1002D01*
G03X179671Y572951I274J-291D01*
G02X179658Y570934I-980J-1002D01*
G03Y570355I276J-290D01*
G02X179665Y568332I-967J-1015D01*
G03X179668Y567754I278J-288D01*
G02X177730Y567744I-964J-1018D01*
G03X177727Y568322I-278J288D01*
G02X177724Y570355I964J1018D01*
G37*
G36*
G01X140913D02*
G03Y570934I-276J289D01*
G02X140920Y572971I967J1015D01*
G03X140926Y573548I-274J291D01*
G02X142866Y573528I980J1002D01*
G03X142860Y572951I274J-291D01*
G02X142847Y570934I-980J-1002D01*
G03Y570355I276J-290D01*
G02X142854Y568332I-967J-1015D01*
G03X142857Y567754I278J-288D01*
G02X140919Y567744I-964J-1018D01*
G03X140916Y568322I-278J288D01*
G02X140913Y570355I964J1018D01*
G37*
G36*
G01X305226Y552581D02*
G03X305237Y551982I270J-295D01*
G02X303380Y551947I-909J-1068D01*
G03X303369Y552546I-270J295D01*
G02X305226Y552581I909J1068D01*
G37*
G36*
G01X298564Y552564D02*
G03Y551964I265J-300D01*
G02X296706I-929J-1050D01*
G03Y552564I-265J300D01*
G02X298564I929J1050D01*
G37*
G36*
G01X281132D02*
G03Y551964I265J-300D01*
G02X279274I-929J-1050D01*
G03Y552564I-265J300D01*
G02X281132I929J1050D01*
G37*
G36*
G01X274850Y552521D02*
G03X274861Y551944I282J-283D01*
G02X272920Y551907I-951J-1030D01*
G03X272909Y552484I-282J283D01*
G02X274850Y552521I951J1030D01*
G37*
G36*
G01X268446Y552564D02*
G03Y551964I265J-300D01*
G02X266588I-929J-1050D01*
G03Y552564I-265J300D01*
G02X268446I929J1050D01*
G37*
G36*
G01X261753D02*
G03Y551964I265J-300D01*
G02X259895I-929J-1050D01*
G03Y552564I-265J300D01*
G02X261753I929J1050D01*
G37*
G36*
G01X244321D02*
G03Y551964I265J-300D01*
G02X242463I-929J-1050D01*
G03Y552564I-265J300D01*
G02X244321I929J1050D01*
G37*
G36*
G01X238039Y552521D02*
G03X238050Y551944I282J-283D01*
G02X236109Y551907I-951J-1030D01*
G03X236098Y552484I-282J283D01*
G02X238039Y552521I951J1030D01*
G37*
G36*
G01X231635Y552564D02*
G03Y551964I265J-300D01*
G02X229777I-929J-1050D01*
G03Y552564I-265J300D01*
G02X231635I929J1050D01*
G37*
G36*
G01X224942D02*
G03Y551964I265J-300D01*
G02X223084I-929J-1050D01*
G03Y552564I-265J300D01*
G02X224942I929J1050D01*
G37*
G36*
G01X207510D02*
G03Y551964I265J-300D01*
G02X205652I-929J-1050D01*
G03Y552564I-265J300D01*
G02X207510I929J1050D01*
G37*
G36*
G01X201228Y552521D02*
G03X201239Y551944I282J-283D01*
G02X199298Y551907I-951J-1030D01*
G03X199287Y552484I-282J283D01*
G02X201228Y552521I951J1030D01*
G37*
G36*
G01X194824Y552564D02*
G03Y551964I265J-300D01*
G02X192966I-929J-1050D01*
G03Y552564I-265J300D01*
G02X194824I929J1050D01*
G37*
G36*
G01X188131D02*
G03Y551964I265J-300D01*
G02X186273I-929J-1050D01*
G03Y552564I-265J300D01*
G02X188131I929J1050D01*
G37*
G36*
G01X170720Y552533D02*
G03Y551945I271J-294D01*
G02X168820I-950J-1031D01*
G03Y552533I-271J294D01*
G02X170720I950J1031D01*
G37*
G36*
G01X164417Y552521D02*
G03X164428Y551944I282J-283D01*
G02X162487Y551907I-951J-1030D01*
G03X162476Y552484I-282J283D01*
G02X164417Y552521I951J1030D01*
G37*
G36*
G01X158013Y552564D02*
G03Y551964I265J-300D01*
G02X156155I-929J-1050D01*
G03Y552564I-265J300D01*
G02X158013I929J1050D01*
G37*
G36*
G01X151320D02*
G03Y551964I265J-300D01*
G02X149462I-929J-1050D01*
G03Y552564I-265J300D01*
G02X151320I929J1050D01*
G37*
G36*
G01X133888D02*
G03Y551964I265J-300D01*
G02X132030I-929J-1050D01*
G03Y552564I-265J300D01*
G02X133888I929J1050D01*
G37*
G36*
G01X125676Y551907D02*
G03X125665Y552484I-282J283D01*
G02X127606Y552521I951J1030D01*
G03X127617Y551944I282J-283D01*
G02X125676Y551907I-951J-1030D01*
G37*
G36*
G01X358510Y552100D02*
G03Y551522I277J-289D01*
G02X356568I-971J-1011D01*
G03Y552100I-277J289D01*
G02X358510I971J1011D01*
G37*
G36*
G01X363196Y547006D02*
G03X362587I-305J-258D01*
G02Y548822I-1069J908D01*
G03X363196I305J258D01*
G02Y547006I1069J-908D01*
G37*
G36*
G01X283053Y551511D02*
G03Y552089I-277J289D01*
G02X283044Y554102I971J1011D01*
G03X283039Y554680I-279J287D01*
G02X284980Y554698I961J1020D01*
G03X284985Y554120I279J-287D01*
G02X284995Y552089I-961J-1020D01*
G03Y551511I277J-289D01*
G02X284994Y549488I-971J-1011D01*
G03Y548910I277J-289D01*
G02X283054I-970J-1012D01*
G03Y549488I-277J289D01*
G02X283053Y551511I970J1012D01*
G37*
G36*
G01X246242D02*
G03Y552089I-277J289D01*
G02X246233Y554102I971J1011D01*
G03X246228Y554680I-279J287D01*
G02X248169Y554698I961J1020D01*
G03X248174Y554120I279J-287D01*
G02X248184Y552089I-961J-1020D01*
G03Y551511I277J-289D01*
G02X248183Y549488I-971J-1011D01*
G03Y548910I277J-289D01*
G02X246243I-970J-1012D01*
G03Y549488I-277J289D01*
G02X246242Y551511I970J1012D01*
G37*
G36*
G01X209431D02*
G03Y552089I-277J289D01*
G02X209422Y554102I971J1011D01*
G03X209417Y554680I-279J287D01*
G02X211358Y554698I961J1020D01*
G03X211363Y554120I279J-287D01*
G02X211373Y552089I-961J-1020D01*
G03Y551511I277J-289D01*
G02X211372Y549488I-971J-1011D01*
G03Y548910I277J-289D01*
G02X209432I-970J-1012D01*
G03Y549488I-277J289D01*
G02X209431Y551511I970J1012D01*
G37*
G36*
G01X172620D02*
G03Y552089I-277J289D01*
G02X172611Y554102I971J1011D01*
G03X172606Y554680I-279J287D01*
G02X174547Y554698I961J1020D01*
G03X174552Y554120I279J-287D01*
G02X174562Y552089I-961J-1020D01*
G03Y551511I277J-289D01*
G02X174561Y549488I-971J-1011D01*
G03Y548910I277J-289D01*
G02X172621I-970J-1012D01*
G03Y549488I-277J289D01*
G02X172620Y551511I970J1012D01*
G37*
G36*
G01X135809D02*
G03Y552089I-277J289D01*
G02X135800Y554102I971J1011D01*
G03X135795Y554680I-279J287D01*
G02X137736Y554698I961J1020D01*
G03X137741Y554120I279J-287D01*
G02X137751Y552089I-961J-1020D01*
G03Y551511I277J-289D01*
G02X137750Y549488I-971J-1011D01*
G03Y548910I277J-289D01*
G02X135810I-970J-1012D01*
G03Y549488I-277J289D01*
G02X135809Y551511I970J1012D01*
G37*
G36*
G01X375837Y544726D02*
G03X375845Y545304I-272J293D01*
G02X377784Y545277I984J999D01*
G03X377776Y544699I272J-293D01*
G02X375837Y544726I-984J-999D01*
G37*
G36*
G01X358688Y533045D02*
G03Y532501I293J-272D01*
G02X356634I-1027J-955D01*
G03Y533045I-293J272D01*
G02X358688I1027J955D01*
G37*
G36*
G01X376202Y517883D02*
G03Y517329I288J-277D01*
G02X374182I-1010J-973D01*
G03Y517883I-288J277D01*
G02X376202I1010J973D01*
G37*
G36*
G01X362680Y516142D02*
G03X363262Y516132I296J269D01*
G02X363227Y514210I1003J-980D01*
G03X362645Y514220I-296J-269D01*
G02X362680Y516142I-1003J980D01*
G37*
G36*
G01X363196Y509206D02*
G03X362587I-305J-258D01*
G02Y511022I-1069J908D01*
G03X363196I305J258D01*
G02Y509206I1069J-908D01*
G37*
G36*
G01X373176Y612291D02*
G02X372642Y611067I863J-1105D01*
G03X371997Y611348I-398J-34D01*
G02X372531Y612572I-863J1105D01*
G03X373176Y612291I398J34D01*
G37*
G36*
G01X375160Y594586D02*
G02X375066Y592831I1044J-936D01*
G03X374444Y592864I-324J-234D01*
G02X372370Y592849I-1044J936D01*
G03X371761Y592825I-294J-271D01*
G02X371689Y594642I-1102J866D01*
G03X372298Y594666I294J271D01*
G02X374538Y594619I1102J-866D01*
G03X375160Y594586I324J234D01*
G37*
G36*
G01X289985Y586787D02*
G02X288233Y586802I-885J-1087D01*
G03X288239Y587427I-247J315D01*
G02X288153Y589525I885J1087D01*
G03Y590103I-277J289D01*
G02Y592125I971J1011D01*
G03Y592703I-277J289D01*
G02X290095I971J1011D01*
G03Y592125I277J-289D01*
G02Y590103I-971J-1011D01*
G03Y589525I277J-289D01*
G02X289991Y587412I-971J-1011D01*
G03X289985Y586787I247J-315D01*
G37*
G36*
G01X253174D02*
G02X251422Y586802I-885J-1087D01*
G03X251428Y587427I-247J315D01*
G02X251342Y589525I885J1087D01*
G03Y590103I-277J289D01*
G02Y592125I971J1011D01*
G03Y592703I-277J289D01*
G02X253284I971J1011D01*
G03Y592125I277J-289D01*
G02Y590103I-971J-1011D01*
G03Y589525I277J-289D01*
G02X253180Y587412I-971J-1011D01*
G03X253174Y586787I247J-315D01*
G37*
G36*
G01X216363D02*
G02X214611Y586802I-885J-1087D01*
G03X214617Y587427I-247J315D01*
G02X214531Y589525I885J1087D01*
G03Y590103I-277J289D01*
G02Y592125I971J1011D01*
G03Y592703I-277J289D01*
G02X216473I971J1011D01*
G03Y592125I277J-289D01*
G02Y590103I-971J-1011D01*
G03Y589525I277J-289D01*
G02X216369Y587412I-971J-1011D01*
G03X216363Y586787I247J-315D01*
G37*
G36*
G01X179552D02*
G02X177800Y586802I-885J-1087D01*
G03X177806Y587427I-247J315D01*
G02X177720Y589525I885J1087D01*
G03Y590103I-277J289D01*
G02Y592125I971J1011D01*
G03Y592703I-277J289D01*
G02X179662I971J1011D01*
G03Y592125I277J-289D01*
G02Y590103I-971J-1011D01*
G03Y589525I277J-289D01*
G02X179558Y587412I-971J-1011D01*
G03X179552Y586787I247J-315D01*
G37*
G36*
G01X142741D02*
G02X140989Y586802I-885J-1087D01*
G03X140995Y587427I-247J315D01*
G02X140909Y589525I885J1087D01*
G03Y590103I-277J289D01*
G02Y592125I971J1011D01*
G03Y592703I-277J289D01*
G02X142851I971J1011D01*
G03Y592125I277J-289D01*
G02Y590103I-971J-1011D01*
G03Y589525I277J-289D01*
G02X142747Y587412I-971J-1011D01*
G03X142741Y586787I247J-315D01*
G37*
G36*
G01X289985Y548987D02*
G02X288233Y549002I-885J-1087D01*
G03X288239Y549627I-247J315D01*
G02X288153Y551725I885J1087D01*
G03Y552303I-277J289D01*
G02Y554325I971J1011D01*
G03Y554903I-277J289D01*
G02X290095I971J1011D01*
G03Y554325I277J-289D01*
G02Y552303I-971J-1011D01*
G03Y551725I277J-289D01*
G02X289991Y549612I-971J-1011D01*
G03X289985Y548987I247J-315D01*
G37*
G36*
G01X253174D02*
G02X251422Y549002I-885J-1087D01*
G03X251428Y549627I-247J315D01*
G02X251342Y551725I885J1087D01*
G03Y552303I-277J289D01*
G02Y554325I971J1011D01*
G03Y554903I-277J289D01*
G02X253284I971J1011D01*
G03Y554325I277J-289D01*
G02Y552303I-971J-1011D01*
G03Y551725I277J-289D01*
G02X253180Y549612I-971J-1011D01*
G03X253174Y548987I247J-315D01*
G37*
G36*
G01X216363D02*
G02X214611Y549002I-885J-1087D01*
G03X214617Y549627I-247J315D01*
G02X214531Y551725I885J1087D01*
G03Y552303I-277J289D01*
G02Y554325I971J1011D01*
G03Y554903I-277J289D01*
G02X216473I971J1011D01*
G03Y554325I277J-289D01*
G02Y552303I-971J-1011D01*
G03Y551725I277J-289D01*
G02X216369Y549612I-971J-1011D01*
G03X216363Y548987I247J-315D01*
G37*
G36*
G01X179552D02*
G02X177800Y549002I-885J-1087D01*
G03X177806Y549627I-247J315D01*
G02X177720Y551725I885J1087D01*
G03Y552303I-277J289D01*
G02Y554325I971J1011D01*
G03Y554903I-277J289D01*
G02X179662I971J1011D01*
G03Y554325I277J-289D01*
G02Y552303I-971J-1011D01*
G03Y551725I277J-289D01*
G02X179558Y549612I-971J-1011D01*
G03X179552Y548987I247J-315D01*
G37*
G36*
G01X142741D02*
G02X140989Y549002I-885J-1087D01*
G03X140995Y549627I-247J315D01*
G02X140909Y551725I885J1087D01*
G03Y552303I-277J289D01*
G02Y554325I971J1011D01*
G03Y554903I-277J289D01*
G02X142851I971J1011D01*
G03Y554325I277J-289D01*
G02Y552303I-971J-1011D01*
G03Y551725I277J-289D01*
G02X142747Y549612I-971J-1011D01*
G03X142741Y548987I247J-315D01*
G37*
G36*
G01X975284Y104251D02*
G03X975861Y104144I338J214D01*
G02X975516Y102270I839J-1123D01*
G03X974939Y102377I-338J-214D01*
G02X975284Y104251I-839J1123D01*
G37*
G36*
G01X1013753Y86617D02*
G03X1013132I-311J-252D01*
G02Y88383I-1089J883D01*
G03X1013753I310J252D01*
G02Y86617I1089J-883D01*
G37*
G36*
G01X1025955Y85404D02*
G03Y84850I288J-277D01*
G02X1023935I-1010J-973D01*
G03Y85404I-288J277D01*
G02X1025955I1010J973D01*
G37*
G36*
G01X1008351Y69924D02*
G03Y69346I277J-289D01*
G02X1006409I-971J-1011D01*
G03Y69924I-277J289D01*
G02X1008351I971J1011D01*
G37*
G36*
G01X1100197Y53958D02*
G03X1099620Y53942I-281J-285D01*
G02X1099565Y55882I-1039J941D01*
G03X1100142Y55898I281J285D01*
G02X1100197Y53958I1039J-941D01*
G37*
G36*
G01X1246007Y51564D02*
G03Y50964I265J-300D01*
G02X1244149I-929J-1050D01*
G03Y51564I-265J300D01*
G02X1246007I929J1050D01*
G37*
G36*
G01X1239314D02*
G03Y50964I265J-300D01*
G02X1237456I-929J-1050D01*
G03Y51564I-265J300D01*
G02X1239314I929J1050D01*
G37*
G36*
G01X1221882D02*
G03Y50964I265J-300D01*
G02X1220024I-929J-1050D01*
G03Y51564I-265J300D01*
G02X1221882I929J1050D01*
G37*
G36*
G01X1209196D02*
G03Y50964I265J-300D01*
G02X1207338I-929J-1050D01*
G03Y51564I-265J300D01*
G02X1209196I929J1050D01*
G37*
G36*
G01X1202503D02*
G03Y50964I265J-300D01*
G02X1200645I-929J-1050D01*
G03Y51564I-265J300D01*
G02X1202503I929J1050D01*
G37*
G36*
G01X1185071D02*
G03Y50964I265J-300D01*
G02X1183213I-929J-1050D01*
G03Y51564I-265J300D01*
G02X1185071I929J1050D01*
G37*
G36*
G01X1172385D02*
G03Y50964I265J-300D01*
G02X1170527I-929J-1050D01*
G03Y51564I-265J300D01*
G02X1172385I929J1050D01*
G37*
G36*
G01X1165692D02*
G03Y50964I265J-300D01*
G02X1163834I-929J-1050D01*
G03Y51564I-265J300D01*
G02X1165692I929J1050D01*
G37*
G36*
G01X1148260D02*
G03Y50964I265J-300D01*
G02X1146402I-929J-1050D01*
G03Y51564I-265J300D01*
G02X1148260I929J1050D01*
G37*
G36*
G01X1135574D02*
G03Y50964I265J-300D01*
G02X1133716I-929J-1050D01*
G03Y51564I-265J300D01*
G02X1135574I929J1050D01*
G37*
G36*
G01X1128881D02*
G03Y50964I265J-300D01*
G02X1127023I-929J-1050D01*
G03Y51564I-265J300D01*
G02X1128881I929J1050D01*
G37*
G36*
G01X1111449D02*
G03Y50964I265J-300D01*
G02X1109591I-929J-1050D01*
G03Y51564I-265J300D01*
G02X1111449I929J1050D01*
G37*
G36*
G01X1230845Y51303D02*
G03Y50725I277J-289D01*
G02X1228903I-971J-1011D01*
G03Y51303I-277J289D01*
G02Y53325I971J1011D01*
G03Y53903I-277J289D01*
G02X1230845I971J1011D01*
G03Y53325I277J-289D01*
G02Y51303I-971J-1011D01*
G37*
G36*
G01X1008310Y51293D02*
G03Y50699I268J-297D01*
G02X1006430I-940J-1040D01*
G03Y51293I-268J297D01*
G02X1008310I940J1040D01*
G37*
G36*
G01X1297889Y50307D02*
G03X1297887Y49723I272J-293D01*
G02X1295974Y49728I-959J-1023D01*
G03X1295976Y50312I-272J293D01*
G02X1297889Y50307I959J1023D01*
G37*
G36*
G01X1120389Y48682D02*
G03X1120380Y48102I271J-294D01*
G02X1118451Y48132I-980J-1002D01*
G03X1118460Y48712I-271J294D01*
G02X1118469Y50725I980J1002D01*
G03Y51303I-277J289D01*
G02Y53325I971J1011D01*
G03Y53903I-277J289D01*
G02X1120411I971J1011D01*
G03Y53325I277J-289D01*
G02Y51303I-971J-1011D01*
G03Y50725I277J-289D01*
G02X1120389Y48682I-971J-1011D01*
G37*
G36*
G01X1193965Y48641D02*
G03X1193954Y48038I257J-306D01*
G02X1192110Y48073I-942J-1038D01*
G03X1192121Y48676I-257J306D01*
G02X1192092Y50725I942J1038D01*
G03Y51303I-277J289D01*
G02Y53325I971J1011D01*
G03Y53903I-277J289D01*
G02X1194034I971J1011D01*
G03Y53325I277J-289D01*
G02Y51303I-971J-1011D01*
G03Y50725I277J-289D01*
G02X1193965Y48641I-971J-1011D01*
G37*
G36*
G01X1157153D02*
G03X1157142Y48038I257J-306D01*
G02X1155298Y48073I-942J-1038D01*
G03X1155309Y48676I-257J306D01*
G02X1155280Y50725I942J1038D01*
G03Y51303I-277J289D01*
G02X1155281Y53326I971J1011D01*
G03Y53903I-277J289D01*
G02X1157222Y53902I971J1011D01*
G03Y53325I277J-288D01*
G02Y51303I-971J-1011D01*
G03Y50725I277J-289D01*
G02X1157153Y48641I-971J-1011D01*
G37*
G36*
G01X1012804Y46006D02*
G03X1012195I-305J-258D01*
G02Y47822I-1069J908D01*
G03X1012804I304J258D01*
G02Y46006I1069J-908D01*
G37*
G36*
G01X1225744Y48488D02*
G03Y47910I277J-289D01*
G02X1223804I-970J-1012D01*
G03Y48488I-277J289D01*
G02X1223803Y50511I970J1012D01*
G03Y51089I-277J289D01*
G02X1225745I971J1011D01*
G03Y50511I277J-289D01*
G02X1225744Y48488I-971J-1011D01*
G37*
G36*
G01X1188933D02*
G03Y47910I277J-289D01*
G02X1186993I-970J-1012D01*
G03Y48488I-277J289D01*
G02X1186992Y50511I970J1012D01*
G03Y51089I-277J289D01*
G02X1186973Y53092I971J1011D01*
G03X1186961Y53670I-283J283D01*
G02X1188902Y53708I951J1030D01*
G03X1188914Y53130I283J-283D01*
G02X1188934Y51089I-951J-1030D01*
G03Y50511I277J-289D01*
G02X1188933Y48488I-971J-1011D01*
G37*
G36*
G01X1152121D02*
G03X1152122Y47911I277J-288D01*
G02X1150182Y47910I-969J-1013D01*
G03X1150181Y48487I-277J288D01*
G02X1150180Y50511I970J1012D01*
G03Y51089I-277J289D01*
G02X1150161Y53092I971J1011D01*
G03X1150149Y53670I-283J283D01*
G02X1152090Y53708I951J1030D01*
G03X1152102Y53130I283J-283D01*
G02X1152122Y51089I-951J-1030D01*
G03Y50511I277J-289D01*
G02X1152121Y48488I-971J-1011D01*
G37*
G36*
G01X1115310D02*
G03Y47910I277J-289D01*
G02X1113370I-970J-1012D01*
G03Y48488I-277J289D01*
G02X1113369Y50511I970J1012D01*
G03Y51089I-277J289D01*
G02X1113354Y53097I971J1011D01*
G03X1113345Y53674I-282J284D01*
G02X1115286Y53703I955J1026D01*
G03X1115295Y53126I282J-284D01*
G02X1115311Y51089I-955J-1026D01*
G03Y50511I277J-289D01*
G02X1115310Y48488I-971J-1011D01*
G37*
G36*
G01X1009185Y32318D02*
G03X1009179Y31740I273J-292D01*
G02X1007242Y31760I-979J-1004D01*
G03X1007248Y32338I-273J292D01*
G02X1009185Y32318I979J1004D01*
G37*
G36*
G01X1225750Y29719D02*
G03Y29131I271J-294D01*
G02X1223850I-950J-1031D01*
G03Y29719I-271J294D01*
G02X1223839Y31771I950J1031D01*
G03X1223834Y32359I-274J292D01*
G02X1223803Y34410I940J1040D01*
G03Y34988I-277J289D01*
G02X1225745I971J1011D01*
G03Y34410I277J-289D01*
G02X1225735Y32378I-971J-1011D01*
G03X1225740Y31790I274J-292D01*
G02X1225750Y29719I-940J-1040D01*
G37*
G36*
G01X1188952Y29731D02*
G03X1188960Y29143I275J-290D01*
G02X1187060Y29119I-937J-1043D01*
G03X1187052Y29707I-275J290D01*
G02X1187028Y31771I937J1043D01*
G03X1187023Y32359I-274J292D01*
G02X1186992Y34410I940J1040D01*
G03Y34988I-277J289D01*
G02X1188934I971J1011D01*
G03Y34410I277J-289D01*
G02X1188924Y32378I-971J-1011D01*
G03X1188929Y31790I274J-292D01*
G02X1188952Y29731I-940J-1040D01*
G37*
G36*
G01X1152140D02*
G03X1152148Y29143I275J-290D01*
G02X1150248Y29119I-937J-1043D01*
G03X1150240Y29707I-275J290D01*
G02X1150216Y31771I937J1043D01*
G03X1150211Y32359I-274J292D01*
G02X1150181Y34411I940J1040D01*
G03Y34988I-277J288D01*
G02X1152122Y34987I971J1011D01*
G03Y34410I277J-288D01*
G02X1152112Y32378I-971J-1011D01*
G03X1152117Y31790I274J-292D01*
G02X1152140Y29731I-940J-1040D01*
G37*
G36*
G01X1115329D02*
G03X1115337Y29143I275J-290D01*
G02X1113437Y29119I-937J-1043D01*
G03X1113429Y29707I-275J290D01*
G02X1113405Y31771I937J1043D01*
G03X1113400Y32359I-274J292D01*
G02X1113369Y34410I940J1040D01*
G03Y34988I-277J289D01*
G02X1115311I971J1011D01*
G03Y34410I277J-289D01*
G02X1115301Y32378I-971J-1011D01*
G03X1115306Y31790I274J-292D01*
G02X1115329Y29731I-940J-1040D01*
G37*
G36*
G01X1230848Y29532D02*
G03X1230851Y28954I278J-288D01*
G02X1228913Y28944I-964J-1018D01*
G03X1228910Y29522I-278J288D01*
G02X1228907Y31555I964J1018D01*
G03Y32134I-276J289D01*
G02X1228876Y34133I967J1015D01*
G03X1228859Y34711I-285J281D01*
G02X1230798Y34766I941J1039D01*
G03X1230815Y34188I285J-281D01*
G02X1230841Y32134I-941J-1039D01*
G03Y31555I276J-289D01*
G02X1230848Y29532I-967J-1015D01*
G37*
G36*
G01X1194037D02*
G03X1194040Y28954I278J-288D01*
G02X1192102Y28944I-964J-1018D01*
G03X1192099Y29522I-278J288D01*
G02X1192096Y31555I964J1018D01*
G03Y32134I-276J289D01*
G02X1192098Y34166I967J1015D01*
G03X1192089Y34754I-275J290D01*
G02X1193988Y34783I934J1046D01*
G03X1193997Y34195I275J-290D01*
G02X1194030Y32134I-934J-1046D01*
G03Y31555I276J-289D01*
G02X1194037Y29532I-967J-1015D01*
G37*
G36*
G01X1157226D02*
G03X1157229Y28954I278J-288D01*
G02X1155290Y28944I-964J-1018D01*
G03X1155287Y29522I-278J288D01*
G02X1155284Y31555I964J1018D01*
G03Y32134I-276J289D01*
G02X1155286Y34166I967J1015D01*
G03X1155277Y34754I-275J290D01*
G02X1157176Y34783I934J1046D01*
G03X1157185Y34195I275J-290D01*
G02X1157218Y32134I-934J-1046D01*
G03Y31555I276J-289D01*
G02X1157226Y29532I-967J-1015D01*
G37*
G36*
G01X1120414D02*
G03X1120417Y28954I278J-288D01*
G02X1118479Y28944I-964J-1018D01*
G03X1118476Y29522I-278J288D01*
G02X1118473Y31555I964J1018D01*
G03Y32134I-276J289D01*
G02X1118475Y34166I967J1015D01*
G03X1118466Y34754I-275J290D01*
G02X1120365Y34783I934J1046D01*
G03X1120374Y34195I275J-290D01*
G02X1120407Y32134I-934J-1046D01*
G03Y31555I276J-289D01*
G02X1120414Y29532I-967J-1015D01*
G37*
G36*
G01X1013899Y16081D02*
G03X1013311Y16074I-291J-275D01*
G02X1013290Y17975I-1041J939D01*
G03X1013878Y17982I291J275D01*
G02X1013899Y16081I1041J-939D01*
G37*
G36*
G01X1100193Y16163D02*
G03X1099598Y16128I-282J-284D01*
G02X1099488Y17994I-1098J872D01*
G03X1100083Y18029I282J284D01*
G02X1100193Y16163I1098J-872D01*
G37*
G36*
G01X1047394Y15661D02*
G03X1046925Y15287I-70J-394D01*
G02X1045768Y16738I-1400J70D01*
G03X1046237Y17112I70J394D01*
G02X1047394Y15661I1400J-70D01*
G37*
G36*
G01X1246007Y13764D02*
G03Y13164I265J-300D01*
G02X1244149I-929J-1050D01*
G03Y13764I-265J300D01*
G02X1246007I929J1050D01*
G37*
G36*
G01X1239314D02*
G03Y13164I265J-300D01*
G02X1237456I-929J-1050D01*
G03Y13764I-265J300D01*
G02X1239314I929J1050D01*
G37*
G36*
G01X1221882D02*
G03Y13164I265J-300D01*
G02X1220024I-929J-1050D01*
G03Y13764I-265J300D01*
G02X1221882I929J1050D01*
G37*
G36*
G01X1215594Y13725D02*
G03X1215607Y13148I283J-282D01*
G02X1213666Y13103I-947J-1034D01*
G03X1213653Y13680I-283J282D01*
G02X1215594Y13725I947J1034D01*
G37*
G36*
G01X1209196Y13764D02*
G03Y13164I265J-300D01*
G02X1207338I-929J-1050D01*
G03Y13764I-265J300D01*
G02X1209196I929J1050D01*
G37*
G36*
G01X1202503D02*
G03Y13164I265J-300D01*
G02X1200645I-929J-1050D01*
G03Y13764I-265J300D01*
G02X1202503I929J1050D01*
G37*
G36*
G01X1185071D02*
G03Y13164I265J-300D01*
G02X1183213I-929J-1050D01*
G03Y13764I-265J300D01*
G02X1185071I929J1050D01*
G37*
G36*
G01X1178789Y13721D02*
G03X1178800Y13144I282J-283D01*
G02X1176859Y13107I-951J-1030D01*
G03X1176848Y13684I-282J283D01*
G02X1178789Y13721I951J1030D01*
G37*
G36*
G01X1172385Y13764D02*
G03Y13164I265J-300D01*
G02X1170527I-929J-1050D01*
G03Y13764I-265J300D01*
G02X1172385I929J1050D01*
G37*
G36*
G01X1165692D02*
G03Y13164I265J-300D01*
G02X1163834I-929J-1050D01*
G03Y13764I-265J300D01*
G02X1165692I929J1050D01*
G37*
G36*
G01X1148260D02*
G03Y13164I265J-300D01*
G02X1146402I-929J-1050D01*
G03Y13764I-265J300D01*
G02X1148260I929J1050D01*
G37*
G36*
G01X1141978Y13721D02*
G03X1141989Y13144I282J-283D01*
G02X1140048Y13107I-951J-1030D01*
G03X1140037Y13684I-282J283D01*
G02X1141978Y13721I951J1030D01*
G37*
G36*
G01X1135574Y13764D02*
G03Y13164I265J-300D01*
G02X1133716I-929J-1050D01*
G03Y13764I-265J300D01*
G02X1135574I929J1050D01*
G37*
G36*
G01X1128881D02*
G03Y13164I265J-300D01*
G02X1127023I-929J-1050D01*
G03Y13764I-265J300D01*
G02X1128881I929J1050D01*
G37*
G36*
G01X1111449D02*
G03Y13164I265J-300D01*
G02X1109591I-929J-1050D01*
G03Y13764I-265J300D01*
G02X1111449I929J1050D01*
G37*
G36*
G01X1105167Y13721D02*
G03X1105178Y13144I282J-283D01*
G02X1103237Y13107I-951J-1030D01*
G03X1103226Y13684I-282J283D01*
G02X1105167Y13721I951J1030D01*
G37*
G36*
G01X1008071Y13303D02*
G03Y12725I277J-289D01*
G02X1006129I-971J-1011D01*
G03Y13303I-277J289D01*
G02X1008071I971J1011D01*
G37*
G36*
G01X1098845Y12664D02*
G03X1098830Y12087I269J-296D01*
G02X1096889Y12136I-996J-987D01*
G03X1096904Y12713I-269J296D01*
G02X1098845Y12664I996J987D01*
G37*
G36*
G01X1230810Y10870D02*
G03X1230793Y10290I267J-298D01*
G02X1228864Y10344I-993J-990D01*
G03X1228881Y10924I-267J298D01*
G02X1228903Y12925I993J990D01*
G03Y13503I-277J289D01*
G02Y15525I971J1011D01*
G03Y16103I-277J289D01*
G02X1230845I971J1011D01*
G03Y15525I277J-289D01*
G02Y13503I-971J-1011D01*
G03Y12925I277J-289D01*
G02X1230810Y10870I-971J-1011D01*
G37*
G36*
G01X1194012Y10882D02*
G03X1194003Y10302I271J-294D01*
G02X1192074Y10332I-980J-1002D01*
G03X1192083Y10912I-271J294D01*
G02X1192092Y12925I980J1002D01*
G03Y13503I-277J289D01*
G02Y15525I971J1011D01*
G03Y16103I-277J289D01*
G02X1194034I971J1011D01*
G03Y15525I277J-289D01*
G02Y13503I-971J-1011D01*
G03Y12925I277J-289D01*
G02X1194012Y10882I-971J-1011D01*
G37*
G36*
G01X1157201D02*
G03X1157192Y10302I271J-294D01*
G02X1155263Y10332I-980J-1002D01*
G03X1155272Y10912I-271J294D01*
G02X1155281Y12925I980J1002D01*
G03Y13503I-277J289D01*
G02Y15525I971J1011D01*
G03Y16103I-277J289D01*
G02X1157223I971J1011D01*
G03Y15525I277J-289D01*
G02Y13503I-971J-1011D01*
G03Y12925I277J-289D01*
G02X1157201Y10882I-971J-1011D01*
G37*
G36*
G01X1120389D02*
G03X1120380Y10302I271J-294D01*
G02X1118451Y10332I-980J-1002D01*
G03X1118460Y10912I-271J294D01*
G02X1118469Y12925I980J1002D01*
G03Y13503I-277J289D01*
G02Y15525I971J1011D01*
G03Y16103I-277J289D01*
G02X1120411I971J1011D01*
G03Y15525I277J-289D01*
G02Y13503I-971J-1011D01*
G03Y12925I277J-289D01*
G02X1120389Y10882I-971J-1011D01*
G37*
G36*
G01X1259473Y10130D02*
G03X1260036Y10118I288J278D01*
G02X1259991Y8127I964J-1018D01*
G03X1259428Y8139I-288J-278D01*
G02X1259473Y10130I-964J1018D01*
G37*
G36*
G01X1225744Y10688D02*
G03Y10110I277J-289D01*
G02X1223804I-970J-1012D01*
G03Y10688I-277J289D01*
G02X1223803Y12711I970J1012D01*
G03Y13289I-277J289D01*
G02X1223809Y15317I971J1011D01*
G03X1223813Y15895I-275J291D01*
G02X1225755Y15883I977J1005D01*
G03X1225751Y15305I275J-291D01*
G02X1225745Y13289I-977J-1005D01*
G03Y12711I277J-289D01*
G02X1225744Y10688I-971J-1011D01*
G37*
G36*
G01X1188933D02*
G03Y10110I277J-289D01*
G02X1186993I-970J-1012D01*
G03Y10688I-277J289D01*
G02X1186992Y12711I970J1012D01*
G03Y13289I-277J289D01*
G02X1186977Y15297I971J1011D01*
G03X1186968Y15874I-282J284D01*
G02X1188909Y15903I955J1026D01*
G03X1188918Y15326I282J-284D01*
G02X1188934Y13289I-955J-1026D01*
G03Y12711I277J-289D01*
G02X1188933Y10688I-971J-1011D01*
G37*
G36*
G01X1152122D02*
G03Y10110I277J-289D01*
G02X1150182I-970J-1012D01*
G03Y10688I-277J289D01*
G02X1150181Y12711I970J1012D01*
G03Y13289I-277J289D01*
G02X1150166Y15297I971J1011D01*
G03X1150157Y15874I-282J284D01*
G02X1152098Y15903I955J1026D01*
G03X1152107Y15326I282J-284D01*
G02X1152123Y13289I-955J-1026D01*
G03Y12711I277J-289D01*
G02X1152122Y10688I-971J-1011D01*
G37*
G36*
G01X1115310D02*
G03Y10110I277J-289D01*
G02X1113370I-970J-1012D01*
G03Y10688I-277J289D01*
G02X1113369Y12711I970J1012D01*
G03Y13289I-277J289D01*
G02X1113354Y15297I971J1011D01*
G03X1113345Y15874I-282J284D01*
G02X1115286Y15903I955J1026D01*
G03X1115295Y15326I282J-284D01*
G02X1115311Y13289I-955J-1026D01*
G03Y12711I277J-289D01*
G02X1115310Y10688I-971J-1011D01*
G37*
G36*
G01X1026779Y7498D02*
G03X1027385Y7467I316J245D01*
G02X1027291Y5642I1015J-967D01*
G03X1026685Y5673I-316J-245D01*
G02X1026779Y7498I-1015J967D01*
G37*
G36*
G01X1115301Y-5422D02*
G03X1115306Y-6010I274J-292D01*
G02X1113405Y-6029I-940J-1040D01*
G03X1113400Y-5441I-274J292D01*
G02X1113369Y-3390I940J1040D01*
G03Y-2812I-277J289D01*
G02X1115311I971J1011D01*
G03Y-3390I277J-289D01*
G02X1115301Y-5422I-971J-1011D01*
G37*
G36*
G01X1225759Y-8073D02*
G03X1225764Y-8661I273J-292D01*
G02X1223863Y-8677I-942J-1039D01*
G03X1223858Y-8089I-273J292D01*
G02X1223839Y-6029I942J1039D01*
G03X1223834Y-5441I-274J292D01*
G02X1223803Y-3390I940J1040D01*
G03Y-2812I-277J289D01*
G02X1225745I971J1011D01*
G03Y-3390I277J-289D01*
G02X1225735Y-5422I-971J-1011D01*
G03X1225740Y-6010I274J-292D01*
G02X1225759Y-8073I-940J-1040D01*
G37*
G36*
G01X1188948D02*
G03X1188953Y-8661I273J-292D01*
G02X1187052Y-8677I-942J-1039D01*
G03X1187047Y-8089I-273J292D01*
G02X1187028Y-6029I942J1039D01*
G03X1187023Y-5441I-274J292D01*
G02X1186992Y-3390I940J1040D01*
G03Y-2812I-277J289D01*
G02X1188934I971J1011D01*
G03Y-3390I277J-289D01*
G02X1188924Y-5422I-971J-1011D01*
G03X1188929Y-6010I274J-292D01*
G02X1188948Y-8073I-940J-1040D01*
G37*
G36*
G01X1152137D02*
G03X1152142Y-8661I273J-292D01*
G02X1150241Y-8677I-942J-1039D01*
G03X1150236Y-8089I-273J292D01*
G02X1150217Y-6029I942J1039D01*
G03X1150212Y-5441I-274J292D01*
G02X1150181Y-3390I940J1040D01*
G03Y-2812I-277J289D01*
G02X1152123I971J1011D01*
G03Y-3390I277J-289D01*
G02X1152113Y-5422I-971J-1011D01*
G03X1152118Y-6010I274J-292D01*
G02X1152137Y-8073I-940J-1040D01*
G37*
G36*
G01X1230848Y-8268D02*
G03X1230851Y-8846I278J-288D01*
G02X1228913Y-8856I-964J-1018D01*
G03X1228910Y-8278I-278J288D01*
G02X1228907Y-6245I964J1018D01*
G03Y-5666I-276J290D01*
G02X1228943Y-3603I967J1015D01*
G03X1228954Y-3014I-265J300D01*
G02X1230853Y-3048I968J1014D01*
G03X1230842Y-3637I265J-300D01*
G02X1230841Y-5666I-968J-1014D01*
G03Y-6245I276J-290D01*
G02X1230848Y-8268I-967J-1015D01*
G37*
G36*
G01X1194037D02*
G03X1194040Y-8846I278J-288D01*
G02X1192102Y-8856I-964J-1018D01*
G03X1192099Y-8278I-278J288D01*
G02X1192096Y-6245I964J1018D01*
G03Y-5666I-276J290D01*
G02X1192132Y-3603I967J1015D01*
G03X1192143Y-3014I-265J300D01*
G02X1194042Y-3048I968J1014D01*
G03X1194031Y-3637I265J-300D01*
G02X1194030Y-5666I-968J-1014D01*
G03Y-6245I276J-290D01*
G02X1194037Y-8268I-967J-1015D01*
G37*
G36*
G01X1157226D02*
G03X1157229Y-8846I278J-288D01*
G02X1155291Y-8856I-964J-1018D01*
G03X1155288Y-8278I-278J288D01*
G02X1155285Y-6245I964J1018D01*
G03Y-5666I-276J290D01*
G02X1155321Y-3603I967J1015D01*
G03X1155332Y-3014I-265J300D01*
G02X1157231Y-3048I968J1014D01*
G03X1157220Y-3637I265J-300D01*
G02X1157219Y-5666I-968J-1014D01*
G03Y-6245I276J-290D01*
G02X1157226Y-8268I-967J-1015D01*
G37*
G36*
G01X1120414D02*
G03X1120417Y-8846I278J-288D01*
G02X1118479Y-8856I-964J-1018D01*
G03X1118476Y-8278I-278J288D01*
G02X1118473Y-6245I964J1018D01*
G03Y-5666I-276J290D01*
G02X1120407I967J1015D01*
G03Y-6245I276J-290D01*
G02X1120414Y-8268I-967J-1015D01*
G37*
G36*
G01X1013495Y91625D02*
G02Y93375I-1095J875D01*
G03X1014120I312J250D01*
G02Y91625I1095J-875D01*
G03X1013495I-313J-250D01*
G37*
G36*
G01X1024615Y75306D02*
G02X1023185I-715J-1206D01*
G03Y75994I-204J344D01*
G02X1024615I715J1206D01*
G03Y75306I204J-344D01*
G37*
G36*
G01X1267011Y55414D02*
G02X1266804Y53749I1011J-971D01*
G03X1266168Y53828I-348J-198D01*
G02X1266375Y55493I-1011J971D01*
G03X1267011Y55414I348J198D01*
G37*
G36*
G01X1215569Y50981D02*
G02X1213984Y51142I-909J-1067D01*
G03X1214051Y51797I-193J351D01*
G02X1215636Y51636I909J1067D01*
G03X1215569Y50981I193J-351D01*
G37*
G36*
G01X1105013Y50725D02*
G02X1103403Y50698I-786J-1161D01*
G03X1103391Y51353I-236J323D01*
G02X1105001Y51380I786J1161D01*
G03X1105013Y50725I236J-323D01*
G37*
G36*
G01X1266336Y46199D02*
G02X1266158Y47939I-1179J758D01*
G03X1266780Y48003I285J280D01*
G02X1266958Y46263I1179J-758D01*
G03X1266336Y46199I-285J-280D01*
G37*
G36*
G01X1100010Y47672D02*
G02X1099974Y46187I1171J-771D01*
G03X1099296Y46203I-344J-204D01*
G02X1099332Y47688I-1171J771D01*
G03X1100010Y47672I344J204D01*
G37*
G36*
G01X1099301Y35187D02*
G02X1099201Y36520I-1279J574D01*
G03X1099902Y36573I336J217D01*
G02X1100002Y35240I1279J-574D01*
G03X1099301Y35187I-336J-217D01*
G37*
G36*
G01X1266424Y27299D02*
G02X1266071Y28962I-1267J600D01*
G03X1266693Y29094I261J304D01*
G02X1267046Y27431I1267J-600D01*
G03X1266424Y27299I-261J-304D01*
G37*
G36*
G01X1031207Y24330D02*
G02X1029654Y24304I-757J-1180D01*
G03X1029643Y24970I-227J329D01*
G02X1031196Y24996I757J1180D01*
G03X1031207Y24330I227J-329D01*
G37*
G36*
G01X1025003Y18760D02*
G02X1023684Y19551I-1263J-610D01*
G03X1024028Y20124I-16J399D01*
G02X1025347Y19333I1263J610D01*
G03X1025003Y18760I16J-399D01*
G37*
G36*
G01X1299110Y597327D02*
G03Y596773I288J-277D01*
G02X1297090I-1010J-973D01*
G03Y597327I-288J277D01*
G02X1299110I1010J973D01*
G37*
G36*
G01X1024477Y592640D02*
G03X1023923I-277J-288D01*
G02X1021901Y592720I-973J1010D01*
G03X1021313Y592731I-299J-266D01*
G02X1021349Y594630I-1013J969D01*
G03X1021937Y594619I299J266D01*
G02X1023923Y594660I1013J-969D01*
G03X1024477I277J288D01*
G02Y592640I973J-1010D01*
G37*
G36*
G01X1266772Y592646D02*
G03X1266186I-293J-272D01*
G02X1266185Y594553I-1029J953D01*
G03X1266771I293J272D01*
G02X1268811Y594571I1028J-953D01*
G03X1269389I289J277D01*
G02Y592629I1011J-971D01*
G03X1268811I-289J-277D01*
G02X1266772Y592646I-1011J971D01*
G37*
G36*
G01X1299110Y591527D02*
G03Y590973I288J-277D01*
G02X1297090I-1010J-973D01*
G03Y591527I-288J277D01*
G02X1299110I1010J973D01*
G37*
G36*
G01X1246007Y590364D02*
G03Y589764I265J-300D01*
G02X1244149I-929J-1050D01*
G03Y590364I-265J300D01*
G02X1246007I929J1050D01*
G37*
G36*
G01X1239314D02*
G03Y589764I265J-300D01*
G02X1237456I-929J-1050D01*
G03Y590364I-265J300D01*
G02X1239314I929J1050D01*
G37*
G36*
G01X1221882D02*
G03Y589764I265J-300D01*
G02X1220024I-929J-1050D01*
G03Y590364I-265J300D01*
G02X1221882I929J1050D01*
G37*
G36*
G01X1209196D02*
G03Y589764I265J-300D01*
G02X1207338I-929J-1050D01*
G03Y590364I-265J300D01*
G02X1209196I929J1050D01*
G37*
G36*
G01X1202503D02*
G03Y589764I265J-300D01*
G02X1200645I-929J-1050D01*
G03Y590364I-265J300D01*
G02X1202503I929J1050D01*
G37*
G36*
G01X1185071D02*
G03Y589764I265J-300D01*
G02X1183213I-929J-1050D01*
G03Y590364I-265J300D01*
G02X1185071I929J1050D01*
G37*
G36*
G01X1178789Y590321D02*
G03X1178800Y589744I282J-283D01*
G02X1176859Y589707I-951J-1030D01*
G03X1176848Y590284I-282J283D01*
G02X1178789Y590321I951J1030D01*
G37*
G36*
G01X1172385Y590364D02*
G03Y589764I265J-300D01*
G02X1170527I-929J-1050D01*
G03Y590364I-265J300D01*
G02X1172385I929J1050D01*
G37*
G36*
G01X1165692D02*
G03Y589764I265J-300D01*
G02X1163834I-929J-1050D01*
G03Y590364I-265J300D01*
G02X1165692I929J1050D01*
G37*
G36*
G01X1148260D02*
G03Y589764I265J-300D01*
G02X1146402I-929J-1050D01*
G03Y590364I-265J300D01*
G02X1148260I929J1050D01*
G37*
G36*
G01X1141978Y590321D02*
G03X1141989Y589744I282J-283D01*
G02X1140048Y589707I-951J-1030D01*
G03X1140037Y590284I-282J283D01*
G02X1141978Y590321I951J1030D01*
G37*
G36*
G01X1135574Y590364D02*
G03Y589764I265J-300D01*
G02X1133716I-929J-1050D01*
G03Y590364I-265J300D01*
G02X1135574I929J1050D01*
G37*
G36*
G01X1128881D02*
G03Y589764I265J-300D01*
G02X1127023I-929J-1050D01*
G03Y590364I-265J300D01*
G02X1128881I929J1050D01*
G37*
G36*
G01X1111491Y590303D02*
G03Y589725I277J-289D01*
G02X1109549I-971J-1011D01*
G03Y590303I-277J289D01*
G02X1111491I971J1011D01*
G37*
G36*
G01X1105167Y590321D02*
G03X1105178Y589744I282J-283D01*
G02X1103237Y589707I-951J-1030D01*
G03X1103226Y590284I-282J283D01*
G02X1105167Y590321I951J1030D01*
G37*
G36*
G01X1098802Y589591D02*
G03X1098590Y589035I144J-373D01*
G02X1096841Y589703I-1247J-641D01*
G03X1097053Y590259I-144J373D01*
G02X1098802Y589591I1247J641D01*
G37*
G36*
G01X1007377Y589955D02*
G03Y589377I277J-289D01*
G02X1005435I-971J-1011D01*
G03Y589955I-277J289D01*
G02X1007377I971J1011D01*
G37*
G36*
G01X1012804Y584806D02*
G03X1012195I-305J-258D01*
G02Y586622I-1069J908D01*
G03X1012804I304J258D01*
G02X1014884Y586685I1068J-908D01*
G03X1015462I289J277D01*
G02Y584743I1011J-971D01*
G03X1014884I-289J-277D01*
G02X1012804Y584806I-1012J971D01*
G37*
G36*
G01X1225744Y587288D02*
G03Y586710I277J-289D01*
G02X1223804I-970J-1012D01*
G03Y587288I-277J289D01*
G02X1223803Y589311I970J1012D01*
G03Y589889I-277J289D01*
G02X1223794Y591902I971J1011D01*
G03X1223789Y592480I-279J287D01*
G02X1225730Y592498I961J1020D01*
G03X1225735Y591920I279J-287D01*
G02X1225745Y589889I-961J-1020D01*
G03Y589311I277J-289D01*
G02X1225744Y587288I-971J-1011D01*
G37*
G36*
G01X1188933D02*
G03Y586710I277J-289D01*
G02X1186993I-970J-1012D01*
G03Y587288I-277J289D01*
G02X1186992Y589311I970J1012D01*
G03Y589889I-277J289D01*
G02X1186983Y591902I971J1011D01*
G03X1186978Y592480I-279J287D01*
G02X1188919Y592498I961J1020D01*
G03X1188924Y591920I279J-287D01*
G02X1188934Y589889I-961J-1020D01*
G03Y589311I277J-289D01*
G02X1188933Y587288I-971J-1011D01*
G37*
G36*
G01X1152122D02*
G03Y586710I277J-289D01*
G02X1150182I-970J-1012D01*
G03Y587288I-277J289D01*
G02X1150181Y589311I970J1012D01*
G03Y589889I-277J289D01*
G02X1150172Y591902I971J1011D01*
G03X1150167Y592480I-279J287D01*
G02X1152108Y592498I961J1020D01*
G03X1152113Y591920I279J-287D01*
G02X1152123Y589889I-961J-1020D01*
G03Y589311I277J-289D01*
G02X1152122Y587288I-971J-1011D01*
G37*
G36*
G01X1115310D02*
G03Y586710I277J-289D01*
G02X1113370I-970J-1012D01*
G03Y587288I-277J289D01*
G02X1113369Y589311I970J1012D01*
G03Y589889I-277J289D01*
G02X1113360Y591902I971J1011D01*
G03X1113355Y592480I-279J287D01*
G02X1115296Y592498I961J1020D01*
G03X1115301Y591920I279J-287D01*
G02X1115311Y589889I-961J-1020D01*
G03Y589311I277J-289D01*
G02X1115310Y587288I-971J-1011D01*
G37*
G36*
G01X1294692Y581162D02*
G03X1295092Y580762I400J0D01*
G02X1293688Y579358I-2J-1402D01*
G03X1293288Y579758I-400J0D01*
G02X1294692Y581162I2J1402D01*
G37*
G36*
G01X1266400Y575506D02*
G03X1267009Y575382I355J185D01*
G02X1266657Y573651I891J-1082D01*
G03X1266048Y573775I-355J-185D01*
G02X1266400Y575506I-891J1082D01*
G37*
G36*
G01X1008303Y570999D02*
G03Y570421I277J-289D01*
G02X1006361I-971J-1011D01*
G03Y570999I-277J289D01*
G02X1008303I971J1011D01*
G37*
G36*
G01X1225771Y568539D02*
G03Y567961I277J-289D01*
G02X1223829I-971J-1011D01*
G03Y568539I-277J289D01*
G02X1223839Y570571I971J1011D01*
G03X1223834Y571159I-274J292D01*
G02X1223803Y573210I940J1040D01*
G03Y573788I-277J289D01*
G02X1225745I971J1011D01*
G03Y573210I277J-289D01*
G02X1225735Y571178I-971J-1011D01*
G03X1225740Y570590I274J-292D01*
G02X1225771Y568539I-940J-1040D01*
G37*
G36*
G01X1188960D02*
G03Y567961I277J-289D01*
G02X1187018I-971J-1011D01*
G03Y568539I-277J289D01*
G02X1187028Y570571I971J1011D01*
G03X1187023Y571159I-274J292D01*
G02X1186992Y573210I940J1040D01*
G03Y573788I-277J289D01*
G02X1188934I971J1011D01*
G03Y573210I277J-289D01*
G02X1188924Y571178I-971J-1011D01*
G03X1188929Y570590I274J-292D01*
G02X1188960Y568539I-940J-1040D01*
G37*
G36*
G01X1152149D02*
G03Y567961I277J-289D01*
G02X1150207I-971J-1011D01*
G03Y568539I-277J289D01*
G02X1150217Y570571I971J1011D01*
G03X1150212Y571159I-274J292D01*
G02X1150181Y573210I940J1040D01*
G03Y573788I-277J289D01*
G02X1152123I971J1011D01*
G03Y573210I277J-289D01*
G02X1152113Y571178I-971J-1011D01*
G03X1152118Y570590I274J-292D01*
G02X1152149Y568539I-940J-1040D01*
G37*
G36*
G01X1115337D02*
G03Y567961I277J-289D01*
G02X1113395I-971J-1011D01*
G03Y568539I-277J289D01*
G02X1113405Y570571I971J1011D01*
G03X1113400Y571159I-274J292D01*
G02X1113369Y573210I940J1040D01*
G03Y573788I-277J289D01*
G02X1115311I971J1011D01*
G03Y573210I277J-289D01*
G02X1115301Y571178I-971J-1011D01*
G03X1115306Y570590I274J-292D01*
G02X1115337Y568539I-940J-1040D01*
G37*
G36*
G01X1230848Y568332D02*
G03X1230851Y567754I278J-288D01*
G02X1228913Y567744I-964J-1018D01*
G03X1228910Y568322I-278J288D01*
G02X1228907Y570355I964J1018D01*
G03Y570934I-276J289D01*
G02X1228914Y572971I967J1015D01*
G03X1228920Y573548I-274J291D01*
G02X1230860Y573528I980J1002D01*
G03X1230854Y572951I274J-291D01*
G02X1230841Y570934I-980J-1002D01*
G03Y570355I276J-290D01*
G02X1230848Y568332I-967J-1015D01*
G37*
G36*
G01X1194037D02*
G03X1194040Y567754I278J-288D01*
G02X1192102Y567744I-964J-1018D01*
G03X1192099Y568322I-278J288D01*
G02X1192096Y570355I964J1018D01*
G03Y570934I-276J289D01*
G02X1192103Y572971I967J1015D01*
G03X1192109Y573548I-274J291D01*
G02X1194049Y573528I980J1002D01*
G03X1194043Y572951I274J-291D01*
G02X1194030Y570934I-980J-1002D01*
G03Y570355I276J-290D01*
G02X1194037Y568332I-967J-1015D01*
G37*
G36*
G01X1157226D02*
G03X1157229Y567754I278J-288D01*
G02X1155291Y567744I-964J-1018D01*
G03X1155288Y568322I-278J288D01*
G02X1155285Y570355I964J1018D01*
G03Y570934I-276J289D01*
G02X1155292Y572971I967J1015D01*
G03X1155298Y573548I-274J291D01*
G02X1157238Y573528I980J1002D01*
G03X1157232Y572951I274J-291D01*
G02X1157219Y570934I-980J-1002D01*
G03Y570355I276J-290D01*
G02X1157226Y568332I-967J-1015D01*
G37*
G36*
G01X1120414D02*
G03X1120417Y567754I278J-288D01*
G02X1118479Y567744I-964J-1018D01*
G03X1118476Y568322I-278J288D01*
G02X1118473Y570355I964J1018D01*
G03Y570934I-276J289D01*
G02X1118480Y572971I967J1015D01*
G03X1118486Y573548I-274J291D01*
G02X1120426Y573528I980J1002D01*
G03X1120420Y572951I274J-291D01*
G02X1120407Y570934I-980J-1002D01*
G03Y570355I276J-290D01*
G02X1120414Y568332I-967J-1015D01*
G37*
G36*
G01X1246007Y552564D02*
G03Y551964I265J-300D01*
G02X1244149I-929J-1050D01*
G03Y552564I-265J300D01*
G02X1246007I929J1050D01*
G37*
G36*
G01X1239314D02*
G03Y551964I265J-300D01*
G02X1237456I-929J-1050D01*
G03Y552564I-265J300D01*
G02X1239314I929J1050D01*
G37*
G36*
G01X1221882D02*
G03Y551964I265J-300D01*
G02X1220024I-929J-1050D01*
G03Y552564I-265J300D01*
G02X1221882I929J1050D01*
G37*
G36*
G01X1209196D02*
G03Y551964I265J-300D01*
G02X1207338I-929J-1050D01*
G03Y552564I-265J300D01*
G02X1209196I929J1050D01*
G37*
G36*
G01X1202503D02*
G03Y551964I265J-300D01*
G02X1200645I-929J-1050D01*
G03Y552564I-265J300D01*
G02X1202503I929J1050D01*
G37*
G36*
G01X1185071D02*
G03Y551964I265J-300D01*
G02X1183213I-929J-1050D01*
G03Y552564I-265J300D01*
G02X1185071I929J1050D01*
G37*
G36*
G01X1178789Y552521D02*
G03X1178800Y551944I282J-283D01*
G02X1176859Y551907I-951J-1030D01*
G03X1176848Y552484I-282J283D01*
G02X1178789Y552521I951J1030D01*
G37*
G36*
G01X1172385Y552564D02*
G03Y551964I265J-300D01*
G02X1170527I-929J-1050D01*
G03Y552564I-265J300D01*
G02X1172385I929J1050D01*
G37*
G36*
G01X1165692D02*
G03Y551964I265J-300D01*
G02X1163834I-929J-1050D01*
G03Y552564I-265J300D01*
G02X1165692I929J1050D01*
G37*
G36*
G01X1148260D02*
G03Y551964I265J-300D01*
G02X1146402I-929J-1050D01*
G03Y552564I-265J300D01*
G02X1148260I929J1050D01*
G37*
G36*
G01X1141978Y552521D02*
G03X1141989Y551944I282J-283D01*
G02X1140048Y551907I-951J-1030D01*
G03X1140037Y552484I-282J283D01*
G02X1141978Y552521I951J1030D01*
G37*
G36*
G01X1135574Y552564D02*
G03Y551964I265J-300D01*
G02X1133716I-929J-1050D01*
G03Y552564I-265J300D01*
G02X1135574I929J1050D01*
G37*
G36*
G01X1128881D02*
G03Y551964I265J-300D01*
G02X1127023I-929J-1050D01*
G03Y552564I-265J300D01*
G02X1128881I929J1050D01*
G37*
G36*
G01X1111491Y552503D02*
G03Y551925I277J-289D01*
G02X1109549I-971J-1011D01*
G03Y552503I-277J289D01*
G02X1111491I971J1011D01*
G37*
G36*
G01X1105167Y552521D02*
G03X1105178Y551944I282J-283D01*
G02X1103237Y551907I-951J-1030D01*
G03X1103226Y552484I-282J283D01*
G02X1105167Y552521I951J1030D01*
G37*
G36*
G01X1008118Y552100D02*
G03Y551522I277J-289D01*
G02X1006176I-971J-1011D01*
G03Y552100I-277J289D01*
G02X1008118I971J1011D01*
G37*
G36*
G01X1012804Y547006D02*
G03X1012195I-305J-258D01*
G02Y548822I-1069J908D01*
G03X1012804I304J258D01*
G02Y547006I1069J-908D01*
G37*
G36*
G01X1225744Y549488D02*
G03Y548910I277J-289D01*
G02X1223804I-970J-1012D01*
G03Y549488I-277J289D01*
G02X1223803Y551511I970J1012D01*
G03Y552089I-277J289D01*
G02X1223794Y554102I971J1011D01*
G03X1223789Y554680I-279J287D01*
G02X1225730Y554698I961J1020D01*
G03X1225735Y554120I279J-287D01*
G02X1225745Y552089I-961J-1020D01*
G03Y551511I277J-289D01*
G02X1225744Y549488I-971J-1011D01*
G37*
G36*
G01X1188933D02*
G03Y548910I277J-289D01*
G02X1186993I-970J-1012D01*
G03Y549488I-277J289D01*
G02X1186992Y551511I970J1012D01*
G03Y552089I-277J289D01*
G02X1186983Y554102I971J1011D01*
G03X1186978Y554680I-279J287D01*
G02X1188919Y554698I961J1020D01*
G03X1188924Y554120I279J-287D01*
G02X1188934Y552089I-961J-1020D01*
G03Y551511I277J-289D01*
G02X1188933Y549488I-971J-1011D01*
G37*
G36*
G01X1152122D02*
G03Y548910I277J-289D01*
G02X1150182I-970J-1012D01*
G03Y549488I-277J289D01*
G02X1150181Y551511I970J1012D01*
G03Y552089I-277J289D01*
G02X1150172Y554102I971J1011D01*
G03X1150167Y554680I-279J287D01*
G02X1152108Y554698I961J1020D01*
G03X1152113Y554120I279J-287D01*
G02X1152123Y552089I-961J-1020D01*
G03Y551511I277J-289D01*
G02X1152122Y549488I-971J-1011D01*
G37*
G36*
G01X1115310D02*
G03Y548910I277J-289D01*
G02X1113370I-970J-1012D01*
G03Y549488I-277J289D01*
G02X1113369Y551511I970J1012D01*
G03Y552089I-277J289D01*
G02X1113360Y554102I971J1011D01*
G03X1113355Y554680I-279J287D01*
G02X1115296Y554698I961J1020D01*
G03X1115301Y554120I279J-287D01*
G02X1115311Y552089I-961J-1020D01*
G03Y551511I277J-289D01*
G02X1115310Y549488I-971J-1011D01*
G37*
G36*
G01X1025534Y542016D02*
G03X1025512Y542615I-276J290D01*
G02Y544785I888J1085D01*
G03X1025534Y545384I-254J309D01*
G02X1027388Y545315I966J1016D01*
G03X1027366Y544716I254J-309D01*
G02Y542684I-966J-1016D01*
G03X1027388Y542085I276J-290D01*
G02X1027510Y540027I-888J-1085D01*
G03Y539473I288J-277D01*
G02X1025490I-1010J-973D01*
G03Y540027I-288J277D01*
G02X1025534Y542016I1010J973D01*
G37*
G36*
G01X1008178Y533126D02*
G03Y532548I277J-289D01*
G02X1006236I-971J-1011D01*
G03Y533126I-277J289D01*
G02X1008178I971J1011D01*
G37*
G36*
G01X1025810Y517883D02*
G03Y517329I288J-277D01*
G02X1023790I-1010J-973D01*
G03Y517883I-288J277D01*
G02X1025810I1010J973D01*
G37*
G36*
G01X1012288Y516142D02*
G03X1012870Y516132I296J269D01*
G02X1012835Y514210I1003J-980D01*
G03X1012253Y514220I-296J-269D01*
G02X1012288Y516142I-1003J980D01*
G37*
G36*
G01X1012804Y509206D02*
G03X1012195I-305J-258D01*
G02Y511022I-1069J908D01*
G03X1012804I304J258D01*
G02Y509206I1069J-908D01*
G37*
G36*
G01X1022726Y612019D02*
G02X1021807Y610859I474J-1319D01*
G03X1021274Y611281I-397J46D01*
G02X1022193Y612441I-474J1319D01*
G03X1022726Y612019I397J-46D01*
G37*
G36*
G01X1265434Y605850D02*
G02X1263824Y604910I-277J-1374D01*
G03X1263523Y605426I-380J124D01*
G02X1263263Y605505I276J1374D01*
G03X1263015Y605218I-76J-185D01*
G02X1262016Y605886I-1204J-719D01*
G03X1262457Y606397I58J396D01*
G02X1265133Y606366I1343J403D01*
G03X1265434Y605850I380J-124D01*
G37*
G36*
G01X1230735Y586787D02*
G02X1228983Y586802I-885J-1087D01*
G03X1228989Y587427I-247J315D01*
G02X1228903Y589525I885J1087D01*
G03Y590103I-277J289D01*
G02Y592125I971J1011D01*
G03Y592703I-277J289D01*
G02X1230845I971J1011D01*
G03Y592125I277J-289D01*
G02Y590103I-971J-1011D01*
G03Y589525I277J-289D01*
G02X1230741Y587412I-971J-1011D01*
G03X1230735Y586787I247J-315D01*
G37*
G36*
G01X1193924D02*
G02X1192172Y586802I-885J-1087D01*
G03X1192178Y587427I-247J315D01*
G02X1192092Y589525I885J1087D01*
G03Y590103I-277J289D01*
G02Y592125I971J1011D01*
G03Y592703I-277J289D01*
G02X1194034I971J1011D01*
G03Y592125I277J-289D01*
G02Y590103I-971J-1011D01*
G03Y589525I277J-289D01*
G02X1193930Y587412I-971J-1011D01*
G03X1193924Y586787I247J-315D01*
G37*
G36*
G01X1157113D02*
G02X1155361Y586802I-885J-1087D01*
G03X1155367Y587427I-247J315D01*
G02X1155281Y589525I885J1087D01*
G03Y590103I-277J289D01*
G02Y592125I971J1011D01*
G03Y592703I-277J289D01*
G02X1157223I971J1011D01*
G03Y592125I277J-289D01*
G02Y590103I-971J-1011D01*
G03Y589525I277J-289D01*
G02X1157119Y587412I-971J-1011D01*
G03X1157113Y586787I247J-315D01*
G37*
G36*
G01X1120301D02*
G02X1118549Y586802I-885J-1087D01*
G03X1118555Y587427I-247J315D01*
G02X1118469Y589525I885J1087D01*
G03Y590103I-277J289D01*
G02Y592125I971J1011D01*
G03Y592703I-277J289D01*
G02X1120411I971J1011D01*
G03Y592125I277J-289D01*
G02Y590103I-971J-1011D01*
G03Y589525I277J-289D01*
G02X1120307Y587412I-971J-1011D01*
G03X1120301Y586787I247J-315D01*
G37*
G36*
G01X1283571Y582011D02*
G02X1281629I-971J-1011D01*
G03Y582589I-277J289D01*
G02X1282579Y585002I971J1011D01*
G03X1282872Y585667I-6J400D01*
G02X1284548Y584343I4531J4012D01*
G03X1283969Y583904I-188J-353D01*
G02X1283571Y582589I-1369J-303D01*
G03Y582011I277J-289D01*
G37*
G36*
G01X1291833Y574879D02*
G02X1290274Y576083I-4430J-4124D01*
G03X1290847Y576550I190J352D01*
G02X1290798Y577116I1343J401D01*
G03X1290376Y577563I-397J48D01*
G02X1291684Y578798I-84J1399D01*
G03X1292106Y578351I397J-48D01*
G02X1292140Y575551I84J-1399D01*
G03X1291833Y574879I-14J-400D01*
G37*
G36*
G01X1286743Y560598D02*
G02X1286157Y562180I-1343J402D01*
G03X1286757Y562402I217J336D01*
G02X1288885Y563162I1343J-402D01*
G03X1289506Y563450I224J332D01*
G02X1290115Y562138I1394J-150D01*
G03X1289494Y561850I-224J-332D01*
G02X1287343Y560820I-1394J150D01*
G03X1286743Y560598I-217J-336D01*
G37*
G36*
G01X1230735Y548987D02*
G02X1228983Y549002I-885J-1087D01*
G03X1228989Y549627I-247J315D01*
G02X1228903Y551725I885J1087D01*
G03Y552303I-277J289D01*
G02Y554325I971J1011D01*
G03Y554903I-277J289D01*
G02X1230845I971J1011D01*
G03Y554325I277J-289D01*
G02Y552303I-971J-1011D01*
G03Y551725I277J-289D01*
G02X1230741Y549612I-971J-1011D01*
G03X1230735Y548987I247J-315D01*
G37*
G36*
G01X1193924D02*
G02X1192172Y549002I-885J-1087D01*
G03X1192178Y549627I-247J315D01*
G02X1192092Y551725I885J1087D01*
G03Y552303I-277J289D01*
G02Y554325I971J1011D01*
G03Y554903I-277J289D01*
G02X1194034I971J1011D01*
G03Y554325I277J-289D01*
G02Y552303I-971J-1011D01*
G03Y551725I277J-289D01*
G02X1193930Y549612I-971J-1011D01*
G03X1193924Y548987I247J-315D01*
G37*
G36*
G01X1157113D02*
G02X1155361Y549002I-885J-1087D01*
G03X1155367Y549627I-247J315D01*
G02X1155281Y551725I885J1087D01*
G03Y552303I-277J289D01*
G02Y554325I971J1011D01*
G03Y554903I-277J289D01*
G02X1157223I971J1011D01*
G03Y554325I277J-289D01*
G02Y552303I-971J-1011D01*
G03Y551725I277J-289D01*
G02X1157119Y549612I-971J-1011D01*
G03X1157113Y548987I247J-315D01*
G37*
G36*
G01X1120301D02*
G02X1118549Y549002I-885J-1087D01*
G03X1118555Y549627I-247J315D01*
G02X1118469Y551725I885J1087D01*
G03Y552303I-277J289D01*
G02Y554325I971J1011D01*
G03Y554903I-277J289D01*
G02X1120411I971J1011D01*
G03Y554325I277J-289D01*
G02Y552303I-971J-1011D01*
G03Y551725I277J-289D01*
G02X1120307Y549612I-971J-1011D01*
G03X1120301Y548987I247J-315D01*
G37*
G36*
G01X1278982Y546573D02*
G02X1277957Y545548I336J-1361D01*
G03X1277473Y546032I-389J95D01*
G02X1278498Y547057I-336J1361D01*
G03X1278982Y546573I389J-95D01*
G37*
G54D70*
X388187Y88678D03*
Y50878D03*
Y69778D03*
Y13078D03*
Y31978D03*
Y-5822D03*
Y551879D03*
Y589679D03*
Y570755D03*
Y514079D03*
Y532955D03*
X1037797Y50878D03*
Y88678D03*
Y69778D03*
Y13078D03*
Y31978D03*
Y-5822D03*
Y551879D03*
Y589679D03*
Y570755D03*
Y514079D03*
Y532955D03*
G54D48*
X19800Y257900D03*
G54D26*
X19904Y254162D03*
X37000Y265350D03*
X33490Y267900D03*
X37000Y275000D03*
X105892Y8700D03*
X106200Y26500D03*
X106000Y17260D03*
X104500Y-1850D03*
X102100Y73800D03*
X105892Y45290D03*
X105898Y55194D03*
X160431Y-1801D03*
X153738Y9114D03*
X150391Y-7851D03*
X163391D03*
X157084D03*
X153738Y-1751D03*
X160431Y9114D03*
X120273Y16839D03*
X147045Y9114D03*
X130163D03*
X123620D03*
X126580Y-7851D03*
X132959Y-7700D03*
X120273Y-9901D03*
X123620Y-1801D03*
X130313Y-1751D03*
X147045D03*
X167124D03*
X169770Y-7700D03*
X166974Y9114D03*
X169770Y30100D03*
X167124Y36049D03*
X120273Y27899D03*
X123620Y35983D03*
X130313D03*
X126580Y29949D03*
X132959Y30100D03*
X147045Y36049D03*
X153738D03*
X157084Y29949D03*
X163391D03*
X160431Y35999D03*
X150391Y29949D03*
X132959Y33700D03*
X163391D03*
X160431Y27899D03*
X130313D03*
X157084Y34100D03*
X153738Y27899D03*
X126580Y33700D03*
X123620Y27899D03*
X150391Y34100D03*
X147045Y27899D03*
X169770Y33700D03*
X167124Y27899D03*
X132959Y-4100D03*
X130313Y17157D03*
X163391Y-4100D03*
X160431Y17157D03*
Y-9901D03*
X130313D03*
X157084Y-3700D03*
X153738Y17157D03*
Y-9901D03*
X126580Y-4100D03*
X123620Y17157D03*
Y-9901D03*
X147045Y17157D03*
X150391Y-3700D03*
X147045Y-9901D03*
X169770Y-4100D03*
X167124Y17157D03*
Y-9901D03*
X120273Y9157D03*
X116070Y35780D03*
X114050Y21320D03*
X116692Y-1800D03*
X116300Y-9460D03*
X166974Y46914D03*
X123620D03*
X147045D03*
X120273Y54839D03*
X130163Y46914D03*
X120273Y66000D03*
X160431Y46914D03*
X153738D03*
X130313Y54957D03*
X160431D03*
X153738D03*
X123620D03*
X147045D03*
X167124D03*
X120273Y46957D03*
X116200Y70387D03*
X115980Y73680D03*
X113100Y57770D03*
X183856Y-1751D03*
Y9114D03*
Y36049D03*
X190549Y9114D03*
X197242D03*
X193895Y-7851D03*
X187202D03*
X200202D03*
X190549Y-1751D03*
X197242Y-1801D03*
X203935Y-1751D03*
X206581Y-7700D03*
X203785Y9114D03*
X200202Y29949D03*
X187202D03*
X193895D03*
X203935Y36049D03*
X206581Y30100D03*
X220667Y-1751D03*
X227360D03*
X234053Y-1801D03*
X230706Y-7851D03*
X224013D03*
X220667Y9114D03*
X234053D03*
X227360D03*
X224013Y29949D03*
X230706D03*
X234053Y35999D03*
X220667Y36049D03*
X227360D03*
X197242Y35999D03*
X190549Y36049D03*
X193895Y34100D03*
X190549Y27899D03*
X187202Y34100D03*
X183856Y27899D03*
X206581Y33700D03*
X203935Y27899D03*
X230706Y34100D03*
X227360Y27899D03*
X200202Y33700D03*
X197242Y27899D03*
X224013Y34100D03*
X220667Y27899D03*
X234053D03*
X193895Y-3700D03*
X190549Y17157D03*
Y-9901D03*
X187202Y-3700D03*
X183856Y17157D03*
Y-9901D03*
X206581Y-4100D03*
X203935Y17157D03*
Y-9901D03*
X230706Y-3700D03*
X227360Y17157D03*
Y-9901D03*
X200202Y-4100D03*
X197242Y17157D03*
Y-9901D03*
X224013Y-3700D03*
X220667Y17157D03*
Y-9901D03*
X234053Y17157D03*
Y-9901D03*
X183856Y46914D03*
X203785D03*
X190549D03*
X197242D03*
X220667D03*
X227360D03*
X234053D03*
X190549Y54957D03*
X183856D03*
X203935D03*
X227360D03*
X197242D03*
X220667D03*
X234053D03*
X270864Y-1801D03*
X240746Y-1751D03*
X264171D03*
X257478D03*
X243392Y-7700D03*
X260824Y-7851D03*
X237013D03*
X267517D03*
X264171Y9114D03*
X240596D03*
X270864D03*
X257478D03*
X267517Y29949D03*
X243392Y30100D03*
X257478Y36049D03*
X240746D03*
X264171D03*
X260824Y29949D03*
X237013D03*
X294289Y-1751D03*
X273824Y-7851D03*
X280203Y-7700D03*
X294289Y9114D03*
X277407D03*
X277557Y-1751D03*
X273824Y29949D03*
X280203Y30100D03*
X277557Y36049D03*
X294289D03*
X270864Y35999D03*
X243392Y33700D03*
X240746Y27899D03*
X267517Y34100D03*
X264171Y27899D03*
X237013Y33700D03*
X260824Y34100D03*
X257478Y27899D03*
X280203Y33700D03*
X277557Y27899D03*
X273824Y33700D03*
X270864Y27899D03*
X294289D03*
X243392Y-4100D03*
X240746Y17157D03*
Y-9901D03*
X267517Y-3700D03*
X264171Y17157D03*
Y-9901D03*
X237013Y-4100D03*
X260824Y-3700D03*
X257478Y17157D03*
Y-9901D03*
X280203Y-4100D03*
X277557Y17157D03*
Y-9901D03*
X270864Y17157D03*
X273824Y-4100D03*
X270864Y-9901D03*
X294289Y17157D03*
Y-9901D03*
X257478Y46914D03*
X240596D03*
X270864D03*
X264171D03*
X294289D03*
X277407D03*
X240746Y54957D03*
X264171D03*
X257478D03*
X277557D03*
X270864D03*
X273910Y49914D03*
X294289Y54957D03*
X297635Y-7851D03*
X304328D03*
X300982Y-1751D03*
Y9114D03*
X307675Y-1843D03*
Y9300D03*
X304328Y29949D03*
X307992Y13200D03*
X300982Y36049D03*
X321192Y13200D03*
X321334Y32100D03*
X308092D03*
X307675Y35957D03*
X297635Y29949D03*
X334292Y13200D03*
Y32100D03*
X308157Y-7180D03*
X307675Y17057D03*
Y28014D03*
X321061D03*
X327754Y35957D03*
X324407Y28014D03*
Y35957D03*
X314368Y28014D03*
X311021Y35957D03*
X304328Y34100D03*
X300982Y27899D03*
X297635Y34100D03*
X334447Y35957D03*
X331100Y28014D03*
X354525Y28022D03*
X354526Y35957D03*
X351179Y28022D03*
X347833Y35957D03*
X344486D03*
Y28022D03*
X337793Y35957D03*
X341140Y28022D03*
X334446Y28014D03*
X321061Y17057D03*
Y-7108D03*
X327754Y9114D03*
Y-1743D03*
X324407Y17057D03*
Y-9901D03*
Y-4536D03*
Y9114D03*
X314368Y-7108D03*
X311021Y-4536D03*
X314368Y17057D03*
X311021Y9114D03*
X304328Y-3700D03*
X300982Y17157D03*
Y-9901D03*
X297635Y-3700D03*
X334447Y-1743D03*
X334446Y9114D03*
X331100Y-9786D03*
Y17057D03*
X354526Y-7108D03*
Y17057D03*
X354525Y9122D03*
Y-1742D03*
X351179Y-9901D03*
Y17057D03*
X347833Y9122D03*
Y-1743D03*
X344486Y9122D03*
Y-4536D03*
Y17057D03*
Y-9786D03*
X337793Y9114D03*
Y-4536D03*
X341140Y17057D03*
Y-7108D03*
X334447D03*
Y17057D03*
X317714Y35957D03*
Y-4536D03*
Y9114D03*
X307950Y50729D03*
X321192Y51000D03*
X300982Y46914D03*
X321334Y69900D03*
X334292Y51000D03*
Y69900D03*
X307675Y54857D03*
X321061Y65814D03*
Y92757D03*
X327754Y73757D03*
Y87392D03*
X324407Y65814D03*
Y89964D03*
Y73757D03*
Y84599D03*
X314368Y65814D03*
Y92657D03*
X311021Y84714D03*
X334447Y73757D03*
Y87392D03*
X331100Y65814D03*
Y89964D03*
X354525Y65822D03*
X354415Y92757D03*
X354526Y73757D03*
X354415Y87392D03*
X351179Y65822D03*
Y89964D03*
X347833Y73757D03*
Y87392D03*
X344486Y84714D03*
Y73757D03*
Y65822D03*
Y89964D03*
X337793Y84599D03*
Y73757D03*
X341140Y65822D03*
Y92757D03*
X334446Y65814D03*
X334447Y92757D03*
X321061Y54857D03*
X327754Y46914D03*
X324407Y54857D03*
Y46914D03*
X314368Y54857D03*
X311021Y46914D03*
X300982Y54957D03*
X334446Y46914D03*
X331100Y54857D03*
X354526D03*
X354525Y46922D03*
X351179Y54857D03*
X347833Y46922D03*
X344486D03*
Y54857D03*
X337793Y46914D03*
X341140Y54857D03*
X334447D03*
X317714Y84714D03*
Y73757D03*
Y46914D03*
X348978Y220809D03*
Y209109D03*
X352357Y211060D03*
X342218Y220809D03*
X338838Y211058D03*
X355737Y209109D03*
Y220809D03*
X342218Y205210D03*
X345598Y207159D03*
X342218Y209109D03*
X348978Y205210D03*
Y216909D03*
X352357Y218860D03*
X345598D03*
X342218Y213009D03*
X338838Y214960D03*
X359117Y211060D03*
Y218860D03*
X355737Y216909D03*
Y213009D03*
X342218Y216909D03*
X338838Y207158D03*
Y203258D03*
X345598Y211060D03*
X348978Y213009D03*
X352357Y238360D03*
X345598D03*
X342218Y224709D03*
X345598Y230559D03*
X338838Y222760D03*
X352357D03*
X348978Y224709D03*
X355737D03*
X348978Y228610D03*
X352357Y230559D03*
X348978Y236409D03*
Y240309D03*
X352357Y234460D03*
X345598Y242260D03*
Y234460D03*
X342218Y240309D03*
Y228610D03*
Y236409D03*
X359117Y230559D03*
X355737Y228610D03*
Y236409D03*
X352357Y242260D03*
X355737Y240309D03*
X345598Y222760D03*
X380200Y-1200D03*
X394192Y-9700D03*
X408184Y32100D03*
Y13200D03*
X404723Y28022D03*
X401377Y35957D03*
X364565Y28014D03*
Y35942D03*
X361218Y28014D03*
Y35942D03*
X414762Y28021D03*
X398029Y28007D03*
X404723Y35957D03*
X414763D03*
X408069Y28007D03*
X394684Y35957D03*
X404722Y-9901D03*
X404723Y17057D03*
X401376Y9121D03*
X401375Y-1743D03*
X364565Y-9786D03*
Y-1858D03*
Y9114D03*
X361218Y-9786D03*
Y-1858D03*
Y9114D03*
X414761Y-7108D03*
X414762Y17058D03*
X398029Y17042D03*
Y-9901D03*
X404722Y9121D03*
Y-4536D03*
X414763Y9122D03*
X414761Y-1743D03*
X408069Y17042D03*
X408068Y-7108D03*
X394682Y11792D03*
X394683Y-2200D03*
X376700Y-1300D03*
X371258Y-1858D03*
Y-9800D03*
X411415Y36058D03*
Y-4536D03*
X411416Y9122D03*
X394682Y17157D03*
X371042Y46900D03*
X380792Y56500D03*
X408184Y51000D03*
Y69900D03*
X394492Y54700D03*
X404723Y65822D03*
X404722Y89964D03*
X401377Y73757D03*
X401375Y87392D03*
X414763Y65822D03*
X414761Y92757D03*
X398029Y65807D03*
Y89964D03*
X404723Y73757D03*
X404722Y84599D03*
X414763Y73757D03*
X414761Y87392D03*
X408069Y65807D03*
X408068Y92757D03*
X394682Y87392D03*
X404723Y54857D03*
X401377Y46922D03*
X364565Y54842D03*
X361218D03*
X414763Y54857D03*
X398029Y54842D03*
X404723Y46922D03*
X414763D03*
X408069Y54842D03*
X394682Y49592D03*
X380600Y37400D03*
X384992Y81600D03*
X411415Y84714D03*
X411416Y73757D03*
Y46922D03*
X394682Y68492D03*
X386292Y98800D03*
X401375Y103116D03*
X414819D03*
X408126D03*
X362497Y209109D03*
Y220809D03*
X369257D03*
X382777D03*
Y209109D03*
X376017Y220809D03*
Y209109D03*
X389537D03*
Y220809D03*
X396296Y209109D03*
Y220809D03*
X407706Y209109D03*
Y220809D03*
X372637Y207159D03*
X399676D03*
X372637Y211060D03*
X392916D03*
X389537Y213009D03*
X396296D03*
X369257D03*
X396296Y216909D03*
X376017D03*
X365877Y218860D03*
X372637D03*
X362497Y216909D03*
X382777Y213009D03*
X399676Y218860D03*
X386157Y211060D03*
X407706Y216909D03*
X379397Y207159D03*
X369257Y216909D03*
X382777D03*
X379397Y218860D03*
X392916D03*
X362497Y213009D03*
X386157Y218860D03*
X389537Y216909D03*
X376017Y213009D03*
X399676Y211060D03*
X379397Y238360D03*
Y250060D03*
X386157Y238360D03*
X389537Y248109D03*
X376017D03*
X382777D03*
X386157Y250060D03*
X359117Y238360D03*
X365877D03*
X372637D03*
X392916Y250060D03*
Y238360D03*
X396296Y248109D03*
X399676Y250060D03*
X407706Y248109D03*
X396296Y244209D03*
Y240309D03*
X376017Y224709D03*
X372637Y222760D03*
X365877D03*
X369257Y224709D03*
X362497D03*
X386157Y222760D03*
X396296Y228610D03*
X389537Y224709D03*
X399676Y222760D03*
X382777Y224709D03*
X379397Y222760D03*
X359117D03*
X392916D03*
X396296Y224709D03*
X379397Y230559D03*
X365877Y242260D03*
X407706Y236409D03*
X372637Y234460D03*
X365877D03*
X372637Y230559D03*
X365877D03*
X369257Y236409D03*
X362497D03*
X369257Y228610D03*
X362497D03*
X382777D03*
X389537Y236409D03*
X399676Y230559D03*
Y234460D03*
X382777Y236409D03*
X392916Y230559D03*
X407706Y224709D03*
Y228610D03*
X376017Y236409D03*
X369257Y240309D03*
X376017D03*
X386157Y230559D03*
X372637Y242260D03*
X379397Y234460D03*
X399676Y238360D03*
X359117Y242260D03*
X362497Y240309D03*
X359117Y234460D03*
X386157D03*
X392916D03*
X389537Y228610D03*
X396296Y236409D03*
X376017Y228610D03*
X391787Y254259D03*
X388407Y256500D03*
X385027Y254259D03*
X395166Y256400D03*
X398546Y254259D03*
X405306Y254500D03*
X401926Y256500D03*
X399676Y242260D03*
X389537Y240309D03*
X382777D03*
X392916Y242260D03*
X386157D03*
X379397D03*
X389537Y244209D03*
X382777D03*
X376017D03*
X392916Y246160D03*
X386157D03*
X379397D03*
X372637D03*
X407706Y244209D03*
X399676Y246160D03*
X433508Y32100D03*
X421368D03*
X433508Y13200D03*
X421368D03*
X421455Y9121D03*
X421454Y-1817D03*
X438189Y35957D03*
X431494Y28007D03*
X444880Y28022D03*
X444882Y35957D03*
X428149D03*
X421456Y28022D03*
X434842Y35957D03*
X424801Y28007D03*
X438189Y28022D03*
X438187Y-4536D03*
Y9120D03*
X431494Y-9901D03*
X444880Y-9786D03*
Y-4536D03*
X431494Y17042D03*
X444880Y17059D03*
Y9122D03*
X428147Y-1743D03*
Y9120D03*
X421454Y-7108D03*
X421456Y17057D03*
X434840Y-1743D03*
Y9120D03*
X424801Y-9786D03*
X438187D03*
X424801Y17042D03*
X438187Y17059D03*
X421368Y51000D03*
X433508D03*
Y69900D03*
X421368D03*
X421455Y46921D03*
X421456Y73757D03*
X438187Y84714D03*
X438189Y73757D03*
X431494Y65807D03*
X444880Y65822D03*
X431494Y89964D03*
X444880D03*
Y84714D03*
X428147Y87392D03*
X428149Y73757D03*
X421456Y65822D03*
X421454Y92757D03*
X434842Y73757D03*
X434840Y87392D03*
X424801Y65807D03*
X438189Y65822D03*
X424801Y89964D03*
X438187D03*
X438189Y46922D03*
X431494Y54842D03*
X444880Y54859D03*
Y46922D03*
X428149D03*
X421456Y54857D03*
X434842Y46922D03*
X424801Y54842D03*
X438187Y54859D03*
X427696Y103100D03*
X421512Y103116D03*
X105392Y574800D03*
X105412Y556580D03*
X105392Y566000D03*
X105352Y594770D03*
X106192Y604600D03*
X130163Y547914D03*
X123620D03*
X147045D03*
X123620Y574799D03*
X130313Y574849D03*
X120092Y566900D03*
X147045Y585714D03*
X120273Y555700D03*
X130163Y585714D03*
X123620D03*
X166974Y547914D03*
X160431D03*
X153738D03*
X160431Y585714D03*
X166974D03*
X153738D03*
Y574849D03*
X157084Y568749D03*
X169770Y568900D03*
X160431Y574799D03*
X166974Y574849D03*
X163391Y568749D03*
X150391D03*
X147045Y574849D03*
X126580Y568749D03*
X132959Y568900D03*
X130313Y555957D03*
X132959Y572500D03*
X160431Y555957D03*
X163391Y572500D03*
X160431Y566699D03*
X130313D03*
X153738Y555957D03*
X157084Y572900D03*
X153738Y566699D03*
X123620Y555957D03*
X126580Y572500D03*
X123620Y566699D03*
X147045Y555957D03*
X150391Y572900D03*
X147045Y566699D03*
X167124Y555957D03*
X169770Y572500D03*
X167124Y566699D03*
X119892Y547900D03*
Y574700D03*
Y585700D03*
X114150Y585850D03*
X114509Y575658D03*
X116927Y555700D03*
X115883Y548024D03*
X132959Y606700D03*
X126580Y606549D03*
X120092Y604900D03*
X150391Y606549D03*
X163391D03*
X169770Y606700D03*
X157084Y606549D03*
X132959Y610300D03*
X130313Y593757D03*
X163391Y610300D03*
X160431Y593757D03*
Y604499D03*
X130313D03*
X157084Y610700D03*
X153738Y593757D03*
Y604499D03*
X126580Y610300D03*
X123620Y593757D03*
Y604499D03*
X150391Y610700D03*
X147045Y593757D03*
Y604499D03*
X167124Y593757D03*
X169770Y610300D03*
X167124Y604499D03*
X183856Y547914D03*
X190549D03*
X203785D03*
X197242D03*
Y574799D03*
X190549Y585714D03*
X183856D03*
X197242D03*
X203785D03*
X234053Y547914D03*
X220667D03*
X227360D03*
X220667Y585714D03*
X234053D03*
X227360D03*
Y574849D03*
X230706Y568749D03*
X220667Y574849D03*
X224013Y568749D03*
X234053Y574799D03*
X206581Y568900D03*
X183856Y574849D03*
X190549D03*
X193895Y568749D03*
X187202D03*
X200202D03*
X203935Y574849D03*
X190549Y555957D03*
X193895Y572900D03*
X190549Y566699D03*
X183856Y555957D03*
X187202Y572900D03*
X183856Y566699D03*
X203935Y555957D03*
X206581Y572500D03*
X203935Y566699D03*
X227360Y555957D03*
X230706Y572900D03*
X227360Y566699D03*
X197242Y555957D03*
X200202Y572500D03*
X197242Y566699D03*
X220667Y555961D03*
X224013Y572900D03*
X220667Y566699D03*
X234053Y555957D03*
Y566699D03*
X187202Y606549D03*
X193895D03*
X200202D03*
X206581Y606700D03*
X224013Y606549D03*
X230706D03*
X190549Y593757D03*
X193895Y610700D03*
X190549Y604499D03*
X183856Y593757D03*
X187202Y610700D03*
X183856Y604499D03*
X206581Y610300D03*
X203935Y593757D03*
Y604499D03*
X230706Y610700D03*
X227360Y593757D03*
Y604499D03*
X197242Y593757D03*
X200202Y610300D03*
X197242Y604499D03*
X224013Y610700D03*
X220667Y593761D03*
Y604499D03*
X234053Y593757D03*
Y604499D03*
X270864Y547914D03*
X264171D03*
X257478D03*
X240596D03*
X270864Y585714D03*
X264171D03*
X257478D03*
X240596D03*
X294289Y547914D03*
X277407D03*
Y585714D03*
X294289D03*
Y574849D03*
X277407D03*
X280203Y568900D03*
X273824Y568749D03*
X243392Y568900D03*
X260824Y568749D03*
X257478Y574849D03*
X264171D03*
X237013Y568749D03*
X240746Y574849D03*
X267517Y568749D03*
X270864Y574799D03*
X240746Y555957D03*
X243392Y572500D03*
X240746Y566699D03*
X264171Y555957D03*
X267517Y572900D03*
X264171Y566699D03*
X237013Y572500D03*
X257478Y555957D03*
X260824Y572900D03*
X257478Y566699D03*
X277557Y555957D03*
X280203Y572500D03*
X277557Y566699D03*
X270864Y555957D03*
X273824Y572500D03*
X270864Y566699D03*
X294289Y555957D03*
Y566699D03*
X260824Y606549D03*
X237013D03*
X243392Y606700D03*
X267517Y606549D03*
X273824D03*
X294289Y612249D03*
X280203Y606700D03*
X240746Y593757D03*
X243392Y610300D03*
X240746Y604499D03*
X267517Y610700D03*
X264171Y593757D03*
Y604499D03*
X237013Y610300D03*
X257478Y593757D03*
X260824Y610700D03*
X257478Y604499D03*
X280203Y610300D03*
X277557Y593757D03*
Y604499D03*
X273824Y610300D03*
X270864Y593757D03*
Y604499D03*
X294289Y593757D03*
Y604499D03*
X352357Y359260D03*
X345598D03*
X355737Y376809D03*
Y388509D03*
X348978Y376809D03*
X342218Y388509D03*
Y376809D03*
X345598Y390460D03*
X352357Y386560D03*
X342218Y384609D03*
X341892Y396301D03*
X345598Y386560D03*
X348978Y388509D03*
X342218Y380709D03*
X351192Y402800D03*
X345598Y378760D03*
X348978Y380709D03*
X345598Y367060D03*
X348978Y372909D03*
X342218D03*
X352357Y378760D03*
Y374860D03*
X359117Y386560D03*
X355737Y380709D03*
X359117Y374860D03*
X355737Y372909D03*
X348978Y369010D03*
X352357Y367060D03*
X355737Y384609D03*
X345598Y355360D03*
X348978Y357309D03*
Y361209D03*
X345598Y363160D03*
X342218Y357309D03*
Y369010D03*
Y361209D03*
X352357Y363160D03*
X359117D03*
X355737Y361209D03*
Y369010D03*
X352357Y355360D03*
X355737Y357309D03*
X348978Y384609D03*
X345598Y374860D03*
X324187Y499793D03*
X321061Y518157D03*
Y529014D03*
X327754Y512792D03*
X324407Y529014D03*
Y515364D03*
Y509999D03*
X326922Y497170D03*
X314368Y518057D03*
X334447Y512792D03*
X331100Y529014D03*
Y515364D03*
X354525Y529022D03*
X354526Y518157D03*
X354307Y512792D03*
X351179Y515364D03*
Y529022D03*
X347833Y512792D03*
X344486Y510114D03*
Y529022D03*
Y515364D03*
X337793Y509999D03*
X341140Y529022D03*
Y518157D03*
X334446Y529014D03*
X334447Y518157D03*
X317714Y510114D03*
X307675Y548200D03*
X300982Y547914D03*
X321334Y533100D03*
X321123Y552000D03*
X308100D03*
X307992Y570900D03*
X321334D03*
X321192Y589800D03*
X307675Y574757D03*
X300982Y574849D03*
Y585714D03*
X334292Y533100D03*
Y552000D03*
Y570900D03*
Y589800D03*
X297635Y568749D03*
X304328D03*
X307675Y555857D03*
X307984Y566743D03*
X327754Y536957D03*
X324407D03*
X311021D03*
X334447D03*
X354526D03*
X347833D03*
X344486D03*
X337793D03*
X321061Y566814D03*
Y555857D03*
X327754Y547914D03*
Y574757D03*
X324407Y555857D03*
Y566814D03*
Y547914D03*
Y574757D03*
X314368Y566814D03*
X311021Y574757D03*
X314368Y555857D03*
X311021Y547914D03*
X300982Y555957D03*
X304328Y572900D03*
X300982Y566699D03*
X297635Y572900D03*
X334446Y547914D03*
X334447Y574757D03*
X331100Y555857D03*
Y566814D03*
X354526Y555857D03*
X354525Y566822D03*
Y547922D03*
X354526Y574757D03*
X351179Y555857D03*
Y566822D03*
X347833Y547922D03*
Y574757D03*
X344486Y547922D03*
Y574757D03*
Y566822D03*
Y555857D03*
X337793Y547914D03*
Y574757D03*
X341140Y555857D03*
Y566822D03*
X334447Y555857D03*
X334446Y566814D03*
X327754Y585714D03*
X324407D03*
X311021D03*
X334446D03*
X354525Y585722D03*
X347833D03*
X344486D03*
X337793Y585714D03*
X317714Y536957D03*
Y547914D03*
Y574757D03*
Y585714D03*
X304328Y606549D03*
X297635D03*
X300982Y612249D03*
X307675Y611600D03*
X308157Y607220D03*
X321061Y593657D03*
Y607292D03*
X324407Y604499D03*
Y593657D03*
Y609864D03*
X314368Y607292D03*
X311021Y609864D03*
X314368Y593657D03*
X304328Y610700D03*
X300982Y593757D03*
Y604499D03*
X297635Y610700D03*
X331100Y604614D03*
Y593657D03*
X354526D03*
Y607292D03*
X351179Y604499D03*
Y593657D03*
X344486Y609864D03*
Y604614D03*
Y593657D03*
X337793Y609864D03*
X341140Y607292D03*
Y593657D03*
X334447Y607292D03*
Y593657D03*
X317714Y609864D03*
X388407Y345160D03*
X395166D03*
X401926D03*
X379397Y359260D03*
X386157Y351460D03*
Y359260D03*
X389537Y353409D03*
X372637Y359260D03*
X365877D03*
X359117D03*
X376017Y376809D03*
X369257D03*
X382777Y388509D03*
X369257D03*
X362497D03*
X376017D03*
X389537D03*
Y376809D03*
X382777D03*
X362497D03*
X396296Y353409D03*
X405306Y347109D03*
X399676Y351460D03*
X392916D03*
Y359260D03*
X396296Y388509D03*
Y376809D03*
X403056D03*
Y388509D03*
X392916Y355360D03*
X396296Y357309D03*
X389537D03*
X372637Y390460D03*
X396296Y384609D03*
X372637Y386560D03*
X392916D03*
X389537Y384609D03*
X399676Y390460D03*
X376017Y372909D03*
X369257Y384609D03*
X396296Y380709D03*
X369257Y372909D03*
X362497D03*
X372637Y378760D03*
X362497Y380709D03*
X372637Y374860D03*
X365877D03*
X376017Y380709D03*
X365877Y378760D03*
X382777Y384609D03*
X386157Y374860D03*
X399676Y378760D03*
X396296Y369010D03*
X386157Y386560D03*
X389537Y372909D03*
X403056Y380709D03*
X399676Y374860D03*
X379397Y386560D03*
X369257Y380709D03*
X382777D03*
Y372909D03*
X379397Y378760D03*
Y374860D03*
X392916Y378760D03*
X362497Y384609D03*
X359117Y378760D03*
X386157D03*
X392916Y374860D03*
X389537Y380709D03*
X396296Y372909D03*
X376017Y384609D03*
X379397Y367060D03*
X365877Y355360D03*
X403056Y361209D03*
X369257Y369010D03*
X362497D03*
X369257Y361209D03*
X362497D03*
X372637Y367060D03*
X365877D03*
X372637Y363160D03*
X365877D03*
X382777Y369010D03*
X389537Y361209D03*
X399676Y367060D03*
Y363160D03*
X382777Y361209D03*
X392916Y367060D03*
X403056Y372909D03*
Y369010D03*
X376017Y361209D03*
X369257Y357309D03*
X376017D03*
X386157Y367060D03*
X372637Y355360D03*
X379397Y363160D03*
X399676Y359260D03*
X359117Y355360D03*
X362497Y357309D03*
X359117Y367060D03*
X386157Y363160D03*
X392916D03*
X389537Y369010D03*
X396296Y361209D03*
X376017Y369010D03*
X391787Y347109D03*
X398546D03*
X399676Y355360D03*
X382777Y353409D03*
X386157Y355360D03*
X403056Y396309D03*
X411086Y394359D03*
Y390460D03*
X399676Y386560D03*
X411086D03*
Y382660D03*
X398546Y402900D03*
X382777Y357309D03*
X379397Y355360D03*
X402892Y400400D03*
X385244Y504027D03*
X363760Y529293D03*
X404723Y529022D03*
X404722Y515364D03*
X401375Y512792D03*
X414761Y518157D03*
X398029Y529007D03*
Y515364D03*
X404722Y509999D03*
X414761Y512792D03*
X408068Y518157D03*
X408069Y529007D03*
X394682Y512792D03*
X411415Y510114D03*
X394587Y529026D03*
X376785Y538305D03*
X376892Y577500D03*
X408184Y533100D03*
Y552000D03*
Y589800D03*
Y570900D03*
X401377Y536957D03*
X404723D03*
X414763D03*
X394595Y537058D03*
X404723Y566822D03*
Y555857D03*
X401376Y547922D03*
X401377Y574757D03*
X364565Y566814D03*
Y555842D03*
Y574742D03*
X361218Y566814D03*
X361320Y555842D03*
X361218Y574742D03*
X414763Y566822D03*
Y555857D03*
X398029Y566807D03*
Y555842D03*
X404723Y547922D03*
Y574757D03*
X414763D03*
Y547922D03*
X408069Y566807D03*
Y555842D03*
X394682Y550592D03*
X394684Y574757D03*
X401377Y585722D03*
X404723D03*
X414763D03*
X394682Y588392D03*
X376892Y581127D03*
X370596Y585614D03*
X411416Y536957D03*
X411415Y547921D03*
X411416Y574757D03*
Y585722D03*
X394682Y569492D03*
X404723Y593657D03*
X404722Y604499D03*
X364565Y604614D03*
X365311Y593642D03*
X364565Y612242D03*
X361218Y604614D03*
X361964Y593642D03*
X361218Y612242D03*
X414761Y607292D03*
X414763Y593657D03*
X398029Y593642D03*
Y604499D03*
X404722Y609864D03*
X408068Y607292D03*
X408069Y593642D03*
X378600Y606200D03*
X371312Y604709D03*
X411415Y609864D03*
X394682Y607292D03*
X438187Y510114D03*
X435192Y499400D03*
X431494Y515364D03*
X444880D03*
Y510114D03*
X428147Y512792D03*
X421456Y529022D03*
X421454Y518157D03*
X434840Y512792D03*
X424801Y515364D03*
X438187D03*
X421368Y533100D03*
X434395Y532904D03*
X433508Y552000D03*
X421368D03*
X420634Y589800D03*
X433508Y570900D03*
X421368D03*
X433500Y589800D03*
X421456Y547922D03*
Y585722D03*
X438189Y536957D03*
X444882D03*
X428149D03*
X434842D03*
X438189Y547922D03*
Y574757D03*
X431494Y566807D03*
X444880Y566822D03*
X444882Y574757D03*
X431494Y555842D03*
X444880Y555859D03*
Y547922D03*
X428149D03*
Y574757D03*
X421456Y555857D03*
Y566822D03*
X434842Y547922D03*
Y574757D03*
X424801Y566807D03*
X438189Y566822D03*
X424801Y555842D03*
X438187Y555859D03*
X438189Y585722D03*
X444880D03*
X428149D03*
X434842D03*
X447744Y607220D03*
X438187Y609864D03*
X431494Y604499D03*
X444880Y604614D03*
Y609864D03*
X431494Y593642D03*
X444880Y593659D03*
X421454Y607292D03*
X421456Y593657D03*
X424801Y604614D03*
X438187D03*
X424801Y593642D03*
X438187Y593659D03*
X957283Y-1843D03*
Y9300D03*
X957600Y13200D03*
X957700Y32100D03*
X970800Y13200D03*
X970942Y32100D03*
X957283Y35957D03*
X957765Y-7180D03*
X957283Y28014D03*
Y17057D03*
X970669Y28014D03*
X974015D03*
Y35957D03*
X963976Y28014D03*
X960629Y35957D03*
X970669Y-7108D03*
Y17057D03*
X974015D03*
Y-9901D03*
Y9114D03*
Y-4536D03*
X963976Y-7108D03*
X960629Y-4536D03*
X963976Y17057D03*
X960629Y9114D03*
X967322Y35957D03*
Y-4536D03*
Y9114D03*
X957558Y50729D03*
X970800Y50860D03*
X970942Y69900D03*
X957283Y54857D03*
X970669Y65814D03*
Y92757D03*
X974015Y65814D03*
Y89964D03*
Y84599D03*
Y73757D03*
X963976Y65814D03*
Y92657D03*
X960629Y84714D03*
X970669Y54857D03*
X974015D03*
Y46914D03*
X963976Y54857D03*
X960629Y46914D03*
X967322Y73757D03*
Y84714D03*
Y46914D03*
X983900Y13200D03*
Y32100D03*
X1026700Y1700D03*
X977362Y35957D03*
X1014173Y28014D03*
Y35942D03*
X1010826Y28014D03*
Y35942D03*
X984055Y35957D03*
X980708Y28014D03*
X1004133Y28022D03*
X1004134Y35957D03*
X1000787Y28022D03*
X997441Y35957D03*
X994094D03*
Y28022D03*
X987401Y35957D03*
X990748Y28022D03*
X984054Y28014D03*
X977362Y-1743D03*
Y9114D03*
X1014173Y-9786D03*
Y-1858D03*
Y9114D03*
X1010826Y-9786D03*
Y-1858D03*
Y9114D03*
X984055Y-1743D03*
X984054Y9114D03*
X980708Y-9786D03*
Y17057D03*
X1004134Y-7108D03*
Y17057D03*
X1004133Y-1742D03*
Y9122D03*
X1000787Y-9901D03*
Y17057D03*
X997441Y-1743D03*
Y9122D03*
X994094Y-4536D03*
Y9122D03*
Y-9786D03*
Y17057D03*
X987401Y9114D03*
Y-4536D03*
X990748Y-7108D03*
Y17057D03*
X984055Y-7108D03*
Y17057D03*
X1020866Y-1858D03*
X983900Y51000D03*
Y69900D03*
X1014350Y73000D03*
X1030400Y56500D03*
X1031600Y42900D03*
X977362Y73757D03*
Y87392D03*
X984055D03*
Y73757D03*
X980708Y65814D03*
Y89964D03*
X1004133Y65822D03*
X1004023Y92757D03*
X1004134Y73757D03*
X1004023Y87392D03*
X1000787Y65822D03*
Y89964D03*
X997441Y73757D03*
Y87392D03*
X994094Y84714D03*
Y73757D03*
Y65822D03*
Y89964D03*
X987401Y84599D03*
Y73757D03*
X990748Y65822D03*
Y92757D03*
X984054Y65814D03*
X984055Y92757D03*
X977362Y46914D03*
X1014173Y54842D03*
X1010826D03*
X984054Y46914D03*
X980708Y54857D03*
X1004134D03*
X1004133Y46922D03*
X1000787Y54857D03*
X997441Y46922D03*
X994094D03*
Y54857D03*
X987401Y46914D03*
X990748Y54857D03*
X984055D03*
X1020650Y46900D03*
X1030300Y63200D03*
X1035900Y98800D03*
X998586Y209109D03*
Y220809D03*
X991826D03*
X988446Y211058D03*
X1005345Y209109D03*
Y220809D03*
X1001965Y211060D03*
X1025625Y209109D03*
Y220809D03*
X1012105D03*
Y209109D03*
X1018865Y220809D03*
X1032385D03*
Y209109D03*
X1022245Y207159D03*
X991826Y205210D03*
X1022245Y211060D03*
X995206Y207159D03*
X991826Y209109D03*
X998586Y205210D03*
X1018865Y213009D03*
X998586Y216909D03*
X1001965Y218860D03*
X995206D03*
X991826Y213009D03*
X988446Y214960D03*
X1025625Y216909D03*
X1015485Y218860D03*
X1022245D03*
X1012105Y216909D03*
X1032385Y213009D03*
X1035765Y211060D03*
X1029005Y207159D03*
X1018865Y216909D03*
X1032385D03*
X1029005Y218860D03*
X1008725Y211060D03*
X1012105Y213009D03*
X1008725Y218860D03*
X1005345Y216909D03*
Y213009D03*
X1035765Y218860D03*
X1025625Y213009D03*
X991826Y216909D03*
X988446Y207158D03*
Y203258D03*
X995206Y211060D03*
X998586Y213009D03*
X995206Y238360D03*
X1029005D03*
X1008725D03*
X1001965D03*
X1035765D03*
Y250060D03*
X1029005D03*
X1032385Y248109D03*
X1025625D03*
X1015485Y238360D03*
X1022245D03*
X991826Y224709D03*
X995206Y230559D03*
X1025625Y224709D03*
X988446Y222760D03*
X1022245D03*
X1015485D03*
X1018865Y224709D03*
X1012105D03*
X1035765Y222760D03*
X1001965D03*
X998586Y224709D03*
X1032385D03*
X1029005Y222760D03*
X1008725D03*
X1005345Y224709D03*
X998586Y228610D03*
X1001965Y230559D03*
X998586Y236409D03*
Y240309D03*
X1029005Y230559D03*
X1015485Y242260D03*
X1001965Y234460D03*
X995206Y242260D03*
Y234460D03*
X991826Y240309D03*
Y228610D03*
Y236409D03*
X1022245Y234460D03*
X1015485D03*
X1022245Y230559D03*
X1015485D03*
X1018865Y236409D03*
X1012105D03*
X1018865Y228610D03*
X1012105D03*
X1032385D03*
Y236409D03*
X1025625D03*
X1018865Y240309D03*
X1025625D03*
X1035765Y230559D03*
X1022245Y242260D03*
X1029005Y234460D03*
X1008725Y242260D03*
X1012105Y240309D03*
X1008725Y230559D03*
Y234460D03*
X1005345Y228610D03*
Y236409D03*
X1001965Y242260D03*
X1005345Y240309D03*
X1035765Y234460D03*
X1025625Y228610D03*
X1034635Y254259D03*
X995206Y222760D03*
X1032385Y240309D03*
X1035765Y242260D03*
X1029005D03*
X1032385Y244209D03*
X1025625D03*
X1035765Y246160D03*
X1029005D03*
X1022245D03*
X1043800Y-9700D03*
X1057792Y13200D03*
Y32100D03*
X1097352Y-7180D03*
X1083116Y13200D03*
Y32100D03*
X1097900Y31900D03*
X1070976Y13200D03*
Y32100D03*
X1097834Y28100D03*
X1071062Y-1817D03*
X1071064Y9122D03*
X1054331Y28022D03*
X1050985Y35957D03*
X1087797D03*
X1064371Y28022D03*
X1081102Y28007D03*
X1094488Y28022D03*
X1094490Y35957D03*
X1047637Y28007D03*
X1054331Y35957D03*
X1077757D03*
X1064371D03*
X1071064Y28022D03*
X1057677Y28007D03*
X1084450Y35957D03*
X1074409Y28007D03*
X1087797Y28022D03*
X1044292Y35957D03*
X1054330Y-9901D03*
X1054331Y17057D03*
X1050985Y9122D03*
X1050983Y-1743D03*
X1087797Y9122D03*
X1087795Y-4536D03*
X1064369Y-7108D03*
X1081102Y-9901D03*
X1094488Y-9786D03*
Y-4536D03*
X1064371Y17057D03*
X1081102Y17042D03*
X1094488Y17059D03*
Y9122D03*
X1047637Y-9901D03*
X1054331Y9122D03*
X1054330Y-4536D03*
X1077757Y9122D03*
X1077755Y-1743D03*
X1064371Y9122D03*
X1064369Y-1743D03*
X1071062Y-7108D03*
X1071064Y17057D03*
X1057677Y17042D03*
X1057676Y-7108D03*
X1084450Y9122D03*
X1084448Y-1743D03*
X1074409Y-9786D03*
X1087795D03*
X1074409Y17042D03*
X1087795Y17059D03*
X1044290Y11792D03*
X1044291Y-2200D03*
X1061024Y35957D03*
X1061023Y-4536D03*
X1061024Y9122D03*
X1057792Y51000D03*
Y69900D03*
X1083116Y51000D03*
X1098100D03*
X1070976D03*
X1083116Y69900D03*
X1070976D03*
X1044100Y54700D03*
X1071064Y46922D03*
Y73757D03*
X1054331Y65822D03*
X1054330Y89964D03*
X1050985Y73757D03*
X1050983Y87392D03*
X1087797Y73757D03*
X1087795Y84714D03*
X1064371Y65822D03*
X1081102Y65807D03*
X1094488Y65822D03*
X1064369Y92757D03*
X1081102Y89964D03*
X1094488D03*
Y84714D03*
X1047637Y65807D03*
Y89964D03*
X1054331Y73757D03*
X1054330Y84599D03*
X1077755Y87392D03*
X1077757Y73757D03*
X1064371D03*
X1064369Y87392D03*
X1071064Y65822D03*
X1071062Y92757D03*
X1057677Y65807D03*
X1057676Y92757D03*
X1084448Y87392D03*
X1084450Y73757D03*
X1074409Y65807D03*
X1087797Y65822D03*
X1074409Y89964D03*
X1087795D03*
X1044290Y87392D03*
X1054331Y54857D03*
X1050985Y46922D03*
X1087797D03*
X1064371Y54857D03*
X1081102Y54842D03*
X1094488Y54859D03*
Y46922D03*
X1047637Y54842D03*
X1054331Y46922D03*
X1077757D03*
X1064371D03*
X1071064Y54857D03*
X1057677Y54842D03*
X1084450Y46922D03*
X1074409Y54842D03*
X1087795Y54859D03*
X1044290Y49592D03*
X1061024Y73757D03*
X1061023Y84714D03*
X1061024Y46922D03*
X1044290Y68964D03*
X1050983Y103116D03*
X1064427D03*
X1077304Y103100D03*
X1057734Y103116D03*
X1071120D03*
X1045904Y220809D03*
X1057314D03*
Y209109D03*
X1045904D03*
X1039145D03*
Y220809D03*
X1049284Y207159D03*
X1042524Y211060D03*
X1039145Y213009D03*
X1045904D03*
Y216909D03*
X1049284Y218860D03*
X1057314Y216909D03*
X1042524Y218860D03*
X1039145Y216909D03*
X1049284Y211060D03*
X1057314Y248109D03*
X1039145D03*
X1042524Y250060D03*
X1049284D03*
X1045904Y248109D03*
X1042524Y238360D03*
X1045904Y244209D03*
Y240309D03*
Y228610D03*
X1039145Y224709D03*
X1049284Y222760D03*
X1042524D03*
X1045904Y224709D03*
X1057314Y236409D03*
X1039145D03*
X1049284Y230559D03*
Y234460D03*
X1042524Y230559D03*
X1057314Y224709D03*
Y228610D03*
X1049284Y238360D03*
X1042524Y234460D03*
X1039145Y228610D03*
X1045904Y236409D03*
X1038015Y256500D03*
X1041395Y254259D03*
X1048154D03*
X1051534Y256500D03*
X1044774Y256400D03*
X1054914Y254500D03*
X1049284Y242260D03*
X1039145Y240309D03*
X1042524Y242260D03*
X1039145Y244209D03*
X1042524Y246160D03*
X1057314Y244209D03*
X1049284Y246160D03*
X1104141Y-7851D03*
X1110520Y-7700D03*
X1107874Y-1751D03*
X1101181Y-1801D03*
X1107724Y9114D03*
X1101181D03*
X1107874Y36049D03*
X1110520Y30100D03*
X1104141Y29949D03*
X1131299Y9114D03*
X1124606D03*
X1137992D03*
X1144535D03*
X1127952Y-7851D03*
X1124606Y-1751D03*
X1131299D03*
X1134645Y-7851D03*
X1147331Y-7700D03*
X1140952Y-7851D03*
X1137992Y-1801D03*
X1144685Y-1751D03*
X1147331Y30100D03*
X1134645Y29949D03*
X1137992Y35999D03*
X1140952Y29949D03*
X1144685Y36049D03*
X1127952Y29949D03*
X1131299Y36049D03*
X1124606D03*
X1110520Y33700D03*
X1107874Y27899D03*
X1134645Y34100D03*
X1131299Y27899D03*
X1104141Y33700D03*
X1101181Y27899D03*
X1127952Y34100D03*
X1124606Y27899D03*
X1147331Y33700D03*
X1144685Y27899D03*
X1140952Y33700D03*
X1137992Y27899D03*
X1110520Y-4100D03*
X1107874Y17157D03*
Y-9901D03*
X1134645Y-3700D03*
X1131299Y17157D03*
Y-9901D03*
X1104141Y-4100D03*
X1101181Y-9901D03*
X1127952Y-3700D03*
X1124606Y17157D03*
Y-9901D03*
X1147331Y-4100D03*
X1144685Y17157D03*
Y-9901D03*
X1140952Y-4100D03*
X1137992Y17157D03*
Y-9901D03*
X1107724Y46914D03*
X1137992D03*
X1144535D03*
X1131299D03*
X1124606D03*
X1107874Y54957D03*
X1131299D03*
X1124606D03*
X1144685D03*
X1137992D03*
X1141038Y49914D03*
X1161417Y9114D03*
X1168110D03*
X1174803D03*
X1171456Y-7851D03*
X1164763D03*
X1177763D03*
X1168110Y-1751D03*
X1161417D03*
X1174803Y-1801D03*
X1161417Y36049D03*
X1164763Y29949D03*
X1171456D03*
X1177763D03*
X1168110Y36049D03*
X1174803Y35999D03*
X1181496Y-1751D03*
X1181346Y9114D03*
X1204921D03*
X1198228D03*
X1184142Y-7700D03*
X1201574Y-7851D03*
X1204921Y-1751D03*
X1198228D03*
X1218307D03*
X1211614Y-1801D03*
X1214574Y-7851D03*
X1208267D03*
X1220953Y-7700D03*
X1218157Y9114D03*
X1211614D03*
X1181496Y36049D03*
X1184142Y30100D03*
X1204921Y36049D03*
X1198228D03*
X1201574Y29949D03*
X1218307Y36049D03*
X1211614Y35999D03*
X1208267Y29949D03*
X1220953Y30100D03*
X1214574Y29949D03*
X1171456Y34100D03*
X1168110Y27899D03*
X1164763Y34100D03*
X1161417Y27899D03*
X1184142Y33700D03*
X1181496Y27899D03*
X1208267Y34100D03*
X1204921Y27899D03*
X1177763Y33700D03*
X1174803Y27899D03*
X1201574Y34100D03*
X1198228Y27899D03*
X1220953Y33700D03*
X1218307Y27899D03*
X1214574Y33700D03*
X1211614Y27899D03*
X1171456Y-3700D03*
X1168110Y17157D03*
Y-9901D03*
X1164763Y-3700D03*
X1161417Y17157D03*
Y-9901D03*
X1184142Y-4100D03*
X1181496Y17157D03*
Y-9901D03*
X1204921Y17157D03*
X1208267Y-3700D03*
X1204921Y-9901D03*
X1177763Y-4100D03*
X1174803Y17157D03*
Y-9901D03*
X1198228Y17157D03*
X1201574Y-3700D03*
X1198228Y-9901D03*
X1220953Y-4100D03*
X1218307Y17157D03*
Y-9901D03*
X1214574Y-4100D03*
X1211614Y17157D03*
Y-9901D03*
X1168110Y46914D03*
X1161417D03*
X1174803D03*
X1181346D03*
X1198228D03*
X1204921D03*
X1211614D03*
X1218157D03*
X1168110Y54957D03*
X1161417D03*
X1181496D03*
X1204921D03*
X1174803D03*
X1177849Y49914D03*
X1198228Y54957D03*
X1218307D03*
X1211614D03*
X1241732Y36049D03*
X1238385Y29949D03*
X1245078D03*
X1251771Y16999D03*
X1248425Y36049D03*
Y27899D03*
X1269700Y13078D03*
X1241732Y-1751D03*
X1238385Y-7851D03*
X1241732Y9114D03*
X1248425Y-1751D03*
Y-9901D03*
X1251771D03*
X1245078Y-7851D03*
X1248425Y9157D03*
X1269800Y-5822D03*
X1235039Y9114D03*
Y-1751D03*
Y36049D03*
X1245078Y34100D03*
X1241732Y27899D03*
X1238385Y34100D03*
X1235039Y27899D03*
X1245078Y-3700D03*
X1241732Y17157D03*
Y-9901D03*
X1238385Y-3700D03*
X1235039Y17157D03*
Y-9901D03*
X1251771Y27899D03*
Y36057D03*
X1248425Y17057D03*
X1258464Y36057D03*
Y27899D03*
X1265157Y36057D03*
X1261811D03*
Y27899D03*
Y16999D03*
X1258464D03*
X1265157Y9157D03*
X1251771D03*
Y-1743D03*
X1261811Y-9901D03*
X1258464D03*
X1261811Y-1743D03*
X1265157D03*
X1258464D03*
X1255118Y-9901D03*
Y27899D03*
Y16999D03*
Y-1743D03*
Y36057D03*
Y9157D03*
X1265157Y-9901D03*
Y16999D03*
X1241732Y46914D03*
X1248425Y46957D03*
X1235039Y46914D03*
X1241732Y54957D03*
X1235039D03*
X1251771Y54799D03*
X1248425Y54857D03*
X1251771Y46957D03*
X1258464D03*
Y54799D03*
X1261811Y46957D03*
Y54799D03*
X1255118D03*
Y46957D03*
X1304940Y32350D03*
X1292692Y1008D03*
X1296908Y36900D03*
X1304500Y40066D03*
X973795Y499793D03*
X970669Y529014D03*
Y518157D03*
X974015Y515364D03*
Y529014D03*
Y509999D03*
X963976Y518057D03*
X967322Y510114D03*
X970942Y533100D03*
X970731Y552000D03*
X970942Y570900D03*
X970731Y589800D03*
X974015Y536957D03*
X970669Y555857D03*
Y566814D03*
X974015Y555857D03*
Y566814D03*
Y547914D03*
Y574757D03*
X963976Y566814D03*
Y555857D03*
X974015Y585714D03*
X960629D03*
X967322Y536957D03*
Y574757D03*
Y547914D03*
Y585714D03*
X970669Y593657D03*
Y607292D03*
X974015Y593657D03*
Y604499D03*
Y609864D03*
X963976Y607292D03*
X960629Y609864D03*
X963976Y593657D03*
X967322Y609864D03*
X995206Y359260D03*
X998586Y376809D03*
X991826Y388509D03*
X995206Y390460D03*
X991826Y376809D03*
X1001965Y359260D03*
X1008725D03*
X1015485D03*
X1022245D03*
X1029005D03*
X1032385Y388509D03*
Y376809D03*
X1005345D03*
Y388509D03*
X1001965Y386560D03*
X1025625Y376809D03*
Y388509D03*
X1018865Y376809D03*
X1012105D03*
X1018865Y388509D03*
X1012105D03*
X991826Y384609D03*
X991500Y396301D03*
X1022245Y390460D03*
X995206Y386560D03*
X1022245D03*
X998586Y388509D03*
X991826Y380709D03*
X1000800Y402800D03*
X995206Y378760D03*
X998586Y380709D03*
X1025625Y372909D03*
X1018865Y384609D03*
X995206Y367060D03*
X998586Y372909D03*
X991826D03*
X1018865D03*
X1012105D03*
X1022245Y378760D03*
X1012105Y380709D03*
X1022245Y374860D03*
X1015485D03*
X1025625Y380709D03*
X1015485Y378760D03*
X1032385Y384609D03*
X1035765Y374860D03*
Y386560D03*
X1029005D03*
X1018865Y380709D03*
X1001965Y378760D03*
Y374860D03*
X1032385Y380709D03*
Y372909D03*
X1029005Y378760D03*
Y374860D03*
X1008725Y386560D03*
X1012105Y384609D03*
X1008725Y378760D03*
X1005345Y380709D03*
X1008725Y374860D03*
X1005345Y372909D03*
X998586Y369010D03*
X1001965Y367060D03*
X1005345Y384609D03*
X1035765Y378760D03*
X1025625Y384609D03*
X995206Y355360D03*
X998586Y357309D03*
X1029005Y367060D03*
X1015485Y355360D03*
X998586Y361209D03*
X995206Y363160D03*
X991826Y357309D03*
Y369010D03*
Y361209D03*
X1018865Y369010D03*
X1012105D03*
X1018865Y361209D03*
X1012105D03*
X1022245Y367060D03*
X1015485D03*
X1022245Y363160D03*
X1015485D03*
X1032385Y369010D03*
X1025625Y361209D03*
X1018865Y357309D03*
X1001965Y363160D03*
X1025625Y357309D03*
X1035765Y367060D03*
X1022245Y355360D03*
X1029005Y363160D03*
X1008725Y355360D03*
X1012105Y357309D03*
X1008725Y363160D03*
Y367060D03*
X1005345Y361209D03*
Y369010D03*
X1001965Y355360D03*
X1005345Y357309D03*
X1025625Y369010D03*
X998586Y384609D03*
X995206Y374860D03*
X1013500Y529200D03*
X1034200Y506956D03*
X1035750Y503006D03*
X977362Y512792D03*
X976530Y497170D03*
X984055Y512792D03*
X980708Y529014D03*
Y515364D03*
X1004133Y529022D03*
X1004134Y518157D03*
X1003915Y512792D03*
X1000787Y515364D03*
Y529022D03*
X997441Y512792D03*
X994094Y510114D03*
Y529022D03*
Y515364D03*
X987401Y509999D03*
X990748Y529022D03*
Y518157D03*
X984055D03*
X984054Y529014D03*
X983900Y533100D03*
Y552000D03*
Y570900D03*
Y589800D03*
X1026500Y577500D03*
X977362Y536957D03*
X984055D03*
X1004134D03*
X997441D03*
X994094D03*
X987401D03*
X977362Y547914D03*
Y574757D03*
X1014173Y566814D03*
Y555842D03*
Y574742D03*
X1010826Y566814D03*
X1010928Y555842D03*
X1010826Y574742D03*
X984054Y547914D03*
X984055Y574757D03*
X980708Y555857D03*
Y566814D03*
X1004134Y555857D03*
X1004133Y566822D03*
Y547922D03*
X1004134Y574757D03*
X1000787Y555857D03*
Y566822D03*
X997441Y547922D03*
Y574757D03*
X994094Y547922D03*
Y574757D03*
Y555857D03*
Y566822D03*
X987401Y547914D03*
Y574757D03*
X990748Y555857D03*
Y566822D03*
X984055Y555857D03*
X984054Y566814D03*
X977362Y585714D03*
X984054D03*
X1004133Y585722D03*
X997441D03*
X994094D03*
X987401Y585714D03*
X1026500Y581000D03*
X1019800Y555800D03*
X1014173Y604614D03*
X1014919Y593642D03*
X1014173Y612242D03*
X1010826Y604614D03*
X1011572Y593642D03*
X1010826Y612242D03*
X980708Y604614D03*
Y593657D03*
X1004134D03*
Y607292D03*
X1000787Y604499D03*
Y593657D03*
X994094Y609864D03*
Y593657D03*
Y604614D03*
X987401Y609864D03*
X990748Y593657D03*
Y607292D03*
X984055D03*
Y593657D03*
X1020700Y604600D03*
X1039145Y388509D03*
X1045904D03*
X1052664D03*
X1039145Y376809D03*
X1045904D03*
X1052664D03*
X1060694Y374860D03*
X1045904Y384609D03*
X1042524Y386560D03*
X1039145Y384609D03*
X1049284Y390460D03*
X1045904Y380709D03*
X1049284Y378760D03*
X1045904Y369010D03*
X1039145Y372909D03*
X1052664Y380709D03*
X1049284Y374860D03*
X1042524Y378760D03*
Y374860D03*
X1039145Y380709D03*
X1045904Y372909D03*
X1049284Y367060D03*
X1042524D03*
X1052664Y372909D03*
Y369010D03*
X1039145D03*
X1060963Y370959D03*
X1052664Y396309D03*
X1060694Y394359D03*
Y390460D03*
X1049284Y386560D03*
X1060694D03*
Y382660D03*
Y378760D03*
X1048154Y402900D03*
X1052500Y400400D03*
X1054331Y529022D03*
X1054330Y515364D03*
X1050983Y512792D03*
X1087795Y510114D03*
X1084800Y499400D03*
X1064369Y518157D03*
X1081102Y515364D03*
X1094488D03*
Y510114D03*
X1047637Y529007D03*
Y515364D03*
X1054330Y509999D03*
X1077755Y512792D03*
X1064369D03*
X1071062Y518157D03*
X1071064Y529022D03*
X1057677Y529007D03*
X1057676Y518157D03*
X1084448Y512792D03*
X1074409Y515364D03*
X1087795D03*
X1044290Y512792D03*
X1061023Y510114D03*
X1044195Y529026D03*
X1057792Y552000D03*
Y533100D03*
Y570900D03*
Y589800D03*
X1070976Y552000D03*
Y533100D03*
X1084003Y532904D03*
X1083116Y552000D03*
X1098300Y553100D03*
X1098118Y549843D03*
X1070976Y570900D03*
X1070242Y589800D03*
X1083116Y570900D03*
X1083108Y589800D03*
X1097899Y574773D03*
X1097834Y569200D03*
X1071064Y547922D03*
Y585722D03*
X1050985Y536957D03*
X1087797D03*
X1094490D03*
X1054331D03*
X1077757D03*
X1064371D03*
X1084450D03*
X1044203Y537058D03*
X1054331Y555857D03*
Y566822D03*
X1050984Y547922D03*
X1050985Y574757D03*
X1087797Y547922D03*
Y574757D03*
X1064371Y566822D03*
X1081102Y566807D03*
X1094488Y566822D03*
X1094490Y574757D03*
X1064371Y555857D03*
X1081102Y555842D03*
X1094488Y555859D03*
Y547922D03*
X1047637Y555842D03*
Y566807D03*
X1054331Y547922D03*
Y574757D03*
X1077757Y547922D03*
Y574757D03*
X1064371Y547922D03*
Y574757D03*
X1071064Y555857D03*
Y566822D03*
X1057677Y555842D03*
Y566807D03*
X1084450Y547922D03*
Y574757D03*
X1074409Y566807D03*
X1087797Y566822D03*
X1074409Y555842D03*
X1087795Y555859D03*
X1044290Y550592D03*
X1044292Y574757D03*
X1050985Y585722D03*
X1087797D03*
X1094488D03*
X1054331D03*
X1077757D03*
X1064371D03*
X1084450D03*
X1044290Y588392D03*
X1061024Y536957D03*
Y574757D03*
Y547922D03*
Y585722D03*
X1044290Y569492D03*
X1097352Y607220D03*
X1054331Y593657D03*
X1054330Y604499D03*
X1087795Y609864D03*
X1064369Y607292D03*
X1081102Y604499D03*
X1094488Y604614D03*
Y609864D03*
X1064371Y593657D03*
X1081102Y593642D03*
X1094488Y593659D03*
X1047637Y604499D03*
Y593642D03*
X1054330Y609864D03*
X1071064Y593657D03*
X1071062Y607292D03*
X1057677Y593642D03*
X1057676Y607292D03*
X1074409Y604614D03*
X1087795D03*
X1074409Y593642D03*
X1087795Y593659D03*
X1061023Y609864D03*
X1044290Y607292D03*
X1107724Y547914D03*
X1101181D03*
X1104141Y568749D03*
X1101181Y585714D03*
X1107724D03*
X1107874Y574849D03*
X1110520Y568900D03*
X1101181Y574799D03*
X1137992Y547914D03*
X1144535D03*
X1131299D03*
X1124606D03*
X1134645Y568749D03*
X1137992Y585714D03*
X1144535D03*
X1140952Y568749D03*
X1137992Y574799D03*
X1144685Y574849D03*
X1147331Y568900D03*
X1131299Y585714D03*
X1124606D03*
X1131299Y574849D03*
X1127952Y568749D03*
X1124606Y574849D03*
X1107874Y555957D03*
X1110520Y572500D03*
X1107874Y566699D03*
X1131299Y555957D03*
X1134645Y572900D03*
X1131299Y566699D03*
X1101181Y555957D03*
X1104141Y572500D03*
X1101181Y566699D03*
X1124606Y555957D03*
X1127952Y572900D03*
X1124606Y566699D03*
X1147331Y572500D03*
X1144685Y555957D03*
Y566699D03*
X1140952Y572500D03*
X1137992Y555957D03*
Y566699D03*
X1110520Y606700D03*
X1104141Y606549D03*
X1147331Y606700D03*
X1134645Y606549D03*
X1140952D03*
X1127952D03*
X1110520Y610300D03*
X1107874Y593757D03*
Y604499D03*
X1134645Y610700D03*
X1131299Y593757D03*
Y604499D03*
X1101181Y593757D03*
X1104141Y610300D03*
X1101181Y604499D03*
X1124606Y593757D03*
X1127952Y610700D03*
X1124606Y604499D03*
X1147700Y611200D03*
X1144685Y593757D03*
Y604499D03*
X1137992Y593757D03*
Y604499D03*
X1161417Y547914D03*
X1168110D03*
X1174803D03*
Y574799D03*
X1161417Y574849D03*
X1171456Y568749D03*
X1168110Y585714D03*
X1161417D03*
X1168110Y574849D03*
X1164763Y568749D03*
X1174803Y585714D03*
X1177763Y568749D03*
X1181346Y547914D03*
X1198228D03*
X1204921D03*
X1211614D03*
X1218157D03*
X1181346Y585714D03*
X1181496Y574849D03*
X1220953Y568900D03*
X1218157Y585714D03*
X1218307Y574849D03*
X1208267Y568749D03*
X1214574D03*
X1211614Y574799D03*
Y585714D03*
X1184142Y568900D03*
X1198228Y585714D03*
Y574849D03*
X1204921Y585714D03*
Y574849D03*
X1201574Y568749D03*
X1171456Y572900D03*
X1168110Y555957D03*
Y566699D03*
X1164763Y572900D03*
X1161417Y555957D03*
Y566699D03*
X1184142Y572500D03*
X1181496Y555957D03*
Y566699D03*
X1208267Y572900D03*
X1204921Y555957D03*
Y566699D03*
X1177763Y572500D03*
X1174803Y555957D03*
Y566699D03*
X1201574Y572900D03*
X1198228Y555957D03*
Y566699D03*
X1218307Y555957D03*
X1220953Y572500D03*
X1218307Y566699D03*
X1211614Y555957D03*
X1214574Y572500D03*
X1214874Y550574D03*
X1211614Y566699D03*
X1214660Y588714D03*
X1171456Y606549D03*
X1164763D03*
X1177763D03*
X1220953Y606700D03*
X1214574Y606549D03*
X1208267D03*
X1184142Y606700D03*
X1201574Y606549D03*
X1168110Y593757D03*
X1171456Y610700D03*
X1168110Y604499D03*
X1161417Y593757D03*
X1164763Y610700D03*
X1161417Y604499D03*
X1181496Y593757D03*
X1184142Y610300D03*
X1181496Y604499D03*
X1208267Y610700D03*
X1204921Y593757D03*
Y604499D03*
X1174803Y593757D03*
X1177763Y610300D03*
X1174803Y604499D03*
X1198228Y593757D03*
X1201574Y610700D03*
X1198228Y604499D03*
X1218307Y593757D03*
X1220953Y610300D03*
X1218307Y604499D03*
X1211614Y593757D03*
X1214574Y610300D03*
X1211614Y604499D03*
X1241732Y547914D03*
X1248425Y547957D03*
X1241732Y574849D03*
Y585714D03*
X1238385Y568749D03*
X1268500Y555800D03*
X1248425Y585757D03*
Y574849D03*
Y566699D03*
X1245078Y568749D03*
X1235039Y547914D03*
Y585714D03*
Y574849D03*
X1241732Y555957D03*
X1245078Y572900D03*
X1241732Y566699D03*
X1238385Y572900D03*
X1235039Y555957D03*
Y566699D03*
X1265157Y547957D03*
X1261811D03*
X1258464D03*
X1251771D03*
X1265157Y585757D03*
X1261811D03*
X1258464D03*
X1251771D03*
X1261811Y555799D03*
X1258464D03*
X1251771D03*
X1248425Y555857D03*
X1251771Y566699D03*
Y574857D03*
X1261811D03*
X1258464D03*
X1261811Y566699D03*
X1258464D03*
X1273200Y582200D03*
X1255120Y555144D03*
Y574834D03*
X1265157Y566676D03*
Y555799D03*
X1238385Y606549D03*
X1251771Y604499D03*
X1248425D03*
X1245078Y606549D03*
X1251771Y593599D03*
X1241732Y593757D03*
X1245078Y610700D03*
X1241732Y604499D03*
X1238385Y610700D03*
X1235039Y593757D03*
Y604499D03*
X1258464Y593599D03*
X1261811D03*
X1248425Y593657D03*
X1258464Y604499D03*
X1255120Y593600D03*
G54D49*
X94683Y31978D03*
Y13078D03*
Y69778D03*
Y50878D03*
Y570755D03*
Y589679D03*
Y551879D03*
X1287403Y-5822D03*
Y31978D03*
Y13078D03*
Y50878D03*
Y551879D03*
%LPD*%
G75*
G54D10*
X-17936Y-49379D03*
Y-53779D03*
Y-44979D03*
Y-40579D03*
X-18079Y-35764D03*
Y-58764D03*
X-14186Y196989D03*
Y199989D03*
X-14839Y445588D03*
X-14753Y448601D03*
X-17179Y643156D03*
X-17194Y638753D03*
X-17179Y647556D03*
Y660756D03*
Y651956D03*
Y656356D03*
X-13636Y-40479D03*
Y-44879D03*
Y-53679D03*
X-9079Y-50164D03*
X-4679D03*
X-279D03*
X-9079Y-54264D03*
X-4679D03*
X-279D03*
X22964Y-40379D03*
Y-44779D03*
Y-53579D03*
Y-49179D03*
X18964Y-53579D03*
Y-49179D03*
X13964Y-53579D03*
Y-49179D03*
X8964Y-40379D03*
Y-44779D03*
Y-53579D03*
Y-49179D03*
X3964Y-40379D03*
Y-44779D03*
Y-53579D03*
Y-49179D03*
X25921Y-35764D03*
X30321D03*
X43521D03*
X39121D03*
X34721D03*
X8321D03*
X12721D03*
X21521D03*
X17121D03*
X-13679D03*
X-9279D03*
X3921D03*
X-4879D03*
X-479D03*
X17121Y-58764D03*
X21521D03*
X12721D03*
X8321D03*
X34721D03*
X39121D03*
X43521D03*
X30321D03*
X25921D03*
X-479D03*
X-13679D03*
X-4879D03*
X3921D03*
X-13636Y-49279D03*
X-9279Y-58764D03*
X875Y211336D03*
X6074Y211293D03*
X3474Y211263D03*
X875Y208352D03*
X36200Y208600D03*
X33200D03*
X20700D03*
X17700Y211600D03*
X20700D03*
X17700Y208600D03*
X23700Y211600D03*
Y208600D03*
X33200Y211600D03*
X30200D03*
Y208600D03*
X36200Y211600D03*
X6074Y208321D03*
X3474Y208263D03*
X5500Y218500D03*
X-5300Y200191D03*
X-7900D03*
X-2700Y200202D03*
X-11586Y196989D03*
Y199989D03*
X-2600Y232300D03*
X-5246Y232351D03*
X-7846D03*
X20500Y221000D03*
Y224000D03*
X17500Y221000D03*
Y224000D03*
X23500D03*
Y221000D03*
X33300Y224000D03*
Y221000D03*
X30300D03*
Y224000D03*
X36300D03*
Y221000D03*
X-14129Y235221D03*
X-11484Y235215D03*
Y232215D03*
X-14084D03*
X2678Y221018D03*
X5277Y221110D03*
X5173Y224042D03*
X2574Y223963D03*
X-26Y223982D03*
X-11652Y445530D03*
Y448530D03*
X22421Y647556D03*
X26821D03*
X31221D03*
X18021D03*
Y643156D03*
X31221D03*
X26821D03*
X22421D03*
X18006Y638753D03*
X9221Y647556D03*
X13621D03*
Y643156D03*
X9221D03*
X4821D03*
Y647556D03*
X22406Y638753D03*
X26806D03*
X31206D03*
X-12794D03*
X-12779Y647556D03*
Y643156D03*
X40006Y638753D03*
X44406D03*
X35606D03*
X35621Y647556D03*
Y643156D03*
X-9599Y610630D03*
X-3301Y619643D03*
Y601615D03*
X4549Y620682D03*
X4548Y600577D03*
X13801Y624130D03*
Y597130D03*
X23360Y620172D03*
X23352Y601079D03*
X27301Y610630D03*
X18021Y660756D03*
X35621Y656356D03*
X26821Y660756D03*
X18021Y651956D03*
X31221D03*
X22421Y660756D03*
X26821Y651956D03*
X22421D03*
X4821D03*
X13621D03*
X9221D03*
X-8379Y660756D03*
X4821Y656356D03*
X9221D03*
X13621D03*
X-3979D03*
X421D03*
X13621Y660756D03*
X-3979D03*
X421D03*
X4821D03*
X-12779Y651956D03*
X22421Y656356D03*
X26821D03*
X31221D03*
X18021D03*
X-8379D03*
X-12779D03*
X31221Y660756D03*
X35621Y651956D03*
Y660756D03*
X44421D03*
X40021D03*
X-12779D03*
X9221D03*
X107921Y-58764D03*
X102921D03*
X97921D03*
X92921D03*
X87921D03*
X82921D03*
X77921D03*
X72921D03*
X67921D03*
X62921D03*
X57921D03*
X52921D03*
X47921Y-35764D03*
Y-58764D03*
X107921Y-35764D03*
X102921D03*
X97921D03*
X92921D03*
X87921D03*
X82921D03*
X77921D03*
X72921D03*
X67921D03*
X62921D03*
X57921D03*
X52921D03*
X96249Y204722D03*
X64700Y210100D03*
Y212800D03*
X64778Y218062D03*
X58000Y206500D03*
X56900Y197800D03*
X93870Y199131D03*
X97730Y188584D03*
X58200Y230400D03*
Y233400D03*
X55600Y230400D03*
X53000Y230300D03*
Y233300D03*
X55600Y233400D03*
X58200Y227400D03*
X53000Y227300D03*
X55600Y227400D03*
X58200Y239400D03*
X53000Y239300D03*
X55600Y239400D03*
X58200Y236400D03*
X55600D03*
X53000Y236300D03*
X71500Y263300D03*
X68800D03*
X53004Y244632D03*
X55275Y245900D03*
X57875D03*
X57457Y248537D03*
Y251237D03*
X57600Y262800D03*
X57500Y260200D03*
X62800Y265500D03*
X71500Y266000D03*
X65500Y265500D03*
X68800Y266000D03*
X60000Y265500D03*
X76540Y397355D03*
X81900Y398300D03*
X79140Y397355D03*
X98149Y399769D03*
X102456Y393756D03*
X76052Y420935D03*
X78000Y423100D03*
X80100Y425000D03*
X81500Y427400D03*
X79700Y409700D03*
X77400Y407800D03*
X81500Y412100D03*
X84913Y434471D03*
X87013Y436371D03*
X107571Y406291D03*
X48806Y638753D03*
X75206D03*
X106006D03*
X70806D03*
X53206D03*
X66406D03*
X92806D03*
X97206D03*
X101606D03*
X57606D03*
X62006D03*
X79606D03*
X84006D03*
X88406D03*
X53221Y660756D03*
X101621D03*
X97221D03*
X92821D03*
X106021D03*
X48821D03*
X70821D03*
X66421D03*
X62021D03*
X57621D03*
X75221D03*
X88421D03*
X84021D03*
X79621D03*
X167921Y-58764D03*
X162921D03*
X157921D03*
X152921D03*
X147921D03*
X142921D03*
X137921D03*
X132921D03*
X127921D03*
X122921D03*
X117921D03*
X112921D03*
X162921Y-35764D03*
X157921D03*
X152921D03*
X147921D03*
X142921D03*
X137921D03*
X132921D03*
X127921D03*
X122921D03*
X117921D03*
X112921D03*
X167921D03*
X166000Y212900D03*
X168600D03*
X164300Y207870D03*
X160800Y212900D03*
X163400D03*
X157800Y207300D03*
X161216Y209533D03*
Y206933D03*
X154500Y205500D03*
X150600Y212900D03*
X151000Y205500D03*
X140889Y211972D03*
X137615Y212039D03*
X143900Y204600D03*
X147500Y205500D03*
X137300Y204500D03*
X140200Y204400D03*
X153200Y212900D03*
X122044Y162340D03*
X139815Y268974D03*
X137900Y272800D03*
X139800Y237000D03*
X165825Y239543D03*
X168425Y236943D03*
Y239543D03*
X165825Y236943D03*
X163225D03*
X152825D03*
X145025D03*
X147625D03*
X150225D03*
X142425D03*
X163225Y239543D03*
X158025Y236943D03*
X155425D03*
X160625D03*
X142371Y244384D03*
X142466Y268982D03*
X142700Y276200D03*
X136729Y276386D03*
X139683Y276174D03*
X163225Y242143D03*
X168425Y244743D03*
X165825D03*
X163225D03*
X168425Y242143D03*
X165825D03*
X150700Y276800D03*
X169150Y259470D03*
Y255470D03*
X157633Y268727D03*
X162833D03*
X160233D03*
X165433D03*
X168033Y271327D03*
X162833Y276527D03*
Y273927D03*
Y271327D03*
X165433Y276527D03*
Y273927D03*
Y271327D03*
X159983Y276507D03*
X168033Y276527D03*
Y273927D03*
Y268727D03*
X153300Y276800D03*
X139866Y333016D03*
X160233Y306257D03*
Y308857D03*
Y303657D03*
X157518Y335391D03*
X157745Y332800D03*
X139900Y302400D03*
X142433Y301057D03*
X147633D03*
X150233D03*
X145033D03*
X145200Y341300D03*
X148200D03*
X142465Y332940D03*
X152833Y301057D03*
X163233Y306257D03*
Y308857D03*
X168433Y306257D03*
Y308857D03*
Y301057D03*
X165833D03*
X163233D03*
X160633D03*
X158033D03*
X155433D03*
X169150Y287600D03*
Y291600D03*
X165833Y306257D03*
X163233Y303657D03*
X168433D03*
X165833D03*
Y308857D03*
X151000Y341300D03*
X169150Y323600D03*
Y319600D03*
X160501Y332965D03*
X160274Y335556D03*
X165701Y338165D03*
Y335565D03*
X163101Y332965D03*
X168301D03*
X165701D03*
X163101Y335565D03*
X168301Y340765D03*
Y338165D03*
Y335565D03*
X163101Y338165D03*
Y340765D03*
X165701D03*
X154200Y341100D03*
X139767Y364883D03*
X147833Y364457D03*
X142421Y364908D03*
X145033Y364457D03*
X142863Y402829D03*
X140219Y402894D03*
X137619Y402900D03*
X134992D03*
X142818Y400163D03*
X143073Y397194D03*
X140475Y397310D03*
X140218Y400163D03*
X137529Y400296D03*
X134929D03*
X114084Y399937D03*
X122840Y400827D03*
X150633Y364457D03*
X167433Y369657D03*
X169150Y355600D03*
Y351600D03*
X167700Y363900D03*
X161833Y364457D03*
X164633D03*
X159033D03*
X156233D03*
X153433D03*
X164633Y369657D03*
X161833D03*
X161933Y372357D03*
X164733D03*
X167533D03*
X166340Y374785D03*
X167670Y383993D03*
Y387993D03*
X130613Y429647D03*
X123648Y425041D03*
X125328Y427269D03*
X127932Y428571D03*
X110519Y410307D03*
X110199Y413852D03*
X110406Y638753D03*
X145606D03*
X141206D03*
X136806D03*
X132406D03*
X158806D03*
X119206D03*
X123606D03*
X114806D03*
X128006D03*
X163206D03*
X154406D03*
X167606D03*
X150006D03*
X132421Y660756D03*
X145621D03*
X141221D03*
X136821D03*
X123621D03*
X114821D03*
X128021D03*
X110421D03*
X119221D03*
X150021D03*
X167621D03*
X163221D03*
X158821D03*
X154421D03*
X182921Y-58764D03*
X177921D03*
X172921D03*
X227921Y-35764D03*
X222921D03*
X217921D03*
X212921D03*
X207921D03*
X202921D03*
X197921D03*
X192921D03*
X187921D03*
X182921D03*
X177921D03*
X227921Y-58764D03*
X222921D03*
X217921D03*
X212921D03*
X207921D03*
X202921D03*
X197921D03*
X192921D03*
X187921D03*
X172921Y-35764D03*
X211606Y638753D03*
X224806D03*
X220406D03*
X216006D03*
X189606D03*
X198406D03*
X202806D03*
X207206D03*
X176406D03*
X172006D03*
X185206D03*
X180806D03*
X194006D03*
X226500Y649900D03*
X229206Y638753D03*
X224821Y660756D03*
X220421D03*
X198421D03*
X211621D03*
X189621D03*
X202821D03*
X207221D03*
X194021D03*
X185221D03*
X172021D03*
X176421D03*
X180821D03*
X229221D03*
X216021D03*
X292921Y-35764D03*
X287921D03*
X282921D03*
X277921D03*
X272921D03*
X267921D03*
X262921D03*
X257921D03*
X252921D03*
X247921D03*
X242921D03*
X237921D03*
X232921D03*
X292921Y-58764D03*
X287921D03*
X282921D03*
X277921D03*
X272921D03*
X267921D03*
X262921D03*
X257921D03*
X252921D03*
X247921D03*
X242921D03*
X237921D03*
X232921D03*
X290806Y638753D03*
X268806D03*
X273206D03*
X277606D03*
X282006D03*
X260006D03*
X264406D03*
X255606D03*
X251206D03*
X286406D03*
X242406D03*
X246806D03*
X233606D03*
X238006D03*
X286421Y660756D03*
X268821D03*
X282021D03*
X273221D03*
X277621D03*
X264421D03*
X251221D03*
X255621D03*
X260021D03*
X246821D03*
X242421D03*
X238021D03*
X233621D03*
X290821D03*
X352921Y-58764D03*
Y-35764D03*
X347921Y-58764D03*
Y-35764D03*
X342921Y-58764D03*
Y-35764D03*
X337921Y-58764D03*
Y-35764D03*
X332921Y-58764D03*
Y-35764D03*
X327921Y-58764D03*
Y-35764D03*
X322921Y-58764D03*
Y-35764D03*
X317921Y-58764D03*
Y-35764D03*
X312921Y-58764D03*
X307921D03*
Y-35764D03*
X302921Y-58764D03*
Y-35764D03*
X297921D03*
Y-58764D03*
X312921Y-35764D03*
X330406Y638753D03*
X348006D03*
X326006D03*
X312806D03*
X317206D03*
X321606D03*
X352406D03*
X295206D03*
X299606D03*
X308406D03*
X304006D03*
X334806D03*
X339206D03*
X343606D03*
X312821Y660756D03*
X317221D03*
X308421D03*
X304021D03*
X352421D03*
X295221D03*
X326021D03*
X321621D03*
X339221D03*
X299621D03*
X334821D03*
X330421D03*
X343621D03*
X348021D03*
X392921Y-35764D03*
X387921Y-58764D03*
Y-35764D03*
X382921Y-58764D03*
Y-35764D03*
X377921Y-58764D03*
Y-35764D03*
X372921Y-58764D03*
Y-35764D03*
X367921Y-58764D03*
Y-35764D03*
X362921Y-58764D03*
Y-35764D03*
X357921Y-58764D03*
Y-35764D03*
X392921Y-58764D03*
X402921Y-35764D03*
X397921Y-58764D03*
Y-35764D03*
X412921Y-58764D03*
Y-35764D03*
X407921Y-58764D03*
Y-35764D03*
X402921Y-58764D03*
X404594Y264899D03*
X407594D03*
X411188D03*
X414188D03*
X417190D03*
X380885Y273876D03*
Y270876D03*
X382494Y278904D03*
X371094D03*
X378294D03*
X375294D03*
X368094D03*
X389694D03*
X392694D03*
X385945Y278480D03*
X407094Y278910D03*
X414207D03*
X411288D03*
X404094D03*
X400842Y278914D03*
X368094Y295904D03*
X371094D03*
X385494D03*
X375294D03*
X378294D03*
X382494D03*
X389694D03*
X392694D03*
X365693Y311893D03*
X391144Y324173D03*
X388394D03*
X385494D03*
X411294Y295904D03*
X414294D03*
X407094D03*
X404094D03*
X399894D03*
X396894D03*
Y324173D03*
X408894D03*
X411894D03*
X405894D03*
X414894D03*
X393894D03*
X402894D03*
X399894D03*
X383206Y638753D03*
X387606D03*
X392006D03*
X396406D03*
X400806D03*
X405206D03*
X409606D03*
X414006D03*
X370006D03*
X365606D03*
X374406D03*
X378806D03*
X356806D03*
X361206D03*
X374421Y660756D03*
X387621D03*
X383221D03*
X400821D03*
X396421D03*
X392021D03*
X405221D03*
X409621D03*
X414021D03*
X361221D03*
X365621D03*
X356821D03*
X370021D03*
X378821D03*
X477921Y-58764D03*
Y-35764D03*
X472921Y-58764D03*
Y-35764D03*
X467921Y-58764D03*
Y-35764D03*
X462921Y-58764D03*
Y-35764D03*
X457921Y-58764D03*
Y-35764D03*
X452921Y-58764D03*
Y-35764D03*
X447921Y-58764D03*
Y-35764D03*
X442921Y-58764D03*
Y-35764D03*
X437921Y-58764D03*
Y-35764D03*
X432921Y-58764D03*
X422921Y-35764D03*
X417921Y-58764D03*
Y-35764D03*
X432921D03*
X427921Y-58764D03*
Y-35764D03*
X422921Y-58764D03*
X425911Y264710D03*
X420188Y264899D03*
X423092Y264697D03*
X432643Y264508D03*
X418523Y278910D03*
X428694D03*
X432894D03*
X425694D03*
X435894Y278938D03*
X443094Y278904D03*
X440094D03*
X421523Y278944D03*
X451675Y291739D03*
X449148Y292841D03*
X446209Y292842D03*
X451816Y295904D03*
X435894D03*
X418494D03*
X443094D03*
X440094D03*
X446383Y295841D03*
X428694Y295904D03*
X432894D03*
X425694D03*
X421494D03*
X418494Y324173D03*
X451267Y324476D03*
X448694Y323949D03*
X421494Y324173D03*
X446094Y323904D03*
X425694Y324173D03*
X428694D03*
X432894D03*
X435894D03*
X455226Y291686D03*
X454922Y295841D03*
X466806Y638753D03*
X462406D03*
X475606D03*
X471206D03*
X418406D03*
X422806D03*
X427206D03*
X440406D03*
X436006D03*
X431606D03*
X449206D03*
X458006D03*
X453606D03*
X444806D03*
X458021Y660756D03*
X449221D03*
X462421D03*
X466821D03*
X471221D03*
X418421D03*
X475621D03*
X453621D03*
X422821D03*
X427221D03*
X440421D03*
X431621D03*
X436021D03*
X444821D03*
X537921Y-58764D03*
Y-35764D03*
X532921Y-58764D03*
Y-35764D03*
X527921Y-58764D03*
Y-35764D03*
X522921Y-58764D03*
Y-35764D03*
X517921Y-58764D03*
Y-35764D03*
X512921Y-58764D03*
Y-35764D03*
X507921Y-58764D03*
Y-35764D03*
X502921Y-58764D03*
Y-35764D03*
X497921Y-58764D03*
Y-35764D03*
X492921Y-58764D03*
Y-35764D03*
X487921Y-58764D03*
Y-35764D03*
X482921Y-58764D03*
Y-35764D03*
X480006Y638753D03*
X484406D03*
X488806D03*
X493206D03*
X497606D03*
X510806D03*
X537206D03*
X519606D03*
X524006D03*
X532806D03*
X528406D03*
X515206D03*
X502006D03*
X506406D03*
X524021Y660756D03*
X480021D03*
X484421D03*
X497621D03*
X493221D03*
X488821D03*
X519621D03*
X532821D03*
X537221D03*
X528421D03*
X515221D03*
X510821D03*
X506421D03*
X502021D03*
X597921Y-35764D03*
Y-58764D03*
X592921Y-35764D03*
Y-58764D03*
X587921Y-35764D03*
Y-58764D03*
X582921Y-35764D03*
Y-58764D03*
X577921Y-35764D03*
Y-58764D03*
X572921Y-35764D03*
Y-58764D03*
X567921Y-35764D03*
Y-58764D03*
X562921Y-35764D03*
Y-58764D03*
X557921Y-35764D03*
Y-58764D03*
X552921Y-35764D03*
Y-58764D03*
X547921D03*
Y-35764D03*
X542921Y-58764D03*
Y-35764D03*
X590006Y638753D03*
X572406D03*
X559206D03*
X568006D03*
X563606D03*
X550406D03*
X581206D03*
X585606D03*
X576806D03*
X598806D03*
X594406D03*
X601500Y649500D03*
X554806Y638753D03*
X541606D03*
X546006D03*
X559221Y660756D03*
X546021D03*
X554821D03*
X598821D03*
X572421D03*
X568021D03*
X563621D03*
X585621D03*
X541621D03*
X594421D03*
X576821D03*
X590021D03*
X581221D03*
X550421D03*
X637921Y-58764D03*
X632921Y-35764D03*
Y-58764D03*
X627921Y-35764D03*
Y-58764D03*
X622921Y-35764D03*
Y-58764D03*
X617921Y-35764D03*
Y-58764D03*
X612921Y-35764D03*
Y-58764D03*
X607921Y-35764D03*
Y-58764D03*
X602921Y-35764D03*
Y-58764D03*
X652921Y-35764D03*
Y-58764D03*
X647921Y-35764D03*
Y-58764D03*
X642921Y-35764D03*
Y-58764D03*
X637921Y-35764D03*
X662921D03*
Y-58764D03*
X657921Y-35764D03*
Y-58764D03*
X638406Y638753D03*
X634006D03*
X642806D03*
X629606D03*
X616406D03*
X612006D03*
X603206D03*
X625206D03*
X651606D03*
X647206D03*
X660406D03*
X620806D03*
X656006D03*
X607606D03*
X607621Y660756D03*
X638421D03*
X647221D03*
X616421D03*
X634021D03*
X612021D03*
X620821D03*
X625221D03*
X629621D03*
X642821D03*
X603221D03*
X656021D03*
X660421D03*
X651621D03*
X692921Y-58764D03*
X687921Y-35764D03*
Y-58764D03*
X682921Y-35764D03*
Y-58764D03*
X677921Y-35764D03*
Y-58764D03*
X672921Y-35764D03*
Y-58764D03*
X667921Y-35764D03*
Y-58764D03*
X697921Y-35764D03*
Y-58764D03*
X692921Y-35764D03*
X722921D03*
Y-58764D03*
X717921Y-35764D03*
Y-58764D03*
X712921Y-35764D03*
Y-58764D03*
X707921Y-35764D03*
Y-58764D03*
X702921Y-35764D03*
Y-58764D03*
X704466Y-7874D03*
X690966Y-21374D03*
X700525Y1668D03*
X700517Y-17425D03*
X681713Y-17927D03*
X690966Y5626D03*
X681714Y2178D03*
X673864Y-16889D03*
X667566Y-7874D03*
X673864Y1139D03*
X695606Y638753D03*
X673606D03*
X708806D03*
X704406D03*
X700006D03*
X722006D03*
X717606D03*
X713206D03*
X664806D03*
X669206D03*
X686806D03*
X682406D03*
X678006D03*
X691206D03*
X690966Y624130D03*
Y597130D03*
X700525Y620172D03*
X700517Y601079D03*
X704466Y610630D03*
X667566D03*
X673864Y619643D03*
Y601615D03*
X681714Y620682D03*
X681713Y600577D03*
X664821Y660756D03*
X695621D03*
X708821D03*
X700021D03*
X704421D03*
X669221D03*
X686821D03*
X691221D03*
X678021D03*
X673621D03*
X682421D03*
X722021D03*
X717621D03*
X713221D03*
X777921Y-58764D03*
X772921Y-35764D03*
Y-58764D03*
X767921Y-35764D03*
Y-58764D03*
X762921Y-35764D03*
Y-58764D03*
X757921Y-35764D03*
Y-58764D03*
X752921Y-35764D03*
Y-58764D03*
X787921Y-35764D03*
Y-58764D03*
X782921Y-35764D03*
Y-58764D03*
X777921Y-35764D03*
X747921D03*
Y-58764D03*
X742921Y-35764D03*
Y-58764D03*
X737921Y-35764D03*
Y-58764D03*
X732921Y-35764D03*
Y-58764D03*
X727921Y-35764D03*
Y-58764D03*
X786674Y211463D03*
X785920Y204763D03*
X786300Y207400D03*
X787200Y244200D03*
Y271900D03*
X787100Y241100D03*
X773419Y270414D03*
X787200Y276400D03*
X787100Y303900D03*
X753098Y338316D03*
X744698Y332816D03*
X787000Y308300D03*
X787400Y340400D03*
X741774Y376463D03*
X785400Y372400D03*
X757500Y374000D03*
X770406Y638753D03*
X779206D03*
X774806D03*
X730806D03*
X726406D03*
X739606D03*
X735206D03*
X748406D03*
X744006D03*
X766006D03*
X761606D03*
X757206D03*
X752806D03*
X783606D03*
X744021Y660756D03*
X735221D03*
X779221D03*
X770421D03*
X774821D03*
X726421D03*
X730821D03*
X739621D03*
X748421D03*
X783621D03*
X757221D03*
X761621D03*
X752821D03*
X766021D03*
X842921Y-35764D03*
X837921Y-58764D03*
Y-35764D03*
X832921Y-58764D03*
X847921D03*
Y-35764D03*
X842921Y-58764D03*
X832921Y-35764D03*
X827921Y-58764D03*
Y-35764D03*
X822921Y-58764D03*
Y-35764D03*
X817921Y-58764D03*
Y-35764D03*
X812921Y-58764D03*
Y-35764D03*
X807921Y-58764D03*
Y-35764D03*
X802921Y-58764D03*
Y-35764D03*
X797921D03*
Y-58764D03*
X792921Y-35764D03*
Y-58764D03*
X816900Y216300D03*
X816874Y212863D03*
X814274D03*
X811674D03*
X808818Y211179D03*
X808618Y208579D03*
X803200Y213100D03*
X800600D03*
X794474Y211463D03*
X791874D03*
X789274D03*
X788522Y204343D03*
X791122Y204339D03*
X789432Y236947D03*
X789400Y273700D03*
X811983Y244843D03*
Y242243D03*
X814583Y239643D03*
X815432Y237000D03*
X814583Y244843D03*
Y242243D03*
X812832Y237000D03*
X811983Y239643D03*
X802432Y237000D03*
X799832D03*
X792032D03*
X794632D03*
X810232D03*
X797232D03*
X805032D03*
X807632D03*
X791000Y244400D03*
X793600D03*
X816800Y234300D03*
X816900Y230900D03*
X817000Y252500D03*
X789800Y276400D03*
X792400D03*
X801991Y276557D03*
X804591D03*
X792191Y269101D03*
X789591D03*
X814891Y271657D03*
Y274257D03*
Y276857D03*
Y269057D03*
X812291D03*
Y274257D03*
Y276857D03*
Y271657D03*
X817000Y255100D03*
Y257700D03*
X817491Y276857D03*
Y274257D03*
Y271657D03*
Y269057D03*
X817183Y242243D03*
Y239643D03*
Y244843D03*
X818032Y237000D03*
X788600Y306100D03*
X789500Y301200D03*
X797300D03*
X799900D03*
X810300D03*
X802500D03*
X812900D03*
X807700D03*
X805100D03*
X815500D03*
X811991Y308957D03*
Y306357D03*
Y303757D03*
X814591Y306357D03*
Y308957D03*
Y303757D03*
X792900Y308400D03*
X789900D03*
X794700Y301200D03*
X792100D03*
X793000Y340400D03*
X790300Y340300D03*
X816991Y337357D03*
Y334757D03*
Y339957D03*
X814391D03*
Y337357D03*
Y334757D03*
X811791Y337357D03*
Y339957D03*
Y334757D03*
X791879Y332798D03*
X794600Y332600D03*
X816938Y319888D03*
Y323888D03*
X817100Y317000D03*
X818100Y301200D03*
X817191Y303757D03*
Y306357D03*
Y308957D03*
X789860Y364947D03*
X816591Y369857D03*
Y372457D03*
X811391Y369857D03*
X813991D03*
Y372457D03*
X811391D03*
X790900Y372300D03*
X788300Y372400D03*
X802759Y364575D03*
X816672Y358809D03*
X795310Y364721D03*
X816593Y356210D03*
X807959Y364575D03*
X805359D03*
X810559D03*
X815759D03*
X813159D03*
X816900Y361400D03*
X792610Y364821D03*
X816591Y375057D03*
X792238Y396753D03*
X789600Y396809D03*
X811515Y397289D03*
X808915D03*
X813648Y395557D03*
X815472Y390442D03*
X814877Y393138D03*
X792000Y399409D03*
X789400D03*
X849606Y638753D03*
X836406D03*
X832006D03*
X796806D03*
X801206D03*
X792406D03*
X827606D03*
X818806D03*
X823206D03*
X810006D03*
X788006D03*
X845206D03*
X814406D03*
X805606D03*
X840806D03*
X849621Y660756D03*
X832021D03*
X810021D03*
X818821D03*
X836421D03*
X788021D03*
X814421D03*
X801221D03*
X805621D03*
X823221D03*
X827621D03*
X840821D03*
X796821D03*
X792421D03*
X845221D03*
X907921Y-58764D03*
Y-35764D03*
X902921Y-58764D03*
Y-35764D03*
X897921Y-58764D03*
Y-35764D03*
X892921Y-58764D03*
Y-35764D03*
X887921Y-58764D03*
Y-35764D03*
X882921Y-58764D03*
Y-35764D03*
X877921Y-58764D03*
Y-35764D03*
X872921Y-58764D03*
Y-35764D03*
X867921Y-58764D03*
Y-35764D03*
X862921Y-58764D03*
Y-35764D03*
X857921Y-58764D03*
Y-35764D03*
X852921Y-58764D03*
Y-35764D03*
X858406Y638753D03*
X854006D03*
X884806D03*
X880406D03*
X876006D03*
X871606D03*
X867206D03*
X911206D03*
X906806D03*
X889206D03*
X898006D03*
X902406D03*
X893606D03*
X862806D03*
X854021Y660756D03*
X858421D03*
X862821D03*
X898021D03*
X902421D03*
X871621D03*
X884821D03*
X893621D03*
X867221D03*
X889221D03*
X911221D03*
X906821D03*
X880421D03*
X876021D03*
X937921Y-35764D03*
X932921Y-58764D03*
Y-35764D03*
X927921Y-58764D03*
Y-35764D03*
X922921Y-58764D03*
Y-35764D03*
X917921Y-58764D03*
Y-35764D03*
X912921Y-58764D03*
Y-35764D03*
X942921D03*
X967921D03*
X962921Y-58764D03*
Y-35764D03*
X957921Y-58764D03*
Y-35764D03*
X952921Y-58764D03*
Y-35764D03*
X947921Y-58764D03*
Y-35764D03*
X942921Y-58764D03*
X972921D03*
Y-35764D03*
X967921Y-58764D03*
X937921D03*
X924406Y638753D03*
X920006D03*
X915606D03*
X972806D03*
X968406D03*
X964006D03*
X917100Y649300D03*
X942006Y638753D03*
X937606D03*
X933206D03*
X928806D03*
X959606D03*
X955206D03*
X950806D03*
X946406D03*
X959621Y660756D03*
X964021D03*
X968421D03*
X972821D03*
X920021D03*
X915621D03*
X924421D03*
X946421D03*
X942021D03*
X937621D03*
X933221D03*
X928821D03*
X955221D03*
X950821D03*
X1002921Y-58764D03*
Y-35764D03*
X997921Y-58764D03*
Y-35764D03*
X992921Y-58764D03*
Y-35764D03*
X987921Y-58764D03*
Y-35764D03*
X982921Y-58764D03*
Y-35764D03*
X977921Y-58764D03*
Y-35764D03*
X1032921Y-58764D03*
Y-35764D03*
X1027921Y-58764D03*
Y-35764D03*
X1022921Y-58764D03*
Y-35764D03*
X1017921Y-58764D03*
Y-35764D03*
X1012921Y-58764D03*
Y-35764D03*
X1007921Y-58764D03*
Y-35764D03*
X1030489Y270889D03*
Y273889D03*
X1027902Y278904D03*
X1020702D03*
X1017702D03*
X1024902D03*
X1032102D03*
X1017567Y295859D03*
X1024767D03*
X1020567D03*
X1031967D03*
X1027767D03*
X1015293Y311955D03*
X1003606Y638753D03*
X1012406D03*
X977206D03*
X990406D03*
X986006D03*
X994806D03*
X1016806D03*
X1021206D03*
X981606D03*
X999206D03*
X1025606D03*
X1008006D03*
X1030006D03*
X1034406D03*
X999221Y660756D03*
X1034421D03*
X1030021D03*
X1008021D03*
X1012421D03*
X1003621D03*
X1016821D03*
X977221D03*
X981621D03*
X1021221D03*
X1025621D03*
X994821D03*
X986021D03*
X990421D03*
X1067921Y-58764D03*
Y-35764D03*
X1062921Y-58764D03*
Y-35764D03*
X1057921Y-58764D03*
Y-35764D03*
X1052921Y-58764D03*
Y-35764D03*
X1047921Y-58764D03*
Y-35764D03*
X1042921Y-58764D03*
Y-35764D03*
X1037921Y-58764D03*
Y-35764D03*
X1092921Y-58764D03*
Y-35764D03*
X1087921Y-58764D03*
Y-35764D03*
X1082921Y-58764D03*
Y-35764D03*
X1077921Y-58764D03*
Y-35764D03*
X1072921Y-58764D03*
Y-35764D03*
X1075865Y264766D03*
X1070300Y264900D03*
X1073200Y264991D03*
X1057202Y264899D03*
X1060402Y264799D03*
X1066300Y264700D03*
X1063402Y264799D03*
X1054202Y264899D03*
X1042302Y278904D03*
X1039302D03*
X1056602Y278910D03*
X1035814Y278775D03*
X1049867Y278999D03*
X1053459Y278910D03*
X1060958D03*
X1075302D03*
X1078302D03*
X1082330D03*
X1070926D03*
X1063652D03*
X1067783D03*
X1082432Y264620D03*
X1085518Y278910D03*
X1089702Y278904D03*
X1039167Y295859D03*
X1042167D03*
X1034967D03*
X1046367D03*
X1056567D03*
X1049367D03*
X1053567D03*
X1038720Y324174D03*
X1044220D03*
X1035820D03*
X1050220D03*
X1047220D03*
X1053220D03*
X1056220D03*
X1041470D03*
X1059220D03*
X1060767Y295859D03*
X1095756Y292841D03*
X1082367Y295859D03*
X1085367D03*
X1075167D03*
X1078167D03*
X1089567D03*
X1092567D03*
X1095567Y295841D03*
X1070967Y295859D03*
X1063767D03*
X1067967D03*
X1062220Y324174D03*
X1095402Y323904D03*
X1083220Y324174D03*
X1076020D03*
X1079020D03*
X1071820D03*
X1065220D03*
X1068820D03*
X1096006Y638753D03*
X1078406D03*
X1082806D03*
X1074006D03*
X1069606D03*
X1091606D03*
X1052006D03*
X1038806D03*
X1087206D03*
X1060806D03*
X1056406D03*
X1065206D03*
X1043206D03*
X1047606D03*
X1078421Y660756D03*
X1060821D03*
X1087221D03*
X1038821D03*
X1091621D03*
X1052021D03*
X1074021D03*
X1065221D03*
X1096021D03*
X1056421D03*
X1043221D03*
X1047621D03*
X1082821D03*
X1069621D03*
X1157921Y-58764D03*
Y-35764D03*
X1152921Y-58764D03*
Y-35764D03*
X1147921Y-58764D03*
Y-35764D03*
X1142921Y-58764D03*
Y-35764D03*
X1137921Y-58764D03*
Y-35764D03*
X1132921Y-58764D03*
Y-35764D03*
X1127921Y-58764D03*
Y-35764D03*
X1122921Y-58764D03*
Y-35764D03*
X1117921Y-58764D03*
Y-35764D03*
X1112921Y-58764D03*
Y-35764D03*
X1107921Y-58764D03*
Y-35764D03*
X1102921Y-58764D03*
Y-35764D03*
X1097921Y-58764D03*
Y-35764D03*
X1104256Y291841D03*
X1101615Y292447D03*
X1098756Y292841D03*
X1101567Y295859D03*
X1104221Y295696D03*
X1098567Y295841D03*
X1112490Y312723D03*
X1112515Y315369D03*
X1101200Y324013D03*
X1098402Y324017D03*
X1135606Y638753D03*
X1126806D03*
X1144406D03*
X1140006D03*
X1118006D03*
X1122406D03*
X1153206D03*
X1157606D03*
X1104806D03*
X1100406D03*
X1131206D03*
X1148806D03*
X1109206D03*
X1113606D03*
X1157621Y660756D03*
X1148821D03*
X1122421D03*
X1126821D03*
X1100421D03*
X1118021D03*
X1140021D03*
X1113621D03*
X1109221D03*
X1153221D03*
X1144421D03*
X1104821D03*
X1131221D03*
X1135621D03*
X1217921Y-58764D03*
Y-35764D03*
X1212921Y-58764D03*
Y-35764D03*
X1207921Y-58764D03*
Y-35764D03*
X1202921Y-58764D03*
Y-35764D03*
X1197921Y-58764D03*
Y-35764D03*
X1192921Y-58764D03*
Y-35764D03*
X1187921Y-58764D03*
Y-35764D03*
X1182921Y-58764D03*
Y-35764D03*
X1177921Y-58764D03*
Y-35764D03*
X1172921Y-58764D03*
Y-35764D03*
X1167921Y-58764D03*
Y-35764D03*
X1162921Y-58764D03*
Y-35764D03*
X1188406Y638753D03*
X1214806D03*
X1197206D03*
X1201606D03*
X1192806D03*
X1170806D03*
X1162006D03*
X1166406D03*
X1206006D03*
X1219206D03*
X1179606D03*
X1175206D03*
X1210406D03*
X1184006D03*
X1184021Y660756D03*
X1219221D03*
X1192821D03*
X1188421D03*
X1201621D03*
X1179621D03*
X1214821D03*
X1206021D03*
X1166421D03*
X1210421D03*
X1170821D03*
X1162021D03*
X1175221D03*
X1197221D03*
X1232921Y-58764D03*
Y-35764D03*
X1227921Y-58764D03*
Y-35764D03*
X1222921Y-58764D03*
Y-35764D03*
X1252921Y-58764D03*
Y-35764D03*
X1247921Y-58764D03*
Y-35764D03*
X1242921Y-58764D03*
Y-35764D03*
X1237921Y-58764D03*
Y-35764D03*
X1257921D03*
X1272921Y-58764D03*
Y-35764D03*
X1267921Y-58764D03*
Y-35764D03*
X1262921Y-58764D03*
Y-35764D03*
X1257921Y-58764D03*
X1277921D03*
Y-35764D03*
X1263206Y638753D03*
X1223606D03*
X1228006D03*
X1258806D03*
X1241206D03*
X1236806D03*
X1250006D03*
X1245606D03*
X1276406D03*
X1254406D03*
X1280806D03*
X1272006D03*
X1267606D03*
X1232406D03*
X1228021Y660756D03*
X1232421D03*
X1280821D03*
X1245621D03*
X1236821D03*
X1223621D03*
X1276421D03*
X1241221D03*
X1272021D03*
X1258821D03*
X1250021D03*
X1254421D03*
X1263221D03*
X1267621D03*
X1342921Y-35764D03*
Y-58764D03*
X1317921D03*
X1312921Y-35764D03*
Y-58764D03*
X1307921Y-35764D03*
Y-58764D03*
X1302921Y-35764D03*
Y-58764D03*
X1297921D03*
Y-35764D03*
X1292921Y-58764D03*
Y-35764D03*
X1287921Y-58764D03*
Y-35764D03*
X1282921Y-58764D03*
Y-35764D03*
X1322921D03*
Y-58764D03*
X1317921Y-35764D03*
X1337921D03*
Y-58764D03*
X1332921Y-35764D03*
Y-58764D03*
X1327921Y-35764D03*
Y-58764D03*
X1324806Y638753D03*
X1298406D03*
X1285206D03*
X1294006D03*
X1302806D03*
X1333606D03*
X1338006D03*
X1320406D03*
X1311606D03*
X1329206D03*
X1307206D03*
X1342406D03*
X1289606D03*
X1316006D03*
X1329221Y660756D03*
X1311621D03*
X1316021D03*
X1333621D03*
X1342421D03*
X1285221D03*
X1324821D03*
X1338021D03*
X1298421D03*
X1289621D03*
X1294021D03*
X1320421D03*
X1302821D03*
X1307221D03*
X1402921Y-58764D03*
X1397921D03*
X1402921Y-35764D03*
X1392921Y-58764D03*
X1397921Y-35764D03*
X1387921Y-58764D03*
X1392921Y-35764D03*
X1382921Y-58764D03*
X1387921Y-35764D03*
X1377921Y-58764D03*
X1382921Y-35764D03*
X1372921Y-58764D03*
X1377921Y-35764D03*
X1367921Y-58764D03*
X1362921Y-35764D03*
Y-58764D03*
X1357921Y-35764D03*
Y-58764D03*
X1352921Y-35764D03*
Y-58764D03*
X1347921Y-35764D03*
Y-58764D03*
X1395913Y-7874D03*
X1402211Y1139D03*
Y-16889D03*
X1351206Y638753D03*
X1360006D03*
X1404506Y638853D03*
X1355606Y638753D03*
X1386906Y638853D03*
X1364406Y638753D03*
X1391306Y638853D03*
X1346806Y638753D03*
X1400106Y638853D03*
X1382006Y638753D03*
X1377606D03*
X1373206D03*
X1395706Y638853D03*
X1368806Y638753D03*
X1402211Y601615D03*
Y619643D03*
X1395913Y610630D03*
X1368821Y660756D03*
X1346821D03*
X1355621D03*
X1360021D03*
X1364421D03*
X1351221D03*
X1404521Y660856D03*
X1400121D03*
X1395721D03*
X1386921D03*
X1377621Y660756D03*
X1382021D03*
X1373221D03*
X1391321Y660856D03*
X1407921Y-58764D03*
X1412921Y-35764D03*
X1407921D03*
X1442921Y-58764D03*
X1447921Y-35764D03*
X1437921Y-58764D03*
X1442921Y-35764D03*
X1432921Y-58764D03*
X1437921Y-35764D03*
X1427921Y-58764D03*
X1432921Y-35764D03*
X1422921Y-58764D03*
X1427921Y-35764D03*
X1417921Y-58764D03*
X1422921Y-35764D03*
X1412921Y-58764D03*
X1417921Y-35764D03*
X1462921Y-58764D03*
X1457921D03*
X1462921Y-35764D03*
X1452921Y-58764D03*
X1457921Y-35764D03*
X1447921Y-58764D03*
X1452921Y-35764D03*
X1410061Y2178D03*
X1410060Y-17927D03*
X1419313Y5626D03*
Y-21374D03*
X1428872Y1668D03*
X1428864Y-17425D03*
X1432813Y-7874D03*
X1422106Y638853D03*
X1466106D03*
X1448506D03*
X1457306D03*
X1417706D03*
X1413306D03*
X1461706D03*
X1452906D03*
X1408906D03*
X1444106D03*
X1435306D03*
X1426506D03*
X1430906D03*
X1439706D03*
X1432813Y610630D03*
X1428864Y601079D03*
X1428872Y620172D03*
X1419313Y597130D03*
Y624130D03*
X1410060Y600577D03*
X1410061Y620682D03*
X1457321Y660856D03*
X1417721D03*
X1413321D03*
X1408921D03*
X1422121D03*
X1426521D03*
X1435321D03*
X1444121D03*
X1439721D03*
X1430921D03*
X1448521D03*
X1452921D03*
X1466121D03*
X1461721D03*
X1502921Y-58764D03*
X1507921Y-35764D03*
X1497921Y-58764D03*
X1502921Y-35764D03*
X1492921Y-58764D03*
X1497921Y-35764D03*
X1487921Y-58764D03*
X1492921Y-35764D03*
X1482921Y-58764D03*
X1487921Y-35764D03*
X1477921Y-58764D03*
X1482921Y-35764D03*
X1472921Y-58764D03*
X1477921Y-35764D03*
X1467921Y-58764D03*
X1472921Y-35764D03*
X1467921D03*
X1527921Y-58764D03*
X1522921D03*
X1527921Y-35764D03*
X1517921Y-58764D03*
X1522921Y-35764D03*
X1512921Y-58764D03*
X1517921Y-35764D03*
X1507921Y-58764D03*
X1512921Y-35764D03*
X1496906Y638853D03*
X1492506D03*
X1501706Y638753D03*
X1506106D03*
X1514906D03*
X1483706Y638853D03*
X1523706Y638753D03*
X1510506D03*
X1488106Y638853D03*
X1474906D03*
X1519306Y638753D03*
X1479306Y638853D03*
X1528106Y638753D03*
X1470506Y638853D03*
X1496921Y660856D03*
X1483721D03*
X1488121D03*
X1492521D03*
X1479321D03*
X1510521Y660756D03*
X1528121D03*
X1523721D03*
X1501721D03*
X1506121D03*
X1514921D03*
X1519321D03*
X1474921Y660856D03*
X1470521D03*
X1587921Y-58764D03*
X1582921D03*
X1587921Y-35764D03*
X1532921D03*
X1542921D03*
X1532921Y-58764D03*
X1537921Y-35764D03*
X1577921Y-58764D03*
X1582921Y-35764D03*
X1572921Y-58764D03*
X1577921Y-35764D03*
X1567921Y-58764D03*
X1572921Y-35764D03*
X1562921Y-58764D03*
X1567921Y-35764D03*
X1557921Y-58764D03*
X1562921Y-35764D03*
X1552921Y-58764D03*
X1557921Y-35764D03*
X1547921Y-58764D03*
X1552921Y-35764D03*
X1542921Y-58764D03*
X1547921Y-35764D03*
X1537921Y-58764D03*
X1580121Y647556D03*
X1555106Y638753D03*
X1555121Y647556D03*
X1590121D03*
X1590106Y638753D03*
X1590121Y643156D03*
X1585121Y647556D03*
X1585106Y638753D03*
X1585121Y643156D03*
X1565121Y647556D03*
X1570121Y643156D03*
X1570106Y638753D03*
X1565106D03*
X1565121Y643156D03*
X1570121Y647556D03*
X1560121D03*
X1560106Y638753D03*
X1560121Y643156D03*
X1575121D03*
X1575106Y638753D03*
X1575121Y647556D03*
X1555121Y643156D03*
X1580106Y638753D03*
X1580121Y643156D03*
X1550121Y647556D03*
X1541306Y638753D03*
X1545706D03*
X1550106D03*
X1550121Y643156D03*
X1536906Y638753D03*
X1532506D03*
X1565121Y651956D03*
X1570121Y660756D03*
Y656356D03*
X1565121Y660756D03*
X1555121Y651956D03*
X1590121Y660756D03*
Y656356D03*
Y651956D03*
X1585121Y660756D03*
Y656356D03*
Y651956D03*
X1580121Y660756D03*
Y656356D03*
Y651956D03*
X1560121Y660756D03*
Y656356D03*
Y651956D03*
X1555121Y660756D03*
Y656356D03*
X1570121Y651956D03*
X1575121D03*
Y656356D03*
Y660756D03*
X1565121Y656356D03*
X1550121Y651956D03*
Y656356D03*
X1541321Y660756D03*
X1550121D03*
X1545721D03*
X1532521D03*
X1536921D03*
X1642921Y-35764D03*
Y-58764D03*
X1637921Y-35764D03*
Y-58764D03*
X1632921Y-35764D03*
Y-58764D03*
X1627921D03*
X1622921D03*
X1627921Y-35764D03*
X1617921Y-58764D03*
X1622921Y-35764D03*
X1612921Y-58764D03*
X1617921Y-35764D03*
X1607921Y-58764D03*
X1612921Y-35764D03*
X1602921Y-58764D03*
X1607921Y-35764D03*
X1597921Y-58764D03*
X1602921Y-35764D03*
X1592921Y-58764D03*
X1597921Y-35764D03*
X1592921D03*
X1647921D03*
Y-58764D03*
X1625106Y638753D03*
X1625121Y647556D03*
X1630121Y643156D03*
X1630106Y638753D03*
X1630121Y647556D03*
X1635121Y643156D03*
X1635106Y638753D03*
X1635121Y647556D03*
X1640121Y643156D03*
Y647556D03*
X1640106Y638753D03*
X1650121Y647556D03*
X1650106Y638753D03*
X1650121Y643156D03*
X1645121Y647556D03*
X1645106Y638753D03*
X1645121Y643156D03*
X1625121D03*
X1620121Y647556D03*
X1620106Y638753D03*
X1620121Y643156D03*
X1615121Y647556D03*
X1615106Y638753D03*
X1615121Y643156D03*
X1610121Y647556D03*
X1610106Y638753D03*
X1610121Y643156D03*
X1605121Y647556D03*
X1605106Y638753D03*
X1605121Y643156D03*
X1600121Y647556D03*
X1600106Y638753D03*
X1600121Y643156D03*
X1595121Y647556D03*
X1595106Y638753D03*
X1595121Y643156D03*
X1625121Y651956D03*
Y660756D03*
X1630121Y651956D03*
Y656356D03*
Y660756D03*
X1635121Y651956D03*
Y656356D03*
Y660756D03*
X1625121Y656356D03*
X1640121D03*
Y651956D03*
X1650121Y660756D03*
Y656356D03*
Y651956D03*
X1645121Y660756D03*
Y656356D03*
Y651956D03*
X1640121Y660756D03*
X1620121D03*
Y656356D03*
Y651956D03*
X1615121Y660756D03*
Y656356D03*
Y651956D03*
X1610121Y660756D03*
Y656356D03*
Y651956D03*
X1605121Y660756D03*
Y656356D03*
Y651956D03*
X1600121Y660756D03*
Y656356D03*
Y651956D03*
X1595121Y660756D03*
Y656356D03*
Y651956D03*
X1692921Y-40764D03*
X1702921Y-54764D03*
X1687921D03*
X1682921D03*
X1677921D03*
X1672921D03*
X1692921D03*
X1697921D03*
X1707921D03*
X1712921D03*
X1697921Y-40764D03*
X1692921Y-50764D03*
X1687921D03*
X1682921D03*
X1677921D03*
X1672921D03*
X1712921D03*
X1707921D03*
X1702921D03*
X1697921Y-45764D03*
X1707921D03*
X1702921D03*
X1712921D03*
X1697921Y-50764D03*
X1667921Y-35764D03*
X1712921D03*
Y-58764D03*
X1707921Y-35764D03*
Y-58764D03*
X1702921Y-35764D03*
Y-58764D03*
X1697921Y-35764D03*
Y-58764D03*
X1687921Y-40764D03*
X1672921Y-45764D03*
X1677921D03*
X1682921D03*
Y-40764D03*
X1687921Y-45764D03*
X1692921D03*
X1667921Y-58764D03*
X1662921Y-35764D03*
Y-58764D03*
X1657921Y-35764D03*
Y-58764D03*
X1652921Y-35764D03*
Y-58764D03*
X1712921Y-40764D03*
X1707921D03*
X1702921D03*
X1677921D03*
X1672921D03*
X1677921Y-35764D03*
Y-58764D03*
X1672921Y-35764D03*
Y-58764D03*
X1682921Y-35764D03*
Y-58764D03*
X1692921Y-35764D03*
Y-58764D03*
X1687921Y-35764D03*
Y-58764D03*
X1690121Y647556D03*
X1710121D03*
X1710106Y638753D03*
X1710121Y643156D03*
X1705121Y647556D03*
X1705106Y638753D03*
X1695121Y643156D03*
X1695106Y638753D03*
X1695121Y647556D03*
X1700121Y643156D03*
X1700106Y638753D03*
X1685121Y647556D03*
X1685106Y638753D03*
X1685121Y643156D03*
X1680121Y647556D03*
X1680106Y638753D03*
X1680121Y643156D03*
X1675121Y647556D03*
X1675106Y638753D03*
X1675121Y643156D03*
X1670121Y647556D03*
X1670106Y638753D03*
X1670121Y643156D03*
X1665121Y647556D03*
X1665106Y638753D03*
X1665121Y643156D03*
X1660121Y647556D03*
X1660106Y638753D03*
X1660121Y643156D03*
X1655121Y647556D03*
X1655106Y638753D03*
X1655121Y643156D03*
X1690121D03*
X1690106Y638753D03*
X1700121Y647556D03*
X1705121Y643156D03*
X1690121Y656356D03*
Y651956D03*
X1710121Y660756D03*
Y656356D03*
Y651956D03*
X1705121Y660756D03*
Y656356D03*
Y651956D03*
X1690121Y660756D03*
X1695121Y651956D03*
Y656356D03*
Y660756D03*
X1685121Y651956D03*
X1680121Y660756D03*
Y656356D03*
Y651956D03*
X1675121Y660756D03*
Y656356D03*
Y651956D03*
X1670121Y660756D03*
Y656356D03*
Y651956D03*
X1665121Y660756D03*
Y656356D03*
Y651956D03*
X1660121Y660756D03*
Y656356D03*
Y651956D03*
X1655121Y660756D03*
Y656356D03*
Y651956D03*
X1685121Y660756D03*
Y656356D03*
X1700121Y651956D03*
Y656356D03*
Y660756D03*
X1737921Y-50764D03*
X1722921Y-45764D03*
X1727921D03*
X1732921D03*
X1747921D03*
X1752921D03*
X1727921Y-54764D03*
X1757921D03*
X1717921D03*
X1722921D03*
X1767921Y-40764D03*
Y-50764D03*
X1762921D03*
X1757921D03*
X1762921Y-54764D03*
X1752921D03*
X1747921D03*
X1742921D03*
X1737921D03*
X1732921D03*
X1772921D03*
X1767921D03*
X1762921Y-40764D03*
X1772921D03*
X1722921Y-50764D03*
X1717921D03*
X1732921D03*
X1757921Y-40764D03*
X1717921Y-45764D03*
Y-58764D03*
X1742921Y-50764D03*
X1747921D03*
X1752921D03*
X1742921Y-58764D03*
X1737921Y-35764D03*
Y-58764D03*
X1732921Y-35764D03*
Y-58764D03*
X1727921Y-35764D03*
Y-58764D03*
X1722921Y-35764D03*
Y-58764D03*
X1717921Y-35764D03*
X1757921Y-45764D03*
X1762921D03*
X1742921D03*
X1752921Y-40764D03*
X1747921D03*
X1742921D03*
X1737921D03*
X1732921D03*
X1727921D03*
X1722921D03*
X1717921D03*
X1727921Y-50764D03*
X1767921Y-45764D03*
X1772921D03*
X1737921D03*
X1772921Y-35764D03*
Y-58764D03*
X1767921Y-35764D03*
Y-58764D03*
X1762921Y-35764D03*
Y-58764D03*
X1757921Y-35764D03*
Y-58764D03*
X1752921Y-35764D03*
Y-58764D03*
X1747921Y-35764D03*
Y-58764D03*
X1742921Y-35764D03*
X1772921Y-50764D03*
X1775121Y643156D03*
Y647556D03*
X1775106Y638753D03*
X1730121Y647556D03*
X1730106Y638753D03*
X1730121Y643156D03*
X1725121Y647556D03*
X1725106Y638753D03*
X1725121Y643156D03*
X1720121Y647556D03*
X1720106Y638753D03*
X1720121Y643156D03*
X1715121Y647556D03*
X1715106Y638753D03*
X1715121Y643156D03*
X1770121Y647556D03*
X1770106Y638753D03*
X1770121Y643156D03*
X1765121Y647556D03*
X1765106Y638753D03*
X1765121Y643156D03*
X1760121Y647556D03*
X1760106Y638753D03*
X1760121Y643156D03*
X1755121Y647556D03*
X1755106Y638753D03*
X1755121Y643156D03*
X1750121Y647556D03*
X1750106Y638753D03*
X1750121Y643156D03*
X1745121Y647556D03*
X1745106Y638753D03*
X1745121Y643156D03*
X1740121Y647556D03*
X1740106Y638753D03*
X1740121Y643156D03*
X1735121Y647556D03*
X1735106Y638753D03*
X1735121Y643156D03*
X1770121Y660756D03*
X1775121D03*
Y656356D03*
Y651956D03*
X1725121Y660756D03*
Y656356D03*
Y651956D03*
X1720121Y660756D03*
Y656356D03*
Y651956D03*
X1715121Y660756D03*
Y656356D03*
Y651956D03*
X1770121D03*
X1765121Y660756D03*
Y656356D03*
Y651956D03*
X1760121Y660756D03*
Y656356D03*
Y651956D03*
X1755121Y660756D03*
Y656356D03*
Y651956D03*
X1750121Y660756D03*
Y656356D03*
Y651956D03*
X1745121Y660756D03*
Y656356D03*
Y651956D03*
X1740121Y660756D03*
Y656356D03*
Y651956D03*
X1735121Y660756D03*
Y656356D03*
Y651956D03*
X1730121Y660756D03*
Y656356D03*
X1770121D03*
X1730121Y651956D03*
X1817921Y-40764D03*
X1832921Y-45764D03*
Y-54764D03*
X1827921D03*
X1822921D03*
X1817921D03*
X1812921D03*
X1807921D03*
X1802921D03*
X1797921D03*
X1792921D03*
X1787921D03*
X1782921D03*
X1777921D03*
X1832921Y-50764D03*
X1827921D03*
X1822921D03*
X1817921D03*
X1812921D03*
X1807921D03*
X1802921D03*
X1797921D03*
X1792921D03*
X1787921D03*
X1782921Y-40764D03*
X1792921D03*
X1802921D03*
X1807921D03*
X1822921D03*
X1827921D03*
X1832921D03*
X1812921D03*
X1797921D03*
X1777921Y-45764D03*
X1782921D03*
X1787921D03*
X1792921D03*
X1797921D03*
X1802921D03*
X1807921D03*
X1812921D03*
X1817921D03*
X1822921D03*
X1787921Y-40764D03*
X1832921Y-35764D03*
Y-58764D03*
X1827921Y-35764D03*
Y-58764D03*
X1822921Y-35764D03*
Y-58764D03*
X1817921Y-35764D03*
Y-58764D03*
X1812921Y-35764D03*
Y-58764D03*
X1807921Y-35764D03*
Y-58764D03*
X1802921Y-35764D03*
Y-58764D03*
X1797921Y-35764D03*
Y-58764D03*
X1792921Y-35764D03*
Y-58764D03*
X1787921Y-35764D03*
Y-58764D03*
X1782921Y-35764D03*
Y-58764D03*
X1777921Y-35764D03*
Y-58764D03*
X1782921Y-50764D03*
X1777921D03*
Y-40764D03*
X1827921Y-45764D03*
X1794992Y61342D03*
X1797664Y61334D03*
X1797645Y64153D03*
X1792382Y61363D03*
X1792363Y64182D03*
X1794973Y64161D03*
X1807891Y62180D03*
X1810563Y62172D03*
X1810693Y59493D03*
X1808021Y59501D03*
X1805411Y59522D03*
X1813393Y59493D03*
X1813363Y62172D03*
X1810578Y56866D03*
X1805282Y56880D03*
X1807916Y56895D03*
X1813278Y56866D03*
X1805281Y62201D03*
X1831148Y144592D03*
X1836200Y153424D03*
X1833000D03*
X1833600Y145900D03*
X1793205Y165531D03*
X1793268Y162774D03*
X1780121Y643156D03*
X1780106Y638753D03*
X1780121Y647556D03*
X1785121Y643156D03*
X1790121D03*
X1835121Y647556D03*
X1835106Y638753D03*
X1835121Y643156D03*
X1830121Y647556D03*
X1830106Y638753D03*
X1830121Y643156D03*
X1825121Y647556D03*
X1825106Y638753D03*
X1825121Y643156D03*
X1820121Y647556D03*
X1820106Y638753D03*
X1820121Y643156D03*
X1815121Y647556D03*
X1815106Y638753D03*
X1815121Y643156D03*
X1810121Y647556D03*
X1810106Y638753D03*
X1810121Y643156D03*
X1805121Y647556D03*
X1805106Y638753D03*
X1805121Y643156D03*
X1800121Y647556D03*
X1800106Y638753D03*
X1800121Y643156D03*
X1795121Y647556D03*
X1795106Y638753D03*
X1795121Y643156D03*
X1790121Y647556D03*
X1790106Y638753D03*
X1785121Y647556D03*
X1785106Y638753D03*
X1800121Y656356D03*
X1780121Y651956D03*
Y656356D03*
Y660756D03*
X1835121D03*
Y656356D03*
Y651956D03*
X1830121Y660756D03*
Y656356D03*
Y651956D03*
X1825121Y660756D03*
Y656356D03*
Y651956D03*
X1820121Y660756D03*
Y656356D03*
Y651956D03*
X1815121Y660756D03*
Y656356D03*
Y651956D03*
X1810121Y660756D03*
Y656356D03*
Y651956D03*
X1805121Y660756D03*
Y656356D03*
Y651956D03*
X1800121Y660756D03*
Y651956D03*
X1795121Y660756D03*
Y656356D03*
Y651956D03*
X1790121Y660756D03*
Y656356D03*
Y651956D03*
X1785121Y660756D03*
Y656356D03*
Y651956D03*
X1857921Y-45764D03*
X1837921D03*
X1897921D03*
X1892921D03*
X1887921D03*
X1882921D03*
X1877921D03*
X1872921D03*
X1867921D03*
X1862921D03*
X1842921Y-54764D03*
X1852921Y-45764D03*
X1847921D03*
X1842921D03*
X1897921Y-54764D03*
X1892921D03*
X1887921D03*
X1882921D03*
X1877921D03*
X1872921D03*
X1867921D03*
X1862921D03*
X1857921D03*
X1852921D03*
X1847921D03*
X1837921D03*
X1897921Y-50764D03*
X1892921D03*
X1887921D03*
X1882921D03*
X1877921D03*
X1872921D03*
X1867921D03*
X1862921D03*
X1857921D03*
X1852921D03*
X1847921D03*
X1842921D03*
X1837921D03*
X1892921Y-40764D03*
X1897921D03*
X1877921D03*
X1882921D03*
X1887921D03*
X1857921D03*
X1862921D03*
X1867921D03*
X1872921D03*
X1837921D03*
X1842921D03*
X1847921D03*
X1852921D03*
Y-35764D03*
Y-58764D03*
X1847921Y-35764D03*
Y-58764D03*
X1842921Y-35764D03*
Y-58764D03*
X1837921Y-35764D03*
Y-58764D03*
X1862921D03*
X1857921Y-35764D03*
Y-58764D03*
X1882921D03*
X1877921Y-35764D03*
Y-58764D03*
X1872921Y-35764D03*
Y-58764D03*
X1867921Y-35764D03*
Y-58764D03*
X1862921Y-35764D03*
X1897921D03*
Y-58764D03*
X1892921Y-35764D03*
Y-58764D03*
X1887921Y-35764D03*
Y-58764D03*
X1882921Y-35764D03*
X1847797Y26331D03*
X1847564Y21636D03*
X1844732Y-7874D03*
X1851030Y1139D03*
Y-16889D03*
X1858880Y2178D03*
X1858879Y-17927D03*
X1868132Y5626D03*
Y-21374D03*
X1877691Y1668D03*
X1877683Y-17425D03*
X1881632Y-7874D03*
X1895121Y647556D03*
X1895106Y638753D03*
X1895121Y643156D03*
X1890121Y647556D03*
X1890106Y638753D03*
X1890121Y643156D03*
X1885121Y647556D03*
X1885106Y638753D03*
X1885121Y643156D03*
X1880121Y647556D03*
X1880106Y638753D03*
X1880121Y643156D03*
X1875121Y647556D03*
X1875106Y638753D03*
X1875121Y643156D03*
X1870121Y647556D03*
X1870106Y638753D03*
X1870121Y643156D03*
X1865121Y647556D03*
X1865106Y638753D03*
X1865121Y643156D03*
X1860121Y647556D03*
X1860106Y638753D03*
X1860121Y643156D03*
X1855121Y647556D03*
X1855106Y638753D03*
X1855121Y643156D03*
X1850121Y647556D03*
X1850106Y638753D03*
X1850121Y643156D03*
X1845121Y647556D03*
X1845106Y638753D03*
X1845121Y643156D03*
X1840121Y647556D03*
X1840106Y638753D03*
X1840121Y643156D03*
X1844732Y610630D03*
X1851030Y619643D03*
Y601615D03*
X1858880Y620682D03*
X1858879Y600577D03*
X1868132Y624130D03*
Y597130D03*
X1877691Y620172D03*
X1877683Y601079D03*
X1881632Y610630D03*
X1895121Y660756D03*
Y656356D03*
Y651956D03*
X1890121Y660756D03*
Y656356D03*
Y651956D03*
X1885121Y660756D03*
Y656356D03*
Y651956D03*
X1880121Y660756D03*
Y656356D03*
Y651956D03*
X1875121Y660756D03*
Y656356D03*
Y651956D03*
X1870121Y660756D03*
Y656356D03*
Y651956D03*
X1865121Y660756D03*
Y656356D03*
Y651956D03*
X1860121Y660756D03*
Y656356D03*
Y651956D03*
X1855121Y660756D03*
Y656356D03*
Y651956D03*
X1850121Y660756D03*
Y656356D03*
Y651956D03*
X1845121Y660756D03*
Y656356D03*
Y651956D03*
X1840121Y660756D03*
Y656356D03*
Y651956D03*
X1927921Y-40764D03*
X1947921Y-45764D03*
X1942921D03*
X1937921D03*
X1932921D03*
X1927921D03*
X1922921D03*
X1917921D03*
X1912921D03*
X1907921D03*
X1902921D03*
X1927921Y-50764D03*
X1932921D03*
Y-40764D03*
X1937921D03*
X1942921D03*
X1947921D03*
X1907921Y-50764D03*
X1902921D03*
X1922921Y-40764D03*
X1917921D03*
X1912921D03*
X1907921D03*
X1902921D03*
X1922921Y-54764D03*
X1917921D03*
X1912921D03*
X1907921D03*
X1902921D03*
X1927921D03*
X1932921D03*
X1937921D03*
X1942921D03*
X1947921D03*
X1952921D03*
X1957921D03*
Y-50764D03*
X1952921D03*
X1947921D03*
X1942921D03*
X1937921D03*
X1922921D03*
X1917921D03*
X1912921D03*
X1957921Y-35764D03*
Y-58764D03*
X1952921Y-35764D03*
Y-58764D03*
X1947921Y-35764D03*
Y-58764D03*
X1942921Y-35764D03*
Y-58764D03*
X1937921Y-35764D03*
Y-58764D03*
X1932921Y-35764D03*
Y-58764D03*
X1927921Y-35764D03*
Y-58764D03*
X1922921Y-35764D03*
Y-58764D03*
X1917921Y-35764D03*
Y-58764D03*
X1912921Y-35764D03*
Y-58764D03*
X1907921Y-35764D03*
Y-58764D03*
X1902921Y-35764D03*
Y-58764D03*
X1960106Y638753D03*
X1955106D03*
X1950106D03*
X1945121Y647556D03*
Y643156D03*
X1945106Y638753D03*
X1940121Y647556D03*
Y643156D03*
X1940106Y638753D03*
X1935121Y647556D03*
Y643156D03*
X1935106Y638753D03*
X1930106D03*
X1925106D03*
X1920121Y647556D03*
X1910121Y643156D03*
X1910106Y638753D03*
X1905121Y647556D03*
Y643156D03*
X1905106Y638753D03*
X1900121Y647556D03*
X1900106Y638753D03*
X1900121Y643156D03*
X1920106Y638753D03*
X1915121Y647556D03*
X1920121Y643156D03*
X1910121Y647556D03*
X1915106Y638753D03*
X1915121Y643156D03*
X1960121Y656356D03*
Y660756D03*
X1955121Y656356D03*
Y660756D03*
X1950121Y651956D03*
Y656356D03*
Y660756D03*
X1945121Y651956D03*
Y656356D03*
Y660756D03*
X1940121Y651956D03*
Y656356D03*
Y660756D03*
X1935121Y651956D03*
Y656356D03*
Y660756D03*
X1930121Y651956D03*
Y656356D03*
Y660756D03*
X1925121Y651956D03*
Y656356D03*
Y660756D03*
X1920121Y651956D03*
Y656356D03*
X1905121Y651956D03*
Y656356D03*
Y660756D03*
X1900121D03*
Y656356D03*
Y651956D03*
X1915121D03*
Y656356D03*
Y660756D03*
X1920121D03*
X1910121D03*
Y656356D03*
Y651956D03*
X1967921Y-45764D03*
X1962921D03*
Y-40764D03*
X1967921D03*
Y-54764D03*
X1962921D03*
X1967921Y-50764D03*
X1962921D03*
X1967921Y-35764D03*
Y-58764D03*
X1962921Y-35764D03*
Y-58764D03*
X1970121Y647556D03*
Y643156D03*
X1970106Y638753D03*
X1965121Y647556D03*
Y643156D03*
X1965106Y638753D03*
X1970121Y651956D03*
Y656356D03*
Y660756D03*
X1965121Y651956D03*
Y656356D03*
Y660756D03*
G54D20*
X1753465Y536791D03*
X1749528D03*
X1753465D03*
X1749528D03*
G54D11*
G01X-6118Y202189D02*
X-3937Y204370D01*
G01D02*
X-1756Y206551D01*
G01X-6118D02*
X-3937Y204370D01*
G01D02*
X-1756Y202189D01*
G01X1756D02*
X3937Y204370D01*
G01X1756Y206551D02*
X3937Y204370D01*
G01X-13992Y202189D02*
X-11811Y204370D01*
G01D02*
X-9630Y206551D01*
G01X-13992D02*
X-11811Y204370D01*
G01D02*
X-9630Y202189D01*
G01X-6118Y225811D02*
X-3937Y227992D01*
G01D02*
X-1756Y230173D01*
G01X-6118D02*
X-3937Y227992D01*
G01D02*
X-1756Y225811D01*
G01X1756D02*
X3937Y227992D01*
G01X1756Y230173D02*
X3937Y227992D01*
G01X-13992Y225811D02*
X-11811Y227992D01*
G01D02*
X-9630Y230173D01*
G01X-13992D02*
X-11811Y227992D01*
G01D02*
X-9630Y225811D01*
G01X-6118Y334945D02*
X-3937Y337126D01*
G01D02*
X-1756Y339307D01*
G01X-6118D02*
X-3937Y337126D01*
G01D02*
X-1756Y334945D01*
G01X1756D02*
X3937Y337126D01*
G01D02*
X6118Y339307D01*
G01X1756D02*
X3937Y337126D01*
G01D02*
X6118Y334945D01*
G01X-6118Y311323D02*
X-3937Y313504D01*
G01D02*
X-1756Y315685D01*
G01X-6118D02*
X-3937Y313504D01*
G01D02*
X-1756Y311323D01*
G01X1756D02*
X3937Y313504D01*
G01D02*
X6118Y315685D01*
G01X1756D02*
X3937Y313504D01*
G01D02*
X6118Y311323D01*
G01X-13992Y334945D02*
X-11811Y337126D01*
G01D02*
X-9630Y339307D01*
G01X-13992D02*
X-11811Y337126D01*
G01D02*
X-9630Y334945D01*
G01X-13992Y311323D02*
X-11811Y313504D01*
G01D02*
X-9630Y315685D01*
G01X-13992D02*
X-11811Y313504D01*
G01D02*
X-9630Y311323D01*
G01X430749Y-124922D02*
G02I-12000J0D01*
G01X425599D02*
G02I-6850J0D01*
G01X434749D02*
X402749D01*
G01X434749Y-140922D02*
Y-220922D01*
G01D02*
X1729349D01*
G01X434749Y-176422D02*
X1729349D01*
G01X418749Y-140922D02*
Y-108922D01*
G01X434749Y-140922D02*
X1729349D01*
G01X941849D02*
Y-220922D01*
G01X1079349Y-140922D02*
Y-220922D01*
G01X1194349Y-140922D02*
Y-220922D01*
G01X1361849Y-140922D02*
Y-220922D01*
G01X1531849Y-140922D02*
Y-220922D01*
G01X1684953Y534539D02*
X1687205Y536791D01*
G01X1684953Y539043D02*
X1687205Y536791D01*
G01X1729349Y-140922D02*
Y-220922D01*
G01X1757349Y-124922D02*
G02I-12000J0D01*
G01X1752199D02*
G02I-6850J0D01*
G01X1745349Y-140922D02*
Y-108922D01*
G01X1761349Y-124922D02*
X1729349D01*
G01X1717205Y536791D02*
X1719457Y539043D01*
G01X1717205Y536791D02*
X1719457Y534539D01*
G01X1952756Y-14960D02*
X1955958Y-20540D01*
G01X1949554D02*
X1952756Y-14960D01*
G01X1949554Y63848D02*
X1952756Y58268D01*
G01D02*
X1955958Y63848D01*
X-20700Y31400D03*
Y25200D03*
Y22300D03*
Y28100D03*
X-20600Y41200D03*
X-20526Y44263D03*
X-20500Y60300D03*
Y57300D03*
X-20700Y48800D03*
X-20726Y37463D03*
X-20800Y34400D03*
X-20500Y54300D03*
Y51300D03*
X-18000Y247400D03*
X-15000D03*
X-18000Y262700D03*
X-15000D03*
X-14690Y471140D03*
X-16726Y503651D03*
X-17084Y467626D03*
X-17300Y530800D03*
X-17397Y564242D03*
X30600Y-12000D03*
X25838Y-20458D03*
X10600Y25100D03*
X1068Y24831D03*
X27102Y25383D03*
X39530Y5205D03*
X45670Y5185D03*
X33370D03*
X45429Y-4669D03*
X33628Y131D03*
X40994Y-7148D03*
X45700Y40D03*
X11539Y31427D03*
X27200Y30600D03*
X27239Y28027D03*
X25600Y32500D03*
X11600Y33944D03*
X26760Y49595D03*
X27800Y86900D03*
X22100Y56400D03*
X27800Y89900D03*
Y83900D03*
X30400Y89800D03*
Y86800D03*
Y83800D03*
X10925Y56167D03*
X27904Y56294D03*
X30686Y79943D03*
X23530Y94840D03*
X11030D03*
X13530D03*
X16030D03*
X18530D03*
X22380Y92670D03*
X21030Y94840D03*
X2380Y92670D03*
X4880D03*
X7380D03*
X9880D03*
X12380D03*
X14880D03*
X17380D03*
X19880D03*
X3530Y94840D03*
X6030D03*
X8530D03*
X-1000Y81500D03*
X24880Y92670D03*
X25870Y80880D03*
X28294Y80889D03*
X32500Y81791D03*
X25100Y56300D03*
X-1190Y53240D03*
X25886Y71467D03*
X25925Y75867D03*
X26185Y67017D03*
X27488Y64671D03*
X11925Y65311D03*
X27625Y73967D03*
X27525Y69367D03*
X11925Y67811D03*
X11864Y62794D03*
X24064Y61894D03*
X15111Y62553D03*
X27564Y61894D03*
X11600Y36444D03*
X25900Y40300D03*
X27564Y59394D03*
X24064D03*
X25700Y36200D03*
X27300Y34300D03*
Y38300D03*
X27208Y42313D03*
X27239Y47027D03*
X25700Y44400D03*
X27525Y77867D03*
X44200Y139400D03*
X44300Y144800D03*
X44200Y130700D03*
Y116800D03*
X44100Y97800D03*
X44200Y111500D03*
X44300Y102700D03*
Y125600D03*
X44600Y154100D03*
X7995Y285385D03*
X32450Y454050D03*
X35100Y453900D03*
X35900Y423500D03*
X43550Y431300D03*
X20075Y424850D03*
X12025Y427900D03*
X7025D03*
X2025D03*
X21397Y439354D03*
Y444354D03*
X18836Y441785D03*
X7736D03*
X-6104Y461190D03*
X5000Y469000D03*
X10443Y490649D03*
X40132Y499800D03*
X24400Y519500D03*
X280Y524350D03*
X40185Y482918D03*
X37568Y482836D03*
X26780Y488910D03*
X21000Y495800D03*
X13300Y509600D03*
X13600Y504300D03*
X4000Y509500D03*
X2485Y498185D03*
X13700Y498500D03*
X24591Y479139D03*
X35896Y557668D03*
X33396D03*
X38696D03*
X-10200Y558200D03*
X21700Y532300D03*
X19100D03*
X27000D03*
X1040Y531218D03*
X21948Y566700D03*
X19448D03*
X27114Y557563D03*
X24748Y566700D03*
X0Y566800D03*
X29400Y532300D03*
X46400Y536290D03*
Y539790D03*
X43505Y538714D03*
X43241Y535965D03*
X41500Y533800D03*
X29914Y557563D03*
X45880Y554710D03*
Y557820D03*
X46560Y581000D03*
Y577500D03*
X1500Y540600D03*
X15787Y551700D03*
X17100Y545400D03*
X13639Y534683D03*
Y537183D03*
X15800Y543300D03*
X15600Y539100D03*
X17139Y534683D03*
Y537183D03*
X17100Y541200D03*
X17035Y549558D03*
X15800Y547500D03*
X17139Y553683D03*
X1500Y543100D03*
X1439Y538083D03*
X15800Y579500D03*
Y575300D03*
X17108Y585513D03*
X17156Y581481D03*
X17100Y577400D03*
X17139Y573183D03*
X1500Y576600D03*
X17139Y570683D03*
X1500Y579100D03*
X1439Y574083D03*
X15770Y587700D03*
X15800Y583500D03*
X27495Y591409D03*
X-12450Y590965D03*
X30212Y591417D03*
X35085Y591621D03*
X32609Y591538D03*
X46500Y595190D03*
X43190Y598410D03*
X43210Y595180D03*
X43190Y601910D03*
X17139Y589683D03*
X77000Y25992D03*
X74000D03*
X65000Y28500D03*
X68000D03*
X71000D03*
X74000D03*
X77000D03*
X80000Y29000D03*
Y26000D03*
X71000Y25992D03*
X68000D03*
X65800Y14200D03*
X59061Y476D03*
X61152Y-12752D03*
X59281Y-20641D03*
X82013Y14129D03*
X79372Y14895D03*
X81669Y11693D03*
X99102Y-12010D03*
X62076Y5575D03*
X76247Y1189D03*
X84202Y-11395D03*
X81702D03*
X79202D03*
X73611Y1158D03*
X71111D03*
X68611D03*
X73574Y-1437D03*
X71074D03*
X68574D03*
X79500Y-16600D03*
X55713Y-5095D03*
X76165Y-1415D03*
X60500Y79000D03*
X70500Y70500D03*
X73000D03*
X78000D03*
X75500D03*
X81000Y61500D03*
Y58500D03*
X63000Y74000D03*
X60500D03*
X63000Y76500D03*
X60500D03*
X67500Y49500D03*
X70500D03*
X73500D03*
X79500D03*
X61500Y43500D03*
X64500D03*
X67500D03*
X70500D03*
X60500Y70500D03*
X63000D03*
X61500Y58500D03*
Y49500D03*
Y56000D03*
X76500Y43500D03*
X79500Y46500D03*
X76500D03*
X73500D03*
X70500D03*
X67500D03*
X64500D03*
X61500D03*
X68000Y70500D03*
X65500D03*
X79500Y43500D03*
X61500Y61000D03*
X76500Y49500D03*
X73500Y43500D03*
X64500Y49500D03*
X79500Y79000D03*
X63000D03*
X79500Y72500D03*
X52500Y67200D03*
Y63700D03*
Y60700D03*
Y37700D03*
Y34700D03*
Y43700D03*
Y40700D03*
Y57700D03*
X79725Y75993D03*
X71050Y89600D03*
X48700Y90700D03*
Y95500D03*
X61300Y89800D03*
X81861Y93392D03*
X108385Y84291D03*
X63737Y130602D03*
X48900Y132600D03*
X68592D03*
X85250Y127680D03*
X77730Y126860D03*
X63858Y97620D03*
X66600Y102360D03*
X62422Y109413D03*
X68000Y111000D03*
X48900Y123500D03*
X62524Y123395D03*
X68584Y123900D03*
X68654Y118680D03*
X48800Y118900D03*
X48700Y109600D03*
X48600Y104900D03*
X63582Y116409D03*
X62502Y105100D03*
X52500Y152000D03*
X60300Y151500D03*
X70800Y151400D03*
X48800Y137600D03*
X63878Y144800D03*
X68632Y137800D03*
X63888Y140064D03*
X107254Y128041D03*
X106698Y215610D03*
X100500Y188600D03*
X97500Y185700D03*
X104800D03*
X102400D03*
X99900D03*
X77650Y178150D03*
X73500Y191500D03*
X107750Y238730D03*
X83300Y267400D03*
X108000Y249330D03*
X53400Y277582D03*
Y274500D03*
X48800Y282600D03*
Y285100D03*
X53500Y307300D03*
X85300Y335750D03*
X69500Y322000D03*
X103500Y302100D03*
X99770Y325249D03*
X67400Y391690D03*
X67230Y397380D03*
X67710Y402040D03*
X55616Y368998D03*
X52000Y354500D03*
X61000Y383000D03*
X57500Y388100D03*
X77300Y390600D03*
X107224Y393848D03*
X76500Y368300D03*
X76300Y358400D03*
X82037Y358542D03*
X70600Y368400D03*
X82100Y368300D03*
X70900Y358300D03*
X51500Y406000D03*
X57471Y410749D03*
X64007Y408276D03*
X63630Y424280D03*
X63600Y429000D03*
X51890Y424470D03*
Y418970D03*
X103100Y411800D03*
X72603Y474072D03*
X60300Y508650D03*
X51607Y511747D03*
X74480Y504480D03*
X79630Y504580D03*
X60000Y526500D03*
X79400Y502150D03*
X74600Y502064D03*
X77000Y502133D03*
X49800Y524300D03*
X76996Y504587D03*
X60700Y521900D03*
X57936Y516012D03*
X60202Y495342D03*
X57302Y495442D03*
X105958Y518550D03*
X77960Y541468D03*
Y538468D03*
X75461Y541468D03*
Y538468D03*
X73009Y541444D03*
Y538444D03*
X71500Y575000D03*
Y578000D03*
Y582000D03*
X81500Y575000D03*
X78500D03*
X81500Y578000D03*
X78500D03*
X74500Y575000D03*
Y578000D03*
Y582000D03*
X81500D03*
X78500D03*
X75500Y557500D03*
X72500Y561500D03*
Y557500D03*
X69500Y561500D03*
Y557500D03*
X75500Y561500D03*
X78500D03*
X81500D03*
Y557500D03*
X78500D03*
X70521Y538403D03*
X70498Y541394D03*
X75500Y554500D03*
X72500D03*
X69500D03*
X81500D03*
X78500D03*
X80389Y541468D03*
Y538468D03*
X106392Y537000D03*
X105000Y614533D03*
X82459Y618932D03*
X78500Y615500D03*
X81500D03*
X75500D03*
X72500D03*
X69500D03*
X78500Y602000D03*
X72500D03*
X69500Y596000D03*
X81500Y599000D03*
X78500D03*
X81500Y596000D03*
Y612000D03*
X78500D03*
X69500Y599000D03*
Y602000D03*
X75500D03*
X78500Y596000D03*
X72500D03*
X81500Y602000D03*
X75500Y596000D03*
X72500Y599000D03*
X75500D03*
X101898Y611483D03*
X114680Y17320D03*
X169770Y90364D03*
X166974Y84714D03*
Y73849D03*
X169770Y67900D03*
X157084Y67749D03*
X163391D03*
X130313Y73849D03*
X123620Y73799D03*
X141906Y73550D03*
X136780Y73799D03*
X126580Y67749D03*
X132959Y67900D03*
X136806Y65950D03*
X141893Y65736D03*
X120273Y92500D03*
X126616Y90314D03*
X132959Y90414D03*
X141880Y92714D03*
X163427Y90314D03*
X157084Y90414D03*
X150391D03*
X160431Y84714D03*
X153738D03*
X136756Y92500D03*
X141856Y84700D03*
X136780Y84698D03*
X123620Y84714D03*
X147045D03*
X130163D03*
X114082Y55100D03*
X147045Y73849D03*
X153738D03*
X160431Y73799D03*
X150391Y67749D03*
X156954Y192872D03*
X154454Y193021D03*
X151810Y192670D03*
X124895Y212033D03*
X153788Y187309D03*
X156928Y190053D03*
X148900Y180400D03*
X148800Y185300D03*
Y182900D03*
X148900Y190100D03*
X148800Y187700D03*
X113800Y180500D03*
X116900D03*
X151359Y187700D03*
X156294Y187625D03*
X151300Y190200D03*
X141263Y215216D03*
X125563Y218616D03*
X137763Y217716D03*
X128500Y218700D03*
X141263Y217716D03*
X137763Y215216D03*
X154130Y190186D03*
X169150Y223600D03*
Y227600D03*
X112904Y237218D03*
X122820Y244133D03*
X123074Y275948D03*
X113100Y269163D03*
X125624Y223633D03*
Y221133D03*
X141263Y234216D03*
X141200Y229600D03*
X141211Y225615D03*
X141300Y221700D03*
X139763Y231700D03*
Y227600D03*
Y223700D03*
X139582Y219800D03*
X128200Y250700D03*
X125563Y250616D03*
X141263Y249716D03*
Y247216D03*
X137763D03*
Y249716D03*
X125624Y255633D03*
X141300Y253700D03*
X139631Y251900D03*
X125624Y253133D03*
X137763Y279216D03*
X141263Y266216D03*
X139763Y255700D03*
Y259600D03*
X139800Y263700D03*
X141313Y257533D03*
X141263Y279216D03*
X141200Y261600D03*
X137300Y337200D03*
X118800Y298400D03*
X123301Y308044D03*
X110180Y280920D03*
X109960Y313190D03*
X119050Y341625D03*
X113000Y304000D03*
X113100Y333106D03*
X125624Y287633D03*
X128200Y282600D03*
X141263Y311216D03*
X137763D03*
X141263Y281716D03*
X139730Y284200D03*
X139763Y288200D03*
Y292000D03*
Y296000D03*
X125624Y285133D03*
X141200Y286100D03*
X141261Y290076D03*
X141300Y294000D03*
X141263Y298216D03*
X137763Y281716D03*
X125563Y282616D03*
X141211Y325515D03*
X128200Y314800D03*
X141263Y330216D03*
X139763Y327800D03*
X141300Y317500D03*
Y321500D03*
X139582Y315800D03*
X139763Y319400D03*
X125563Y314616D03*
X141263Y313716D03*
X137763D03*
X139763Y323600D03*
X125624Y317133D03*
Y319633D03*
X109640Y376070D03*
X113500Y369000D03*
X110670Y344500D03*
X112600Y366300D03*
X122300Y372100D03*
X119300Y400900D03*
X110397Y402603D03*
X109924Y393848D03*
X141289Y349488D03*
X128100Y346700D03*
X141300Y353300D03*
X141200Y357200D03*
X137763Y345716D03*
X141263D03*
Y343216D03*
X125624Y349133D03*
X137763Y343216D03*
X141263Y362216D03*
X139582Y347800D03*
X139763Y351400D03*
Y355200D03*
Y359500D03*
X125624Y351633D03*
X125563Y346616D03*
X141300Y381800D03*
X139763Y384000D03*
X125624Y381133D03*
X141263Y394216D03*
Y390416D03*
X141261Y385876D03*
X139736Y392300D03*
X125563Y378616D03*
X137763Y375216D03*
X141263D03*
Y377716D03*
X137763D03*
X139631Y379900D03*
X128500Y378700D03*
X139900Y388000D03*
X125624Y383633D03*
X117363Y417416D03*
X130163Y510114D03*
X147045D03*
X132959Y515814D03*
X126616Y515714D03*
X120273Y517900D03*
X136780Y510098D03*
X136756Y517900D03*
X141856Y510100D03*
X141880Y518114D03*
X123620Y510114D03*
X150391Y515814D03*
X169770Y515764D03*
X163427Y515714D03*
X166974Y510114D03*
X160431D03*
X157084Y515814D03*
X153738Y510114D03*
X141893Y528936D03*
X136806Y529150D03*
X141906Y536750D03*
X147045Y537049D03*
X120210Y529200D03*
X130313Y537049D03*
X132959Y531100D03*
X126580Y530949D03*
X123620Y536999D03*
X136780D03*
X113692Y566000D03*
X150391Y530949D03*
X166974Y537049D03*
X163391Y530949D03*
X160431Y536999D03*
X157084Y530949D03*
X153738Y537049D03*
X169770Y531100D03*
X114792Y604600D03*
X178691Y92714D03*
X173591Y84698D03*
X178667Y84700D03*
X183856Y84714D03*
X173567Y92500D03*
X183856Y73849D03*
X178717Y73550D03*
X173591Y73799D03*
X173617Y65950D03*
X178704Y65736D03*
X193895Y67749D03*
X200202D03*
X187202D03*
X206581Y67900D03*
X210428Y65950D03*
X197242Y73799D03*
X203935Y73849D03*
X210402Y73799D03*
Y84698D03*
X210378Y92500D03*
X190549Y73849D03*
Y84714D03*
X197242D03*
X203785D03*
X193895Y90414D03*
X206581D03*
X200238Y90314D03*
X187202Y90414D03*
X215515Y65736D03*
X224013Y67749D03*
X230706D03*
X215502Y92714D03*
X220667Y73849D03*
Y84714D03*
X227360D03*
X230706Y90414D03*
X215478Y84700D03*
X215528Y73550D03*
X227360Y73849D03*
X224013Y90414D03*
X197617Y243089D03*
X191537Y242989D03*
Y240489D03*
X197617Y240589D03*
X191537Y237989D03*
X197617Y238089D03*
X192037Y270750D03*
X194537D03*
X197037D03*
X194537Y299750D03*
X197037D03*
X192037D03*
X194537Y332480D03*
X197037D03*
X192037D03*
X194500Y360200D03*
X197137Y360350D03*
X191900Y360173D03*
X195200Y377800D03*
Y380300D03*
X172697Y407196D03*
X197242Y510114D03*
X200238Y515714D03*
X203785Y510114D03*
X190549D03*
X187202Y515814D03*
X193895D03*
X183856Y510114D03*
X173591Y510098D03*
X173567Y517900D03*
X178691Y518114D03*
X206581Y515814D03*
X210402Y510098D03*
X210378Y517900D03*
X215502Y518114D03*
X215478Y510100D03*
X224013Y515814D03*
X220667Y510114D03*
X227360D03*
X230706Y515814D03*
X190549Y537049D03*
X183856D03*
X187202Y530949D03*
X193895D03*
X197242Y536999D03*
X203935Y537049D03*
X200202Y530949D03*
X178717Y536750D03*
X173617Y529150D03*
X173591Y536999D03*
X178704Y528936D03*
X206581Y531100D03*
X210402Y536999D03*
X210428Y529150D03*
X215515Y528936D03*
X215528Y536750D03*
X224013Y530949D03*
X220667Y537049D03*
X230706Y530949D03*
X227360Y537049D03*
X243392Y67900D03*
X267517Y67749D03*
X252326Y65736D03*
X237013Y67749D03*
X260824D03*
X247239Y65950D03*
X247213Y73799D03*
Y84698D03*
X264171Y84714D03*
X252339Y73550D03*
X257478Y84714D03*
X240746Y73849D03*
X257478D03*
X234053Y73799D03*
X264171Y73849D03*
X243392Y90414D03*
X252313Y92714D03*
X237049Y90314D03*
X270864Y84714D03*
X247189Y92500D03*
X240596Y84714D03*
X234053D03*
X252289Y84700D03*
X260824Y90414D03*
X267517D03*
X270864Y73799D03*
X273824Y67749D03*
X280203Y67900D03*
X289137Y65736D03*
X284050Y65950D03*
X273860Y90314D03*
X277407Y84714D03*
X289100Y84700D03*
X284024Y84698D03*
X284000Y92500D03*
X289150Y73550D03*
X284024Y73799D03*
X289124Y92714D03*
X280203Y90414D03*
X277407Y73849D03*
X264171Y104284D03*
X267517Y109984D03*
X270864Y104284D03*
X257478D03*
X260824Y109984D03*
X243392Y109534D03*
X252339Y112865D03*
X247213Y113114D03*
X237049Y109884D03*
X240596Y104284D03*
X247239Y105265D03*
X252326Y105051D03*
X234053Y104284D03*
X273860Y109884D03*
X284050Y105265D03*
X289137Y105051D03*
X289150Y112865D03*
X284024Y113114D03*
X280203Y109534D03*
X277407Y104284D03*
X271239Y211060D03*
X284759Y207159D03*
X291519D03*
X274619Y213009D03*
Y216909D03*
X277999Y211060D03*
Y214960D03*
Y203260D03*
Y207159D03*
X281379Y213009D03*
X288139Y216909D03*
X284759Y214960D03*
X291519D03*
Y218860D03*
X281379Y201309D03*
X284759Y199360D03*
X291519D03*
X267859Y244209D03*
Y240309D03*
X271239Y238360D03*
X264179D03*
Y250060D03*
X264092Y222710D03*
X264179Y226660D03*
X271239Y269560D03*
Y273460D03*
Y265660D03*
X267859Y263709D03*
Y259809D03*
X264179Y265660D03*
X267859Y252009D03*
X264179Y253960D03*
X291519Y238360D03*
X284759Y234460D03*
X288139Y232509D03*
X281379D03*
X277999Y234460D03*
X274619Y232509D03*
Y220809D03*
Y224709D03*
Y228610D03*
X277999Y230559D03*
X274619Y244209D03*
X277999Y250060D03*
X274619Y240309D03*
Y248109D03*
Y236409D03*
X291519Y246160D03*
Y250060D03*
X284759Y246160D03*
X291519Y242260D03*
X281379Y220809D03*
X284759Y226660D03*
X288139Y236409D03*
X291519Y234460D03*
Y222760D03*
Y230559D03*
Y226660D03*
X281379Y240309D03*
Y252009D03*
X274619D03*
X277999Y253960D03*
X284759D03*
X291519D03*
X284759Y265660D03*
X291519D03*
Y277360D03*
X281379Y275409D03*
Y271509D03*
X284759Y277360D03*
Y273460D03*
X288139Y275409D03*
Y271509D03*
X277999Y277360D03*
X274619Y255909D03*
Y259809D03*
X277999Y269560D03*
X274619Y275409D03*
Y267609D03*
Y263709D03*
X288139Y255909D03*
X291519Y269560D03*
Y257860D03*
Y261760D03*
X281379Y259809D03*
X288139Y252009D03*
X271239Y328060D03*
X267859Y333909D03*
Y341709D03*
Y330009D03*
X264179Y328060D03*
Y339760D03*
X291519Y285160D03*
Y292959D03*
X284759Y285160D03*
X277999Y308560D03*
Y300760D03*
Y292959D03*
Y285160D03*
X291519Y308560D03*
X284759D03*
Y300760D03*
X291519D03*
X284759Y292959D03*
X291519Y316360D03*
X281379Y318309D03*
X291519Y328060D03*
X288139Y341709D03*
X274619Y330009D03*
Y326110D03*
Y322209D03*
X277999Y328060D03*
X274619Y341709D03*
X277999Y320260D03*
Y316360D03*
X274619Y333909D03*
Y337809D03*
X284759Y324160D03*
X288139Y318309D03*
X284759Y316360D03*
X281379Y337809D03*
X291519Y339760D03*
Y335860D03*
X284759Y331960D03*
X291519D03*
X281379Y326110D03*
X288139D03*
X267559Y369010D03*
X271239Y355360D03*
X267859Y349509D03*
Y353409D03*
X267559Y361209D03*
X264179Y343660D03*
Y355360D03*
X267492Y380709D03*
X271239Y390460D03*
X267859Y388509D03*
X271239Y382660D03*
X284759Y351460D03*
X281379Y345609D03*
X291519Y359260D03*
Y355360D03*
Y351460D03*
X284759Y343660D03*
X274619Y365109D03*
X277999Y363160D03*
Y367060D03*
X274619Y369010D03*
Y361209D03*
Y345609D03*
X277999Y347560D03*
X274619Y353409D03*
Y357309D03*
Y349509D03*
X277999Y343660D03*
X291519Y347560D03*
Y343660D03*
X288139Y365109D03*
X281379D03*
X284759Y363160D03*
X291519D03*
X284759Y370959D03*
X291519Y367060D03*
Y370959D03*
X288139Y361209D03*
X281379Y357309D03*
X288139Y345609D03*
Y380709D03*
Y400209D03*
X274619Y380709D03*
X277999Y394359D03*
X274619Y392410D03*
X277999Y390460D03*
Y386560D03*
X274619Y376809D03*
Y372909D03*
X291519Y374860D03*
X277999Y382660D03*
X284759Y398260D03*
X281379Y396309D03*
X291519Y398260D03*
X284759Y390460D03*
X291519D03*
X281379Y376809D03*
Y384609D03*
X284759Y382660D03*
X291519D03*
Y378760D03*
X264171Y510114D03*
X257478D03*
X260824Y515814D03*
Y491044D03*
X247177Y490514D03*
X252313D03*
X236892Y493400D03*
X243392Y493094D03*
X267584Y491219D03*
X271092Y495944D03*
X257392Y495800D03*
X264192D03*
X233292Y495900D03*
X239492Y498500D03*
X247177Y498514D03*
X252313D03*
X252289Y510100D03*
X267517Y515814D03*
X270864Y510114D03*
X247189Y517900D03*
X252313Y518114D03*
X247213Y510098D03*
X240596Y510114D03*
X243392Y515814D03*
X234053Y510114D03*
X237049Y515714D03*
X284024Y490644D03*
X289124D03*
X273860Y515714D03*
X277557Y495944D03*
X277407Y510114D03*
X289100Y510100D03*
X289124Y518114D03*
X284024Y510098D03*
X280203Y515814D03*
X273992Y491144D03*
X280203Y490644D03*
X284024Y498644D03*
X289124D03*
X284000Y517900D03*
X257478Y537049D03*
X237013Y530949D03*
X252339Y536750D03*
X243392Y531100D03*
X247213Y536999D03*
X252326Y528936D03*
X240746Y537049D03*
X234053Y536999D03*
X267517Y530949D03*
X270864Y536999D03*
X264171Y537049D03*
X260824Y530949D03*
X277407Y537049D03*
X273824Y530949D03*
X280203Y531100D03*
X284024Y536999D03*
X289137Y528936D03*
X284050Y529150D03*
X289150Y536750D03*
X321061Y-1743D03*
X314368Y-1843D03*
X331100Y-4536D03*
X327754Y-7108D03*
X317714Y-9786D03*
X311021D03*
X314368Y9114D03*
X321061D03*
X331100D03*
X311021Y28014D03*
X317714D03*
X311021Y17057D03*
X317714D03*
X327754D03*
Y28014D03*
X347833Y-7108D03*
X351179Y9122D03*
Y-4536D03*
X341140Y-1743D03*
X337793Y-9901D03*
X341140Y9122D03*
X347833Y17057D03*
Y28022D03*
X337793Y17057D03*
Y28014D03*
X311021Y65814D03*
X317714D03*
X321061Y35957D03*
X304328Y67749D03*
X297635D03*
X314368Y35957D03*
Y46914D03*
X311021Y54857D03*
X317714D03*
X321061Y46914D03*
X331100D03*
X327754Y65814D03*
X331100Y35957D03*
X327754Y54857D03*
Y92757D03*
X331100Y84714D03*
Y73757D03*
X314368D03*
Y87392D03*
X311021Y89964D03*
X317714D03*
X321061Y87392D03*
Y73757D03*
X307992Y70400D03*
X304278Y90414D03*
X307592Y73800D03*
X300982Y84714D03*
X294289D03*
X300982Y73849D03*
X294289D03*
X308166Y87394D03*
X297635Y90414D03*
X341140Y35957D03*
X337793Y65814D03*
Y54857D03*
X351179Y46922D03*
X347833Y54857D03*
X341140Y46922D03*
X347833Y65822D03*
X351179Y35957D03*
X347833Y92757D03*
X351179Y84599D03*
Y73757D03*
X337793Y89964D03*
X341140Y87392D03*
Y73757D03*
X326592Y105600D03*
X300992Y112300D03*
X297642Y107700D03*
X304192Y105000D03*
X294899Y213009D03*
X308418Y201309D03*
X317428Y193507D03*
X301648Y194841D03*
X332078Y218860D03*
X329818Y214958D03*
X298279Y218860D03*
X311798Y211060D03*
Y218860D03*
Y214960D03*
X308418Y213009D03*
X305039Y211060D03*
Y218860D03*
X324200Y201308D03*
X298279Y199360D03*
X294899Y201309D03*
X312918Y205210D03*
X315178Y209109D03*
X298279Y207159D03*
Y203260D03*
Y211060D03*
X318558Y218860D03*
X315178Y216909D03*
Y213009D03*
X301659Y209109D03*
X325318Y211060D03*
X338838Y218860D03*
X345598Y214960D03*
X352357D03*
X334328Y199108D03*
X345598Y203260D03*
X355737Y205210D03*
X335458Y216909D03*
X294899Y224709D03*
X332078Y242260D03*
Y250060D03*
X328698Y232509D03*
Y220809D03*
X332078Y234460D03*
X298279Y246160D03*
X325318Y250060D03*
X321938Y248109D03*
X305039Y246160D03*
X308418Y244209D03*
X294899D03*
Y248109D03*
X325318Y242260D03*
Y226660D03*
X298279Y234460D03*
X308418Y228610D03*
Y224709D03*
X305039Y230559D03*
X311798Y222760D03*
X308418Y232509D03*
X294899Y228610D03*
X325318Y234460D03*
Y230559D03*
Y222760D03*
X305039Y250060D03*
X318558Y246160D03*
X301659Y248109D03*
X308418Y240309D03*
X315178D03*
X301659D03*
X318558Y242260D03*
X298279Y226660D03*
X318558D03*
X315178Y220809D03*
X321938D03*
X315178Y232509D03*
X301659Y228610D03*
X308418Y236409D03*
X321938D03*
X311798Y238360D03*
X318558D03*
X305039Y226660D03*
X308418Y252009D03*
X298279Y253960D03*
X325318D03*
X308418Y275409D03*
X301659D03*
X308418Y255909D03*
X321938Y275409D03*
X315178Y279310D03*
X318558Y277360D03*
X311798Y261760D03*
X321938Y259809D03*
X301659D03*
X308418Y263709D03*
X325318Y269560D03*
X305039D03*
X318558D03*
X328698Y267609D03*
Y259809D03*
X332078Y269560D03*
X321938Y255909D03*
X308418Y259809D03*
X325318Y273460D03*
Y265660D03*
X301659Y267609D03*
X321938Y263709D03*
X294899Y275409D03*
Y263709D03*
X298279Y265660D03*
X305039Y273460D03*
Y277360D03*
X311798D03*
Y269560D03*
X305039Y265660D03*
X298279Y277360D03*
X328698Y252009D03*
X342218Y244209D03*
Y232509D03*
X355737Y244209D03*
X348978D03*
X345598Y226660D03*
X352357D03*
X348978Y232509D03*
X355737D03*
X338838Y246160D03*
X335458Y248109D03*
X338838Y242260D03*
Y234460D03*
X335458Y236409D03*
X338838Y238360D03*
X335458Y224709D03*
X355737Y248109D03*
X348978D03*
X338838Y253960D03*
X335458Y252009D03*
X338838Y265660D03*
X335458Y259809D03*
Y267609D03*
X345598Y265660D03*
X348978Y263709D03*
X355737Y259809D03*
X352357Y261760D03*
X345598Y273460D03*
Y269560D03*
X342218Y263709D03*
Y271509D03*
Y259809D03*
Y255909D03*
Y267609D03*
Y279310D03*
Y275409D03*
X311798Y292959D03*
X305039D03*
X321938Y283209D03*
X315178D03*
X318558Y281260D03*
Y292959D03*
X311798Y285160D03*
X328698Y310509D03*
X332078Y300760D03*
X328698Y283209D03*
X332078Y292959D03*
Y281260D03*
X298279Y308560D03*
X321938Y310509D03*
X315178D03*
X305039Y308560D03*
X311798D03*
X305039Y300760D03*
X325318D03*
X311798D03*
X298279D03*
X318558D03*
X325318Y292959D03*
Y281260D03*
X305039Y285160D03*
X298279D03*
Y292959D03*
X318558Y312460D03*
X325318D03*
X308418Y333909D03*
Y341709D03*
X325318Y339760D03*
Y335860D03*
X301659Y337809D03*
X315178Y330009D03*
X301659D03*
X308418Y337809D03*
X305039Y331960D03*
X298279Y328060D03*
Y331960D03*
X311798Y324160D03*
X308418Y330009D03*
X315178Y322209D03*
X321938D03*
X294899Y333909D03*
X305039Y328060D03*
X321938Y330009D03*
Y337809D03*
X328698Y330009D03*
Y326110D03*
Y333909D03*
X325318Y324160D03*
X318558Y320260D03*
X301659Y318309D03*
X308418D03*
X305039Y316360D03*
X332078Y331960D03*
Y339760D03*
X298279Y316360D03*
X294899Y322209D03*
Y318309D03*
X311798Y316360D03*
X308418Y326110D03*
X315178Y314409D03*
X332078Y312460D03*
X335458Y310509D03*
X338838Y300760D03*
Y292959D03*
Y281260D03*
X335458Y283209D03*
X342218Y310509D03*
Y283209D03*
X345598Y335860D03*
Y331960D03*
X342218Y314409D03*
X338838Y312460D03*
Y316360D03*
X335458Y330009D03*
X338838Y331960D03*
Y339760D03*
X345598Y328060D03*
Y339760D03*
X352357Y335860D03*
X348978Y333909D03*
X342218Y322209D03*
Y318309D03*
Y330009D03*
Y326110D03*
Y333909D03*
X355737Y337809D03*
X345598Y320260D03*
Y324160D03*
X308418Y357309D03*
X311798Y359260D03*
X298279Y351460D03*
X294899Y349509D03*
Y353409D03*
X321938Y349509D03*
X318558Y359260D03*
X321938Y361209D03*
X298279Y343660D03*
X315178Y357309D03*
X301659D03*
Y349509D03*
X308418Y361209D03*
Y353409D03*
Y345609D03*
X305039Y347560D03*
X325318Y343660D03*
Y347560D03*
X328698Y365109D03*
X332078Y363160D03*
X328698Y345609D03*
X325318Y355360D03*
X332078Y347560D03*
Y355360D03*
X294899Y369010D03*
X325318Y367060D03*
Y370959D03*
X318558D03*
X308418Y365109D03*
X315178D03*
X325318Y363160D03*
X298279D03*
X305039Y370959D03*
X308418Y369010D03*
X305039Y367060D03*
X301659Y369010D03*
X298279Y370959D03*
X318558Y351460D03*
Y355360D03*
X305039Y351460D03*
X301659Y388509D03*
X308418D03*
X318558Y394359D03*
X324458Y399911D03*
X332078Y378760D03*
X318558Y386560D03*
X325318D03*
X311798Y374860D03*
X325318D03*
X294899Y372909D03*
X308418D03*
X321938Y376809D03*
X318558Y382660D03*
Y378760D03*
X298279D03*
X305039D03*
X308418Y384609D03*
X311798Y382660D03*
Y378760D03*
X315178Y376809D03*
X328698D03*
X294899Y384609D03*
X318558Y390460D03*
X320808Y401941D03*
X298279Y386560D03*
Y390460D03*
X315178Y392410D03*
Y388509D03*
X311798Y386560D03*
X298279Y398260D03*
Y394359D03*
X294899Y396309D03*
X325318Y378760D03*
X321938Y380709D03*
X305039Y394359D03*
X302608Y402421D03*
X345598Y370959D03*
X355737Y353409D03*
X348978D03*
X342218Y365109D03*
X338838Y347560D03*
X335458Y361209D03*
X338838Y359260D03*
Y355360D03*
Y351460D03*
X335458Y349509D03*
X348978D03*
X345598Y343660D03*
X342218Y345609D03*
X355737Y349509D03*
X342218Y353409D03*
X338838Y367060D03*
X348978Y365109D03*
X355737D03*
X352357Y370959D03*
X338838Y382660D03*
X345598D03*
X352357D03*
X348978Y392410D03*
X355737D03*
X335458Y372909D03*
Y384609D03*
Y380709D03*
X294289Y490444D03*
X301092Y490700D03*
X326797Y499767D03*
X317714Y515364D03*
X321061Y512792D03*
X311701Y499136D03*
X331100Y510114D03*
X327754Y518157D03*
X314368Y512792D03*
X311021Y515364D03*
X297835Y497644D03*
X308166Y512794D03*
X300982Y510114D03*
X304278Y515814D03*
X297635D03*
X294289Y510114D03*
X304392Y497300D03*
X337793Y515364D03*
X350882Y509999D03*
X347833Y518157D03*
X341140Y512792D03*
X321061Y536957D03*
X317714Y529014D03*
X331100Y547914D03*
Y536957D03*
X327754Y529014D03*
X321061Y547914D03*
X314368D03*
Y536957D03*
X311021Y529014D03*
X307675Y536957D03*
X304328Y530949D03*
X300982Y537049D03*
X297635Y530949D03*
X294289Y537049D03*
X307992Y533100D03*
X327754Y555857D03*
X317714D03*
X311021D03*
X327754Y566814D03*
X331100Y574757D03*
Y585714D03*
X314368D03*
Y574757D03*
X317714Y566814D03*
X311021D03*
X321061Y585714D03*
Y574757D03*
X337793Y529014D03*
X351179Y547922D03*
Y536957D03*
X347833Y529022D03*
X341140Y547922D03*
Y536957D03*
X337793Y555857D03*
X347833D03*
X337793Y566814D03*
X341140Y574757D03*
Y585722D03*
X351179Y574757D03*
Y585722D03*
X347833Y566822D03*
X327754Y607292D03*
X331100Y609864D03*
X327754Y593657D03*
X317714D03*
X311021D03*
X317714Y604614D03*
X311021D03*
X314368Y612457D03*
X321061D03*
X337793Y593657D03*
Y604499D03*
X352109Y609918D03*
X347833Y607292D03*
X341140Y612457D03*
X347833Y593657D03*
X377592Y-10880D03*
X380232Y-10900D03*
X357872Y-9786D03*
X367911D03*
Y-1858D03*
X357872D03*
X367911Y9114D03*
X357672D03*
X357872Y28014D03*
X367911D03*
Y17042D03*
X357872Y17014D03*
X398029Y-4536D03*
X401375Y-7108D03*
X408068Y-1743D03*
X411415Y-9786D03*
X398029Y9107D03*
X408069D03*
X409522Y-20794D03*
X411416Y17057D03*
X401376Y17042D03*
X367911Y46914D03*
Y54842D03*
Y35942D03*
X358619Y36031D03*
X358618Y54842D03*
X357872Y65736D03*
X366992Y65950D03*
X357872Y46914D03*
X357965Y92500D03*
X367911Y87500D03*
X368311Y92500D03*
X367742Y73450D03*
X357872Y87500D03*
X358491Y73479D03*
X408069Y35942D03*
X401376Y54842D03*
X408069Y46907D03*
X398029Y35942D03*
Y46907D03*
X411416Y54857D03*
X401375Y92757D03*
X398029Y84800D03*
Y73742D03*
X408068Y87392D03*
X411415Y89964D03*
X408069Y73742D03*
X408126Y105750D03*
X414820Y105800D03*
X401375D03*
X357987Y193507D03*
X378267D03*
X386157Y207159D03*
X382777Y201309D03*
X365877Y214960D03*
X372637D03*
X379397D03*
X359117D03*
X365877Y203260D03*
X376017Y205211D03*
X362497Y205210D03*
X386157Y214960D03*
X415634Y204496D03*
Y212296D03*
X404392Y199100D03*
X415634Y208397D03*
X392898Y195041D03*
X392916Y214960D03*
Y203260D03*
X396296Y197359D03*
X399676Y203260D03*
Y214960D03*
X386157Y226660D03*
X389537Y232509D03*
X369257Y244209D03*
X362497D03*
X372637Y226660D03*
X365877D03*
X369257Y232509D03*
X362497D03*
X379397Y226660D03*
X382777Y232509D03*
X376017D03*
X359117Y226660D03*
X372637Y250060D03*
X365877Y253960D03*
X362497Y255909D03*
X359117Y257860D03*
X390894Y264899D03*
X369257Y252009D03*
X407706Y240309D03*
Y232509D03*
X415634Y247396D03*
Y235696D03*
Y223996D03*
X392916Y226660D03*
X396296Y232509D03*
X399676Y226660D03*
X397394Y264899D03*
X400394D03*
X393894D03*
X407448Y338641D03*
X416448D03*
X413948D03*
X410948D03*
X370650Y312441D03*
X378156D03*
X375674D03*
X373162Y312400D03*
X368165Y312504D03*
X359117Y339760D03*
X362497Y341709D03*
X403648Y338341D03*
X401148D03*
X398148D03*
X394648D03*
X379397Y347560D03*
Y370959D03*
X372637D03*
X365877D03*
X359117D03*
X386157D03*
X362497Y353409D03*
X376017D03*
X369257D03*
Y345609D03*
X376017D03*
X372637Y347560D03*
X365877Y343660D03*
X389537Y365109D03*
X382777D03*
X369257D03*
X362497D03*
X376017D03*
X390657Y394359D03*
X391787Y402800D03*
X357987D03*
X369257Y392410D03*
X362497D03*
X379397Y382660D03*
X372637D03*
X365877D03*
X359117D03*
X379397Y390460D03*
X378267Y402800D03*
X376017Y392410D03*
X386157Y382660D03*
X411086Y351460D03*
X392916Y370959D03*
X399676D03*
X396296Y365109D03*
X403056D03*
Y357309D03*
X392916Y382660D03*
Y390460D03*
X399676Y382660D03*
X406568Y402471D03*
X403056Y392410D03*
X411086Y374860D03*
X386630Y521860D03*
X359042Y515200D03*
X358918Y510114D03*
X366865D03*
Y515152D03*
X401375Y518157D03*
X398029Y509999D03*
X411415Y515364D03*
X408068Y512792D03*
X370080Y555700D03*
X366890Y586000D03*
X367692Y547914D03*
X357672D03*
X357872Y528942D03*
X367911Y529057D03*
X367692Y536200D03*
X357910Y536727D03*
X367211Y555842D03*
X357910D03*
X367192Y566814D03*
X357910D03*
X367192Y574742D03*
X357872D03*
X357025Y585714D03*
X398029Y536942D03*
X408069Y547907D03*
Y536942D03*
X398029Y547907D03*
X401376Y555842D03*
X411416Y555857D03*
X398029Y574742D03*
Y585707D03*
X408069D03*
Y574742D03*
X408068Y612657D03*
X413324Y623559D03*
X399824D03*
X357872Y604614D03*
X367170Y611759D03*
X357872Y612242D03*
X367911Y593642D03*
X357026D03*
X367911Y604614D03*
X398029Y609864D03*
X401376Y593642D03*
X401375Y607292D03*
X411416Y593657D03*
X411415Y604614D03*
X418108Y-4536D03*
X431494D03*
X424801D03*
X428147Y-7108D03*
X434840D03*
X431494Y9107D03*
X424801D03*
X418108D03*
Y-9701D03*
X441533Y-1843D03*
Y9107D03*
X447744Y-7180D03*
X451573Y-1801D03*
Y9114D03*
X436392Y-20760D03*
X422892Y-20789D03*
X434842Y17057D03*
X441533Y17042D03*
X418108D03*
X428149Y17057D03*
X448226Y28100D03*
X448292Y31900D03*
Y13700D03*
X448892Y17000D03*
X418108Y28007D03*
X441533D03*
X458266Y-1751D03*
X460912Y-7700D03*
X454533Y-7851D03*
X458116Y9114D03*
X469832Y-2051D03*
X464732Y-1801D03*
X474998Y-1751D03*
X469845Y-9864D03*
X478344Y-7851D03*
X464758Y-9652D03*
X474998Y9114D03*
X464732Y9098D03*
X478344Y29949D03*
X460912Y30100D03*
Y14814D03*
X469832Y17114D03*
X454569Y14714D03*
X454533Y29949D03*
X469792Y9300D03*
X478344Y14814D03*
X469845Y27936D03*
X464792Y28100D03*
X464692Y16900D03*
X434842Y54857D03*
X441533Y54842D03*
X424801Y46907D03*
X431494D03*
X428149Y54857D03*
X441533Y46907D03*
X448414Y35761D03*
X448973Y54883D03*
X451573Y35999D03*
X448627Y68090D03*
X448517Y46975D03*
X448492Y51000D03*
X451573Y46900D03*
X418108Y65807D03*
Y54842D03*
X441533Y65807D03*
X431494Y35942D03*
X441533D03*
X424801D03*
X418108D03*
Y46907D03*
X428147Y92500D03*
X424801Y84800D03*
X431400D03*
X431494Y73742D03*
X441533Y87392D03*
Y92500D03*
Y73742D03*
X418108Y89964D03*
Y84599D03*
Y73742D03*
X424801D03*
X434840Y92500D03*
X448651Y70896D03*
X451573Y84714D03*
Y73799D03*
X448610Y85296D03*
X448599Y73589D03*
X448692Y89900D03*
X474998Y36049D03*
X464732Y46898D03*
X460912Y52614D03*
X458266Y36049D03*
X458116Y46914D03*
X464758Y65950D03*
X474998Y46914D03*
X454533Y67749D03*
X454569Y52514D03*
X469832Y54914D03*
X469792Y47100D03*
Y35800D03*
X464692Y54700D03*
X464732Y35999D03*
X478344Y52614D03*
X460912Y67900D03*
X478344Y67749D03*
X469845Y65736D03*
X458116Y84714D03*
X464708Y92500D03*
X464732Y84698D03*
X469808Y84700D03*
X474998Y73849D03*
X469858Y73550D03*
X474998Y84714D03*
X478344Y90414D03*
X469832Y92714D03*
X460912Y90314D03*
X464732Y73799D03*
X458266Y73849D03*
X454569Y90314D03*
X427696Y105800D03*
X421503D03*
X441743Y199841D03*
X421464Y199583D03*
X446253Y206446D03*
X425974D03*
X453013Y218147D03*
X449633Y212296D03*
Y216196D03*
X422594D03*
X419214Y214247D03*
X436113Y212296D03*
X432733Y214247D03*
X429354Y216196D03*
X432733Y218147D03*
X425974D03*
X429353Y212296D03*
X446253Y218147D03*
X442873Y216196D03*
X439493Y214247D03*
X436113Y216196D03*
X453013Y214247D03*
X439493Y210346D03*
X434983Y198931D03*
X455263Y198050D03*
X473292Y218147D03*
X469913Y216196D03*
X469912Y212296D03*
X475692Y199900D03*
X466533Y218147D03*
X473292Y214247D03*
X476672Y212296D03*
Y216196D03*
X459773Y214247D03*
X466533Y206446D03*
X456393Y216196D03*
X462023Y198327D03*
X456393Y212296D03*
X463153Y216196D03*
X429354Y251296D03*
X453013Y245447D03*
Y229847D03*
Y237647D03*
X449633Y251296D03*
Y247396D03*
Y227896D03*
Y223996D03*
X436113Y243496D03*
X442873D03*
X422594D03*
X425974Y245447D03*
Y249347D03*
X432733D03*
X436113Y251296D03*
X429354Y247396D03*
X422594Y251296D03*
X446253Y245447D03*
X419214Y249347D03*
X432733Y245447D03*
X439493Y237647D03*
X446253D03*
X422594Y223996D03*
Y231797D03*
X419214Y233746D03*
Y237647D03*
X436113Y231797D03*
X439493Y241547D03*
X419214D03*
X436113Y223996D03*
X429354D03*
Y220096D03*
Y227896D03*
X446253Y229847D03*
X432733D03*
X425974D03*
X439493Y233746D03*
X442873Y231797D03*
Y223996D03*
X425974Y237647D03*
X432733D03*
X449633Y220096D03*
X439493Y253247D03*
X449633Y255196D03*
Y259096D03*
X446253Y257147D03*
X442873Y255196D03*
X453013Y257147D03*
Y261047D03*
X448900Y269600D03*
X469913Y251296D03*
X466533Y245447D03*
X473292D03*
X476672Y223996D03*
Y243496D03*
Y251296D03*
X469913Y247396D03*
Y223996D03*
X473292Y229847D03*
X469913Y227896D03*
X466533Y229847D03*
X473292Y237647D03*
X466533D03*
X469913Y220096D03*
X456393Y243496D03*
Y251296D03*
X459773Y233746D03*
Y241547D03*
Y237647D03*
X456393Y223996D03*
Y231797D03*
X476672D03*
X463153Y243496D03*
Y251296D03*
Y231797D03*
Y223996D03*
X476672Y259096D03*
X463153D03*
X458408Y278940D03*
X477792Y272747D03*
X462023Y271097D03*
X458643Y269146D03*
X456393Y262996D03*
Y259096D03*
X459773Y261047D03*
X469913Y255196D03*
X473292Y257147D03*
X466533D03*
X468783Y274997D03*
X469913Y270796D03*
X466533Y264947D03*
X426494Y338361D03*
X430089Y338428D03*
X419400Y338600D03*
X469913Y305896D03*
X477792Y307851D03*
X469913Y286396D03*
X477792Y303947D03*
Y288347D03*
Y315647D03*
Y319547D03*
X458643Y338746D03*
X477792Y327347D03*
X462948Y315251D03*
X455263Y340697D03*
X462848Y312741D03*
X467653Y340996D03*
X474413D03*
Y337096D03*
X469913Y321496D03*
X443993Y358547D03*
X441743Y348497D03*
X440613Y352696D03*
X437233Y358547D03*
X450753Y366347D03*
Y350747D03*
Y358547D03*
X437233Y362447D03*
X423714D03*
X433854Y368296D03*
X427094D03*
X440613Y364396D03*
X427094Y372197D03*
X447373D03*
Y368296D03*
X440613Y372197D03*
Y368296D03*
X443993Y366347D03*
X427094Y356596D03*
X433854Y352696D03*
X437233Y354647D03*
X423714D03*
X430474D03*
X427094Y360496D03*
X433854D03*
X445123Y346546D03*
X427094Y352696D03*
X430474Y385847D03*
X450753Y397547D03*
X440613Y395595D03*
X429354Y399496D03*
X433854Y379996D03*
X423714Y374146D03*
X437233D03*
X430474Y378047D03*
X433854Y376096D03*
X443993Y397546D03*
Y401447D03*
Y393647D03*
X440613Y391696D03*
X443993Y385847D03*
X427094Y376096D03*
X437233Y381947D03*
X447373Y376096D03*
X440613Y379996D03*
X443993Y378047D03*
X423715Y397548D03*
X430474Y393647D03*
X433854Y391696D03*
X423715Y401449D03*
X450753Y385847D03*
Y393647D03*
Y378047D03*
X437233Y389747D03*
Y385847D03*
X423714D03*
X477792Y342947D03*
Y362447D03*
Y354647D03*
Y358547D03*
X457513Y362447D03*
X454133Y372197D03*
Y364396D03*
Y348796D03*
Y352696D03*
X464273Y366347D03*
X474413Y372197D03*
X471033Y366347D03*
X467653Y372197D03*
X474413Y364396D03*
X464273Y350747D03*
X474413Y348796D03*
X471033Y350747D03*
X474413Y352696D03*
X471033Y358547D03*
X464273D03*
X467653Y368296D03*
Y348796D03*
X460893Y372197D03*
Y364396D03*
Y352696D03*
X457513Y354647D03*
Y358547D03*
Y346847D03*
X477792Y389747D03*
X457513D03*
X471033Y393647D03*
X460893Y395595D03*
X464273Y401447D03*
X471033D03*
X460893Y391696D03*
X457513Y385847D03*
Y381947D03*
X460893Y379996D03*
X477792Y381947D03*
X474413Y391696D03*
X464273Y385847D03*
X454133Y391696D03*
Y379996D03*
X471033Y385847D03*
X464273Y393647D03*
X474413Y379996D03*
X471033Y378047D03*
X467653Y376096D03*
X464273Y378047D03*
Y397546D03*
X477792Y385847D03*
X447091Y407782D03*
X428224Y407800D03*
X443993Y405347D03*
X467653Y407296D03*
X464273Y405347D03*
X441533Y512792D03*
Y518057D03*
X433192Y497650D03*
X434840Y518157D03*
X431494Y509999D03*
X424801Y510114D03*
X418108Y515364D03*
Y509999D03*
X428147Y518157D03*
X451573Y510114D03*
X448692Y515300D03*
X447735Y512794D03*
X474998Y510114D03*
X464732Y510098D03*
X460912Y515714D03*
X458116Y510114D03*
X454569Y515714D03*
X478344Y515814D03*
X464708Y517900D03*
X469832Y518114D03*
X418108Y536942D03*
Y547907D03*
X431494D03*
X424801D03*
X441533D03*
X418108Y529007D03*
X431494Y536942D03*
X424801D03*
X441533Y536957D03*
Y529007D03*
X451573Y547914D03*
Y536999D03*
X448410Y531156D03*
X448432Y536723D03*
X448692Y553100D03*
X448557Y534061D03*
X451573Y585714D03*
Y574799D03*
X418108Y555842D03*
X428149Y555857D03*
X434842D03*
X441533Y555842D03*
Y585707D03*
Y574742D03*
X418108Y566807D03*
X441533D03*
X424801Y574742D03*
X418108Y585599D03*
Y574742D03*
X431494D03*
Y585707D03*
X424801D03*
X464732Y536999D03*
X460912Y553514D03*
X458116Y547914D03*
X454569Y553514D03*
X454533Y530949D03*
X460912Y531100D03*
X458266Y537049D03*
X469845Y528936D03*
X474998Y537049D03*
X464758Y529150D03*
X469858Y536750D03*
X478344Y553614D03*
X464732Y547898D03*
X474998Y547914D03*
X469808Y547900D03*
X478344Y530949D03*
Y568749D03*
X464732Y574799D03*
X469808Y585700D03*
X469858Y574550D03*
X474998Y574849D03*
Y585714D03*
X464732Y585698D03*
X464758Y566950D03*
X469845Y566736D03*
X458266Y574849D03*
X460912Y568900D03*
X458116Y585714D03*
X454533Y568749D03*
X464708Y555700D03*
X469832Y555914D03*
X441533Y612557D03*
X474998Y612649D03*
X464732Y612599D03*
X458266Y612649D03*
X427324Y623541D03*
X451573Y612599D03*
X441533Y607292D03*
X434840D03*
X428147D03*
X418108Y609864D03*
X424801D03*
X448692Y590900D03*
X431494Y609864D03*
X418108Y593642D03*
X434842Y593657D03*
X428149D03*
X441533Y593642D03*
X418108Y604499D03*
X478344Y591414D03*
X464708Y593500D03*
X469832Y593714D03*
X464758Y604750D03*
X469845Y604536D03*
X478344Y606549D03*
X469858Y612350D03*
X460912Y591314D03*
Y606700D03*
X454533Y606549D03*
X454569Y591314D03*
X511809Y-1751D03*
Y9114D03*
X495077Y-1751D03*
X501544Y-1801D03*
X506692Y-2000D03*
X488384Y-1801D03*
X481691Y-1751D03*
X485037Y-7851D03*
X491344D03*
X506657Y-9864D03*
X497723Y-7700D03*
X501592Y-9700D03*
X481691Y9114D03*
X494927D03*
X488384D03*
X501544Y9098D03*
X497723Y14814D03*
X506644Y17114D03*
X506657Y27936D03*
X497723Y30100D03*
X491380Y14714D03*
X506604Y9300D03*
X485037Y14814D03*
X501504Y16900D03*
X485037Y29949D03*
X491344D03*
X501603Y28100D03*
X515155Y-7851D03*
X538355Y9098D03*
X518502Y-1751D03*
X521848Y-7851D03*
X538355Y-1801D03*
X531888Y-1751D03*
X525195Y-1801D03*
X538403Y-9700D03*
X528155Y-7851D03*
X534534Y-7700D03*
X518502Y9114D03*
X531738D03*
X525195D03*
X521848Y14814D03*
Y29949D03*
X528191Y14714D03*
X538315Y16900D03*
X534534Y30100D03*
X515155Y29949D03*
Y14814D03*
X534534D03*
X528155Y29949D03*
X538415Y28100D03*
X488384Y35999D03*
X501492Y54700D03*
X497723Y52614D03*
Y67900D03*
X501544Y46898D03*
X511809Y46914D03*
X491344Y67749D03*
X506657Y65736D03*
X501570Y65950D03*
X481691Y36049D03*
X495077D03*
X506644Y54914D03*
X494927Y46914D03*
X485037Y52614D03*
X481691Y46914D03*
X511809Y36049D03*
X485037Y67749D03*
X488384Y46914D03*
X506603Y35800D03*
X506592Y47000D03*
X501544Y35999D03*
X511809Y84714D03*
X501544Y84698D03*
X494927Y84714D03*
X506670Y73550D03*
X481691Y84714D03*
X488384D03*
X501520Y92500D03*
X506620Y84700D03*
X511809Y73849D03*
X488384Y73799D03*
X481691Y73849D03*
X506644Y92714D03*
X491380Y90314D03*
X497723Y90414D03*
X485037D03*
X495077Y73849D03*
X501544Y73799D03*
X518502Y36049D03*
Y46914D03*
X521848Y67749D03*
X531888Y36049D03*
X538355Y35999D03*
X534534Y52614D03*
X531738Y46914D03*
X525195Y35999D03*
X515155Y67749D03*
Y52614D03*
X521848D03*
X534534Y67900D03*
X538381Y65950D03*
X528155Y67749D03*
X538355Y46898D03*
X538304Y54700D03*
X525195Y46914D03*
X515155Y90414D03*
X534534D03*
X528191Y90314D03*
X521848Y90414D03*
X518502Y73849D03*
Y84714D03*
X531738D03*
X525195D03*
X538355Y84698D03*
X538331Y92500D03*
X531888Y73849D03*
X525195Y73799D03*
X538355D03*
X512024Y104314D03*
X497723Y109564D03*
X501544Y113114D03*
X506670Y112865D03*
X501570Y105265D03*
X491430Y109564D03*
X506657Y105051D03*
X488634Y104314D03*
X495077D03*
X514820Y109564D03*
X521113D03*
X528191Y109914D03*
X534534Y109564D03*
X538355Y113114D03*
X531738Y104314D03*
X525134D03*
X538381Y105265D03*
X518467Y104314D03*
X511592Y206447D03*
Y210346D03*
Y218147D03*
X486812Y214247D03*
Y218147D03*
X498350Y209900D03*
X501452Y212296D03*
X480052Y214247D03*
Y206447D03*
X486812Y210346D03*
X508212Y212296D03*
X518352Y218147D03*
Y206445D03*
X538631Y210346D03*
Y214247D03*
Y206447D03*
X528491Y208397D03*
X525111Y218147D03*
X528491Y216196D03*
X535251Y204496D03*
X525111Y206447D03*
X531871D03*
X521731Y208397D03*
X511592Y241547D03*
Y249347D03*
X486812Y245447D03*
X494692Y247396D03*
X483432Y251296D03*
X501452Y247396D03*
X480052Y237647D03*
X508212Y239596D03*
X498072Y233746D03*
X486812D03*
Y229847D03*
X494692Y235696D03*
X504832Y229847D03*
X486812Y225947D03*
X498072Y222047D03*
Y225947D03*
X486812Y222047D03*
Y237647D03*
X480052Y233746D03*
X504832Y241547D03*
X480052D03*
X486812D03*
X494692Y243496D03*
X483432D03*
X504832Y245447D03*
X501452Y223996D03*
X508212Y231797D03*
Y220096D03*
Y223996D03*
X483432Y235696D03*
Y223996D03*
X494692Y251296D03*
X501452Y274696D03*
X508212Y278596D03*
X484552Y268847D03*
X494692Y255196D03*
X486812Y257147D03*
X504832Y253247D03*
X487932Y278596D03*
Y274696D03*
X494692Y278596D03*
X501452Y266896D03*
Y259096D03*
X483432D03*
X481172Y274696D03*
Y278596D03*
X508212Y270796D03*
X494692D03*
X480052Y261047D03*
X518352Y229847D03*
X521731Y231797D03*
Y235696D03*
Y247396D03*
Y220096D03*
X538631Y225947D03*
Y222047D03*
Y237647D03*
X528491Y247396D03*
Y243496D03*
X538631Y249347D03*
X535251Y235696D03*
X528491Y227896D03*
Y235696D03*
Y220096D03*
X535251Y247396D03*
Y251296D03*
Y239596D03*
X531871Y222047D03*
X525111Y237647D03*
X514972Y247396D03*
Y227896D03*
Y235696D03*
Y239596D03*
Y223996D03*
X535251Y259096D03*
X531871Y261047D03*
X514972Y270796D03*
Y278596D03*
X525111Y253247D03*
X518352D03*
X528491Y274696D03*
X531871Y268847D03*
Y276646D03*
X535251Y266896D03*
X525111Y280547D03*
X521731Y266896D03*
Y259096D03*
Y274696D03*
X538631Y257147D03*
X504832Y307847D03*
X525111Y315647D03*
X494692Y294196D03*
X501452Y290296D03*
Y282496D03*
X491312Y292245D03*
Y300047D03*
X508212Y290296D03*
Y294196D03*
X511592Y307847D03*
Y284447D03*
X481172Y309797D03*
X494692D03*
X481172Y301996D03*
X487932Y309797D03*
X498072Y303947D03*
X487932Y282496D03*
X484552Y300047D03*
Y292245D03*
X494692Y286396D03*
X501452Y298096D03*
X481172Y290296D03*
X508212Y329296D03*
X487932Y317596D03*
X504832Y319547D03*
X484552Y323446D03*
X508212Y317596D03*
Y325396D03*
X491312Y339047D03*
X494692Y337096D03*
X511592Y327347D03*
Y339047D03*
Y331247D03*
Y335147D03*
Y315647D03*
Y323446D03*
X508212Y313696D03*
X481172D03*
X494692Y340996D03*
X504832Y331247D03*
X508212Y337096D03*
Y333196D03*
X504832Y335147D03*
X501452Y333196D03*
X504832Y339047D03*
X501452Y340996D03*
X504832Y315647D03*
X498072Y319547D03*
X504832Y323446D03*
X498072Y327347D03*
X491312Y331247D03*
X511592Y319547D03*
X538631Y311747D03*
X535251Y290296D03*
X514972Y301996D03*
Y290296D03*
Y286396D03*
Y294196D03*
X525111Y284447D03*
X531871Y288347D03*
Y292245D03*
X528491Y294196D03*
X525111Y300047D03*
X531871D03*
X521731Y301996D03*
X528491Y286396D03*
Y298096D03*
X535251Y294196D03*
X538631Y292245D03*
Y288347D03*
Y284447D03*
X531871Y303947D03*
X535251Y301996D03*
X531871Y311747D03*
Y307847D03*
X535251Y309797D03*
X514972Y333196D03*
Y321496D03*
Y317596D03*
Y329296D03*
Y325396D03*
Y337096D03*
X518352Y319547D03*
Y323446D03*
Y315647D03*
X521731Y317596D03*
Y325396D03*
X518352Y327347D03*
Y339047D03*
X531871Y335147D03*
X525111D03*
X528491Y337096D03*
X531871Y327347D03*
X535251Y329296D03*
X538631Y335147D03*
Y339047D03*
X528491Y317596D03*
X531871Y319547D03*
X535251Y321496D03*
X538631Y319547D03*
X504832Y342947D03*
X491312Y370247D03*
X498072Y366347D03*
X494692Y372197D03*
X504832Y366347D03*
X501452Y368296D03*
X487932D03*
X484552Y362447D03*
X498072D03*
X491312D03*
X494692Y360496D03*
X487932D03*
X501452Y344896D03*
X504832Y354647D03*
X494692Y344896D03*
Y348796D03*
X491312Y350747D03*
Y366347D03*
X487932Y372197D03*
X484552Y370247D03*
X481172Y372197D03*
X484552Y366347D03*
X487932Y364396D03*
X494692D03*
X501452D03*
X491312Y358547D03*
X498072Y350747D03*
Y346847D03*
X501452Y360496D03*
X498072Y342947D03*
X491312Y346847D03*
X494692Y356596D03*
X498072Y358547D03*
Y354647D03*
X481172Y344896D03*
Y360496D03*
X484552Y346847D03*
X508212Y352696D03*
Y360496D03*
X504832Y346847D03*
Y358547D03*
X501452Y356596D03*
Y348796D03*
Y352696D03*
X511592Y370247D03*
X481172Y352696D03*
X484552Y393647D03*
X481172Y391696D03*
X484552Y385847D03*
X498072Y393647D03*
X494692Y391696D03*
X491312Y385847D03*
X498072D03*
X508212Y387796D03*
X501452Y391696D03*
Y395597D03*
X491312Y389747D03*
X504832Y381947D03*
Y378047D03*
X501452Y379996D03*
X481172Y395596D03*
X511592Y378047D03*
Y397546D03*
X491312Y378047D03*
X484552D03*
X481172Y379996D03*
X487932Y376096D03*
X491312Y381947D03*
Y374146D03*
X498072Y397546D03*
X487932Y403396D03*
Y399496D03*
X491312Y397546D03*
X487932Y395597D03*
X514972Y372197D03*
Y356596D03*
X521731Y360496D03*
Y356596D03*
Y348796D03*
X518352Y342947D03*
Y362447D03*
X521731Y372197D03*
X518352Y370247D03*
X525111Y354647D03*
X531871Y346847D03*
X535251Y356596D03*
X538631Y366347D03*
X528491Y364396D03*
X525111Y342947D03*
X514972Y403396D03*
Y379996D03*
X531871Y374146D03*
X521731Y399496D03*
X518352Y397546D03*
Y389747D03*
X535251Y383896D03*
X525111Y381947D03*
X538631Y393647D03*
Y378047D03*
X528491Y403396D03*
X531871Y401447D03*
Y389747D03*
X525111Y393647D03*
X484552Y405347D03*
X538750Y406200D03*
X511712Y495800D03*
X488384Y495887D03*
X494777D03*
X491380Y493744D03*
X506644Y490867D03*
X501560D03*
X497723Y493494D03*
X506620Y510100D03*
X506644Y518114D03*
X501544Y510098D03*
X485037Y515814D03*
X481691Y510114D03*
X491380Y515714D03*
X511809Y510114D03*
X497723Y515814D03*
X494927Y510114D03*
X488384D03*
X501520Y517900D03*
X506644Y498867D03*
X501560D03*
X514755Y491044D03*
X521048Y491144D03*
X538370Y490609D03*
X528241Y490944D03*
X534534Y490794D03*
X515155Y515814D03*
X530792Y495787D03*
X524595D03*
X517892Y495800D03*
X534534Y515814D03*
X528191Y515714D03*
X531738Y510114D03*
X525195D03*
X538355Y510098D03*
X538331Y517900D03*
X521848Y515814D03*
X518502Y510114D03*
X538370Y498609D03*
X506670Y536750D03*
X501570Y529150D03*
X506657Y528936D03*
X501544Y536999D03*
X511809Y547914D03*
Y537049D03*
X491380Y553514D03*
X497723Y553614D03*
X485037D03*
X506620Y547900D03*
X501544Y547898D03*
X481691Y547914D03*
X494927D03*
X488384D03*
X481691Y537049D03*
X491344Y530949D03*
X488384Y536999D03*
X495077Y537049D03*
X497723Y531100D03*
X485037Y530949D03*
Y568749D03*
X481691Y574849D03*
Y585714D03*
X501544Y585698D03*
Y574799D03*
X506657Y566736D03*
X501570Y566950D03*
X506670Y574550D03*
X506620Y585700D03*
X488384Y585714D03*
X511809D03*
Y574849D03*
X494927Y585714D03*
X491344Y568749D03*
X501520Y555700D03*
X506644Y555914D03*
X497723Y568900D03*
X488384Y574799D03*
X495077Y574849D03*
X515155Y553614D03*
Y530949D03*
X534534Y531100D03*
X531888Y537049D03*
X528155Y530949D03*
X525195Y536999D03*
X538355D03*
X538381Y529150D03*
X525195Y547914D03*
X531738D03*
X538355Y547898D03*
X534534Y553614D03*
X528191Y553514D03*
X518502Y547914D03*
X521848Y553614D03*
X518502Y537049D03*
X521848Y530949D03*
X515155Y568749D03*
X538331Y555700D03*
X518502Y585714D03*
Y574849D03*
X521848Y568749D03*
X538355Y585698D03*
Y574799D03*
X538381Y566950D03*
X531738Y585714D03*
X525195D03*
X534534Y568900D03*
X525195Y574799D03*
X528155Y568749D03*
X531888Y574849D03*
X525195Y612599D03*
X518502Y612649D03*
X538355Y612599D03*
X531888Y612649D03*
X501544Y612599D03*
X495077Y612649D03*
X488384Y612599D03*
X511809Y612649D03*
X497723Y591414D03*
X486250Y591020D03*
X491380Y591314D03*
X501520Y593500D03*
X506644Y593714D03*
X501570Y604750D03*
X506657Y604536D03*
X491344Y606549D03*
X497723Y606700D03*
X485037Y607230D03*
X506670Y612350D03*
X480950Y612430D03*
X515155Y606549D03*
Y591414D03*
X521848D03*
Y606549D03*
X534534Y591414D03*
X528191Y591314D03*
X538331Y593500D03*
X538381Y604750D03*
X534534Y606700D03*
X528155Y606549D03*
X562006Y9114D03*
X568549D03*
X555313D03*
X548620D03*
X571345Y-7700D03*
X551966Y-7851D03*
X564966D03*
X558659D03*
X562006Y-1801D03*
X555313Y-1751D03*
X568699D03*
X548620D03*
X543503Y-2000D03*
X543468Y-9864D03*
X543455Y17114D03*
X564992Y14714D03*
X543415Y9300D03*
X558659Y14814D03*
Y29949D03*
X551966Y14814D03*
Y29949D03*
X564966D03*
X571345Y14814D03*
Y30100D03*
X543468Y27936D03*
X575166Y9098D03*
X602163Y16999D03*
X575214Y-9700D03*
X575166Y-1801D03*
X580279Y-9864D03*
X580314Y-2000D03*
X588777Y-7851D03*
X598817Y-9901D03*
X595470Y-7851D03*
X592124Y-1751D03*
X598817D03*
X585431D03*
X602163Y-9901D03*
X598817Y9157D03*
X592124Y9114D03*
X585431D03*
X575182Y16900D03*
X575192Y28100D03*
X580192Y9300D03*
X588777Y29949D03*
X580279Y27936D03*
X595470Y29949D03*
Y14814D03*
X598817Y27899D03*
X588777Y14814D03*
X580266Y17114D03*
X562006Y46914D03*
X551966Y52614D03*
X565352Y52864D03*
X548620Y46914D03*
Y36049D03*
X558659Y52614D03*
X568699Y36049D03*
X555313D03*
X562006Y35999D03*
X551966Y67749D03*
X564966D03*
X571345Y52614D03*
Y67900D03*
X558659Y67749D03*
X568549Y46914D03*
X555313D03*
X543468Y65736D03*
X543404Y47000D03*
X543415Y35800D03*
X543455Y54914D03*
Y92714D03*
X548620Y84714D03*
X568549D03*
X555313D03*
X562006D03*
X543481Y73550D03*
X543431Y84700D03*
X548620Y73849D03*
X568699D03*
X562006Y73799D03*
X555313Y73849D03*
X558659Y90414D03*
X551966D03*
X571345D03*
X575166Y46898D03*
Y35999D03*
X575192Y65950D03*
X585431Y46914D03*
X595470Y52614D03*
X588777D03*
X585431Y36049D03*
X592124D03*
X598817D03*
Y46957D03*
X592124Y46914D03*
X598817Y65699D03*
X595470Y67749D03*
X588777D03*
X580266Y54914D03*
X580192Y35750D03*
X580279Y65736D03*
X602163Y65699D03*
X592124Y84714D03*
X585431D03*
X598817Y84757D03*
X580242Y84700D03*
X580266Y92714D03*
X588777Y90414D03*
X602163Y92599D03*
X575166Y73799D03*
X575142Y92500D03*
X575166Y84698D03*
X595470Y90414D03*
X585431Y73849D03*
X592124D03*
X598817D03*
X580292Y73550D03*
X548620Y104314D03*
X555313D03*
X558659Y110014D03*
X551966D03*
X543481Y112865D03*
X543468Y105051D03*
X602100Y109600D03*
X555531Y216196D03*
X557000Y206800D03*
X548771Y212296D03*
X552151Y214247D03*
X547800Y201400D03*
X545391Y210346D03*
X552151Y218147D03*
Y225947D03*
X558911Y222047D03*
X552151Y233746D03*
X548771Y235696D03*
X558911Y229847D03*
X552151D03*
X562591Y220096D03*
X564084Y235685D03*
X545391Y225947D03*
Y222047D03*
Y233746D03*
X542011Y239596D03*
Y247396D03*
X552151Y241547D03*
X548771Y239596D03*
X552151Y249347D03*
X555531Y247396D03*
X562591Y251296D03*
X548771Y243496D03*
X562591D03*
X572930Y232750D03*
Y228130D03*
X552151Y257147D03*
X562591Y255196D03*
X548771D03*
X573200Y262600D03*
X573100Y258600D03*
X548771Y266896D03*
X558911Y264947D03*
X563800Y275900D03*
X559211Y280547D03*
X548771Y278596D03*
X558911Y272747D03*
X555531Y274696D03*
X564500Y264800D03*
Y268800D03*
X552151Y261047D03*
X545391Y272747D03*
Y280547D03*
Y264947D03*
Y268847D03*
X542011Y274696D03*
X580360Y234590D03*
Y230060D03*
X545391Y307847D03*
X555831Y309797D03*
Y305896D03*
X548771Y309797D03*
X555831Y298096D03*
X552151Y284447D03*
X548771Y286396D03*
X552151Y288347D03*
Y296147D03*
X558145Y286727D03*
X545391Y296147D03*
Y288347D03*
Y292245D03*
Y300047D03*
X542011Y294196D03*
Y298096D03*
X545391Y303947D03*
X548771Y313696D03*
X561971Y317320D03*
X548771Y325396D03*
X558911Y335147D03*
X555531Y333196D03*
X562591D03*
X548771Y340996D03*
X561966Y325502D03*
X559211Y319547D03*
X552151Y323446D03*
X545391Y319547D03*
X542011Y321496D03*
X545391Y335147D03*
Y331247D03*
Y315647D03*
X552151Y350747D03*
X558911Y342947D03*
X559212Y370247D03*
X548771Y368296D03*
X562591Y352696D03*
Y344896D03*
X563200Y356596D03*
X545391Y354647D03*
Y346847D03*
X542011Y368296D03*
X545391Y366347D03*
Y358547D03*
X542011Y360496D03*
Y348796D03*
X559212Y374146D03*
X555531Y387797D03*
X559212Y381947D03*
Y393647D03*
X552151Y378047D03*
X545391Y397546D03*
Y385847D03*
X542011Y376096D03*
X573867Y459903D03*
X575614Y461694D03*
X584076Y443828D03*
X588285Y448306D03*
X586136Y446335D03*
X558659Y493444D03*
X551366Y490744D03*
X543455Y490909D03*
X555313Y510114D03*
X548492Y495800D03*
X554792Y495887D03*
X543431Y510100D03*
X543455Y518114D03*
X551966Y515814D03*
X548620Y510114D03*
X543455Y498909D03*
X568549Y510114D03*
X562006D03*
X571345Y515814D03*
X558659D03*
X582912Y468948D03*
X581032Y467202D03*
X575166Y510098D03*
X575142Y517900D03*
X580266Y518114D03*
X580242Y510100D03*
X598817Y510157D03*
X595470Y515814D03*
X588777D03*
X602163Y517999D03*
X592124Y510114D03*
X585431D03*
X543468Y528936D03*
X543481Y536750D03*
X543431Y547900D03*
X548620Y547914D03*
X551966Y553614D03*
X548620Y537049D03*
X551966Y530949D03*
X558659D03*
X555313Y537049D03*
X562006Y536999D03*
X564966Y530949D03*
X568699Y537049D03*
X571345Y553614D03*
Y531100D03*
X558659Y553614D03*
X555313Y547914D03*
X568549D03*
X562006D03*
X543455Y555914D03*
X571345Y568900D03*
X564966Y568749D03*
X562006Y574799D03*
X555313Y585714D03*
Y574849D03*
X558659Y568749D03*
X568549Y585714D03*
X562006D03*
X568699Y574849D03*
X551966Y568749D03*
X548620Y574849D03*
Y585714D03*
X543481Y574550D03*
X543431Y585700D03*
X543468Y566736D03*
X575166Y547898D03*
X575192Y529150D03*
X575166Y536999D03*
X598817Y547957D03*
X592124Y547914D03*
X595470Y530949D03*
X580242Y547900D03*
X580279Y528936D03*
X580292Y536750D03*
X592124Y537049D03*
X588777Y530949D03*
X598817Y528899D03*
Y537049D03*
X602163Y528899D03*
X585431Y547914D03*
Y537049D03*
X588777Y553614D03*
X595470D03*
X580279Y566736D03*
X585431Y574849D03*
Y585714D03*
X598817Y585757D03*
Y574849D03*
Y566699D03*
X592124Y585714D03*
X595470Y568749D03*
X588777D03*
X592124Y574849D03*
X575142Y555700D03*
X575192Y566950D03*
X575166Y585698D03*
Y574799D03*
X580266Y555914D03*
X580292Y574550D03*
X580242Y585700D03*
X575166Y612599D03*
X585431Y612649D03*
X592124D03*
X598817D03*
X555313D03*
X562006Y612599D03*
X568699Y612649D03*
X548620D03*
X571345Y591414D03*
X558659D03*
X571345Y606700D03*
X558659Y606549D03*
X564966D03*
X551966D03*
Y591414D03*
X543455Y593714D03*
X543468Y604536D03*
X543481Y612350D03*
X580292D03*
X580266Y593714D03*
X595470Y591414D03*
X588777D03*
X598817Y604499D03*
X595470Y606549D03*
X588777D03*
X575192Y604750D03*
X575142Y593500D03*
X602163Y593599D03*
Y604499D03*
X580279Y604536D03*
X620092Y13078D03*
X620192Y31978D03*
Y-5822D03*
X647317Y-1310D03*
X660676Y-2600D03*
X651300Y20000D03*
X659200Y31500D03*
X651300Y17500D03*
X620070Y50878D03*
X620192Y69778D03*
X620092Y88678D03*
X663500Y48000D03*
X663700Y65600D03*
X663476Y45296D03*
X616115Y108339D03*
X622200Y112200D03*
X616167Y118627D03*
X605300Y124600D03*
X630000Y126572D03*
X624500Y129400D03*
X626900Y128300D03*
X633580Y125560D03*
X661700Y142300D03*
X636481Y124951D03*
X635951Y127419D03*
X661053Y115971D03*
X658490Y115432D03*
X650307Y115518D03*
X647809Y116121D03*
X645311Y116724D03*
X650120Y122700D03*
X660900Y123650D03*
Y126650D03*
X647120Y122700D03*
X657900Y126650D03*
Y123650D03*
X651920Y125750D03*
X656111Y121550D03*
X653111D03*
X654558Y115101D03*
X640043Y117728D03*
X639100Y124200D03*
X638800Y126700D03*
X648690Y125590D03*
X643674Y123573D03*
X644950Y125750D03*
X641950D03*
X642899Y117112D03*
X632500Y238500D03*
Y235000D03*
X632692Y248172D03*
X632532Y241717D03*
X630200Y248100D03*
X633308Y263808D03*
X662800Y248600D03*
X643500Y272262D03*
X659900Y256900D03*
Y269200D03*
X652000Y284500D03*
X663200Y298600D03*
X644800Y292150D03*
X654500Y298600D03*
X652100Y288300D03*
X639045Y299555D03*
X639100Y309500D03*
X649000Y339400D03*
X638790Y329500D03*
X639350Y339980D03*
X639100Y319500D03*
X655900Y307700D03*
X656300Y312300D03*
X660700Y307700D03*
X655900Y316500D03*
X656000Y329800D03*
X655900Y320500D03*
X656000Y325100D03*
X660900Y329800D03*
X664100Y348000D03*
X648800D03*
X658900D03*
X662936Y367171D03*
X659936Y364171D03*
X662936D03*
X654000Y348000D03*
X634200Y436800D03*
X637300Y437200D03*
X625430Y490100D03*
X607012Y465997D03*
X623660Y466746D03*
X632113Y496892D03*
X619392Y514700D03*
X656900Y482290D03*
X649600Y492400D03*
X660500Y492000D03*
X652000Y513900D03*
X655000D03*
X661500D03*
X658500D03*
X620192Y532978D03*
X618892Y555800D03*
X618292Y574300D03*
X651750Y584150D03*
X653100Y587000D03*
X618192Y593600D03*
X620033Y608878D03*
X660230Y598170D03*
X674300Y9847D03*
X671800D03*
X669300D03*
X673900Y23100D03*
X671400D03*
X668900D03*
X690000Y15300D03*
X683800Y24856D03*
X670430Y29253D03*
X716858Y-14448D03*
X717720Y23279D03*
X715114Y26395D03*
X704500Y26300D03*
X714337Y7852D03*
Y5352D03*
Y2852D03*
X718555Y-16147D03*
X666500Y48000D03*
X665100Y68600D03*
X668100D03*
X666700Y65600D03*
X678020Y69870D03*
X678300Y92630D03*
Y95130D03*
X675630Y94988D03*
X681300Y95130D03*
Y92630D03*
X684300D03*
X687400Y93900D03*
X673830Y83050D03*
X676430D03*
X676500Y80500D03*
X673900D03*
X674010Y77970D03*
X676610D03*
X692200Y83800D03*
X695000Y67000D03*
X699880Y66840D03*
X724200Y64730D03*
X722460Y69550D03*
X713680Y60910D03*
X700360Y72160D03*
X694910Y72220D03*
X713050Y63650D03*
X710440Y63710D03*
X704880Y66750D03*
X697747Y72184D03*
X723700Y67400D03*
X713620Y58270D03*
X715800Y59490D03*
Y57000D03*
X713590Y53260D03*
X713610Y55730D03*
X700640Y69500D03*
X703120Y69380D03*
X702380Y66840D03*
X697440Y66900D03*
X699800Y89100D03*
X713830Y82730D03*
X692000Y45000D03*
Y48500D03*
X697500D03*
Y45000D03*
X664700Y142800D03*
X675600Y144900D03*
Y150000D03*
X679900Y128200D03*
X682400Y127085D03*
X684900D03*
X673566Y116724D03*
X676494Y116940D03*
X668665Y118185D03*
X671249Y118744D03*
X677896Y119093D03*
X674896D03*
X715505Y155076D03*
X720700Y154750D03*
X725650Y155000D03*
X691583Y200124D03*
X689033D03*
X686533D03*
Y196624D03*
X689033D03*
X691583D03*
X715550Y158880D03*
X705550D03*
X710550D03*
X709200Y198700D03*
X720369Y205199D03*
X716557Y198557D03*
X692513Y213800D03*
X692673Y206200D03*
X692500Y210100D03*
X690861Y211917D03*
Y215717D03*
X692400Y218100D03*
X690861Y204317D03*
Y208117D03*
X706500Y217400D03*
Y214900D03*
X719315Y239104D03*
X669900Y224000D03*
X672500Y224100D03*
X678454Y278000D03*
X675380Y246340D03*
X678000Y246400D03*
X668100Y232200D03*
X667240Y246600D03*
X672530Y246300D03*
X677400Y232300D03*
X674300Y232200D03*
X675200Y224100D03*
X667600Y250200D03*
X688643Y225980D03*
X688388Y231280D03*
X678400Y224100D03*
X690380Y252240D03*
X690939Y266630D03*
X693530Y261240D03*
X690660Y264000D03*
X690704Y271324D03*
X671100Y232200D03*
X701800Y246480D03*
X669750Y246350D03*
X710572Y244773D03*
X719360Y241504D03*
X710627Y242061D03*
X702000Y243900D03*
X722050Y221150D03*
X707653Y226347D03*
X718300Y227400D03*
X700900Y264100D03*
X694361Y223317D03*
Y220817D03*
X690861D03*
Y223317D03*
X672300Y269200D03*
X672200Y256800D03*
X706561Y219917D03*
X719900Y269300D03*
X725500Y279300D03*
X725300Y269400D03*
X719600Y279400D03*
X704175Y287275D03*
X704214Y290775D03*
X680000Y281900D03*
X672150Y288350D03*
X695300Y338100D03*
X695400Y328000D03*
X684100Y338200D03*
X695400Y318000D03*
X695800Y308000D03*
X696088Y297069D03*
X704500Y293800D03*
X707130Y310150D03*
X718200Y295000D03*
X706300Y318400D03*
X678200Y307800D03*
X672700Y307700D03*
X667100D03*
X678100Y324800D03*
X672200Y329800D03*
X678100Y329600D03*
X666900Y329700D03*
X678200Y313700D03*
Y319300D03*
X679000Y348000D03*
X688600Y365100D03*
X671936Y367171D03*
X665936Y370171D03*
X684900Y348000D03*
X674600D03*
X671936Y370171D03*
X665936Y367171D03*
X668936Y370171D03*
Y367171D03*
X665936Y364171D03*
X668936D03*
X669093Y348120D03*
X671936Y373171D03*
X668936D03*
X670300Y375600D03*
X713900Y347800D03*
X698560Y374430D03*
X713900Y342800D03*
Y352800D03*
Y350300D03*
Y345300D03*
X690040Y412030D03*
X685600Y432500D03*
X690600D03*
Y437500D03*
X703876Y414949D03*
X705850Y417093D03*
X710600Y420267D03*
X710423Y417423D03*
X708346Y415859D03*
X708011Y419078D03*
X712980Y417900D03*
X713493Y420449D03*
X723748Y499091D03*
X676900Y489400D03*
X666500Y487600D03*
Y484600D03*
X669500D03*
Y481600D03*
X664610Y512810D03*
X685050Y503970D03*
X704500Y512850D03*
X716267Y522020D03*
X703028Y495600D03*
X709028D03*
X706028D03*
X703028Y492600D03*
X706028D03*
X674200Y588900D03*
X690100Y575860D03*
X689193Y573493D03*
X693126Y581380D03*
X671599Y573493D03*
X671791Y588920D03*
X674099Y573493D03*
X669099D03*
X668891Y588900D03*
X713650Y540750D03*
X715650Y542250D03*
Y545250D03*
X713650Y546750D03*
X708000Y553250D03*
X720200Y551750D03*
X715650Y551250D03*
X696000Y553250D03*
X715650Y548250D03*
X713650Y549750D03*
X723200Y551750D03*
X699000Y553250D03*
X702000D03*
X705000D03*
X713650Y543750D03*
X723200Y554750D03*
X706500Y555750D03*
X703500D03*
X700500D03*
X720200Y554750D03*
X709500Y555750D03*
X712600Y571900D03*
X716300Y569400D03*
X707500Y587800D03*
X691900Y531350D03*
Y534850D03*
X697500Y534750D03*
Y531250D03*
X725173Y598171D03*
X724106Y609550D03*
X721106D03*
X708900Y589850D03*
X706100D03*
X732600Y3600D03*
X755500Y8700D03*
X753600Y-4300D03*
X736715Y33487D03*
X734201Y33510D03*
X726250Y23550D03*
X731457Y8471D03*
X732335Y6000D03*
X786414Y-9650D03*
X779771Y9114D03*
X773228D03*
Y-1801D03*
X779921Y-1751D03*
X776188Y-7851D03*
X769881Y-9901D03*
X782567Y-7700D03*
X786388Y9098D03*
Y-1801D03*
X786414Y28150D03*
X769881Y27899D03*
X782567Y14814D03*
Y30100D03*
X769881Y16839D03*
X776224Y14714D03*
X776188Y29949D03*
X786364Y16900D03*
X736631Y36122D03*
X736655Y38531D03*
X731887Y40916D03*
X734155Y38531D03*
X734131Y36122D03*
X731843Y43571D03*
X756100Y36200D03*
X755500Y46700D03*
X737800Y55800D03*
X751708Y73800D03*
X755500Y84361D03*
X786388Y35999D03*
X786364Y54700D03*
X786388Y46898D03*
X773228Y46914D03*
X779771D03*
X776188Y67749D03*
X769881Y66000D03*
X782567Y67900D03*
Y52614D03*
X769881Y54839D03*
X779921Y35983D03*
X773228D03*
X776224Y52514D03*
X769881Y92500D03*
X773228Y84714D03*
X779771D03*
X776224Y90314D03*
X782567Y90414D03*
X779921Y73849D03*
X773228Y73799D03*
X786414Y65950D03*
X786388Y73799D03*
X786364Y92500D03*
X786388Y84698D03*
X730600Y154984D03*
X746000Y150500D03*
X740718Y150957D03*
X769100Y102900D03*
X758400Y156200D03*
X747600Y161450D03*
X740650Y164800D03*
X735600Y164900D03*
X740650Y158800D03*
X754726Y205037D03*
X752226D03*
X749726D03*
X754726Y207537D03*
X752226D03*
X749726D03*
X742937Y218574D03*
X758400Y159200D03*
X774582Y212033D03*
X770200Y208600D03*
X775171Y218616D03*
X787371Y215216D03*
Y217716D03*
X777700Y218600D03*
X727969Y236770D03*
X736612Y237908D03*
X727997Y239195D03*
X736625Y240308D03*
X742897Y229573D03*
X746303Y243122D03*
X746321Y240569D03*
X760304Y235827D03*
X768560Y244055D03*
X769019Y276400D03*
X762616Y270113D03*
X761480Y242720D03*
X731100Y269300D03*
Y279300D03*
X787371Y247216D03*
Y249716D03*
X775232Y221133D03*
X777700Y250600D03*
X775232Y223633D03*
X775171Y250616D03*
X775232Y253133D03*
Y255633D03*
X787371Y279216D03*
X774347Y339983D03*
X762760Y339500D03*
X727300Y302910D03*
X727474Y338363D03*
Y335363D03*
X732474D03*
Y338363D03*
X756114Y316209D03*
X729974Y338363D03*
Y335363D03*
X771278Y307918D03*
X762842Y302434D03*
X765730Y335064D03*
X777700Y282600D03*
X775232Y287633D03*
Y285133D03*
X775171Y282616D03*
X787371Y281716D03*
Y311216D03*
X777800Y314700D03*
X775171Y314616D03*
X787371Y313716D03*
X775232Y317133D03*
Y319633D03*
X727474Y344663D03*
Y367463D03*
X732474D03*
X729974D03*
X727474Y364863D03*
X732474D03*
X729974D03*
Y347663D03*
X727474D03*
X732474D03*
Y344663D03*
X727574Y373463D03*
X732574D03*
X730074D03*
X732574Y376063D03*
X730074D03*
X729974Y344663D03*
X731100Y362300D03*
X772443Y371976D03*
X760140Y362819D03*
X758952Y384100D03*
X763333Y400212D03*
X772300Y403520D03*
X775171Y346616D03*
X787371Y343216D03*
Y345716D03*
X775232Y349133D03*
X777600Y346600D03*
X775232Y351633D03*
X787321Y374916D03*
Y377316D03*
X775182Y383633D03*
Y381133D03*
X778000Y378700D03*
X775121Y378616D03*
X749640Y431797D03*
X728940Y457806D03*
X775417Y435799D03*
X777979Y436516D03*
X752496Y515974D03*
X732522Y526808D03*
Y524308D03*
X750518Y522108D03*
X734922Y526808D03*
X776224Y515714D03*
X779771Y510114D03*
X773228D03*
X769881Y517900D03*
X782567Y515814D03*
X786388Y510098D03*
X786364Y517900D03*
X732442Y529300D03*
X734842D03*
X736300Y541500D03*
X756000Y537000D03*
X737400Y529400D03*
X734900Y531800D03*
X732400D03*
X726200Y551750D03*
X754910Y556400D03*
X726200Y554750D03*
X727400Y571300D03*
X755000Y574800D03*
X752500Y585150D03*
X727106Y586550D03*
X773228Y536999D03*
X763677Y547783D03*
X776188Y530949D03*
X782567Y531100D03*
X769818Y529200D03*
X779921Y537049D03*
X782567Y553614D03*
X773228Y547914D03*
X779771D03*
X776224Y553514D03*
X786388Y536999D03*
X786414Y529150D03*
X786388Y547898D03*
X786364Y555700D03*
X769881D03*
X773228Y574799D03*
X782567Y568900D03*
X769700Y566900D03*
X776188Y568749D03*
X779921Y574849D03*
X773228Y585714D03*
X779771D03*
X786388Y574799D03*
Y585698D03*
X786414Y566950D03*
X779921Y612649D03*
X773228Y612599D03*
X786388D03*
X755000Y614500D03*
X727000Y606600D03*
X766600Y590700D03*
X769700Y604900D03*
X776188Y606549D03*
X782567Y606700D03*
Y591414D03*
X776224Y591314D03*
X786414Y604750D03*
X786364Y593500D03*
X803346Y-1751D03*
X810039Y-1801D03*
X791514Y-2050D03*
X791501Y-9864D03*
X812999Y-7851D03*
X806692D03*
X799999D03*
X816582Y9114D03*
X796653D03*
X791464Y9100D03*
X810039Y9114D03*
X803346D03*
X816732Y-1751D03*
X796653D03*
X799999Y29949D03*
X806692D03*
X812999D03*
X791501Y27936D03*
X791488Y17114D03*
X799999Y14814D03*
X813035Y14714D03*
X806692Y14814D03*
X828275Y9100D03*
X833464Y9114D03*
X840157D03*
X819378Y-7700D03*
X823199Y9098D03*
Y-1801D03*
X823225Y-9650D03*
X828312Y-9864D03*
X843503Y-7851D03*
X836810D03*
X846850Y-1801D03*
X828325Y-2050D03*
X833464Y-1751D03*
X840157D03*
X846850Y9114D03*
X819378Y14814D03*
Y30100D03*
X843503Y14814D03*
X823175Y16900D03*
X823225Y28150D03*
X828312Y27936D03*
X836810Y29949D03*
X828299Y17114D03*
X836810Y14814D03*
X843503Y29949D03*
X791488Y54914D03*
X799999Y52614D03*
X796653Y46914D03*
X791464Y46900D03*
X810039Y35999D03*
X803346Y36049D03*
X799999Y90414D03*
X791488Y92714D03*
X806692Y90414D03*
X816582Y46914D03*
X816732Y36049D03*
X799999Y67749D03*
X812999D03*
X806692D03*
X791501Y65736D03*
X803346Y46914D03*
X806692Y52614D03*
X813035Y52514D03*
X810039Y46914D03*
X791514Y35750D03*
X796653Y36049D03*
X816582Y73849D03*
X791514Y73550D03*
X796653Y73849D03*
X810039Y73799D03*
X803346Y73849D03*
X816582Y84714D03*
X813035Y90314D03*
X803346Y84714D03*
X810039D03*
X796653D03*
X791464Y84700D03*
X819378Y67900D03*
Y52614D03*
X846850Y35999D03*
X833464Y36049D03*
X840157D03*
X823225Y65950D03*
X823175Y54700D03*
X823199Y46898D03*
Y35999D03*
X828299Y54914D03*
X828275Y46900D03*
X828325Y35750D03*
X833464Y46914D03*
X836810Y52614D03*
X840157Y46914D03*
X828312Y65736D03*
X836810Y67749D03*
X843503D03*
X846850Y46914D03*
X843503Y52614D03*
X823175Y92500D03*
X823199Y84698D03*
X846850Y73799D03*
X843503Y90414D03*
X846850Y84714D03*
X828325Y73550D03*
X840157Y73849D03*
X833464D03*
X828299Y92714D03*
X836810Y90414D03*
X840157Y84714D03*
X833464D03*
X828275Y84700D03*
X819378Y90364D03*
X823199Y73799D03*
X790871Y215216D03*
Y217716D03*
X845100Y268200D03*
X847600D03*
X842600D03*
X847600Y243400D03*
X841400Y243300D03*
X847600Y238400D03*
X841400Y238300D03*
X847600Y240900D03*
X841400Y240800D03*
X789500Y231800D03*
X790900Y234000D03*
Y229700D03*
X790846Y225774D03*
X790882Y221723D03*
X790871Y247216D03*
Y249716D03*
X789471Y227742D03*
X789576Y223737D03*
X789554Y219723D03*
X790900Y253900D03*
X789432Y252000D03*
X790871Y266216D03*
X789432Y255800D03*
X790867Y257724D03*
X789432Y259800D03*
X789500Y263900D03*
X790885Y261711D03*
X790871Y279216D03*
X842600Y299900D03*
X845100D03*
X847600D03*
X845100Y331500D03*
X842600D03*
X847600D03*
X790871Y311216D03*
X789432Y284200D03*
Y288300D03*
Y292400D03*
X789400Y296200D03*
X790871Y298216D03*
X790937Y294270D03*
X790900Y290300D03*
Y286200D03*
X790871Y281716D03*
Y313716D03*
X789432Y319900D03*
Y323900D03*
X790900Y322000D03*
Y326000D03*
X790871Y330216D03*
X789500Y328000D03*
X789478Y315671D03*
X790800Y317700D03*
X847600Y363000D03*
X845100D03*
X842600D03*
X847577Y381842D03*
X789432Y348100D03*
Y352100D03*
X789597Y356105D03*
X789500Y360200D03*
X790900Y358200D03*
X790835Y354048D03*
X790867Y350024D03*
X790871Y345716D03*
Y343216D03*
Y362216D03*
X790821Y374916D03*
X790900Y389300D03*
X789500Y391300D03*
X790900Y393400D03*
Y381100D03*
X789582Y383200D03*
X790900Y385300D03*
X789500Y387300D03*
X790821Y377316D03*
X789282Y379200D03*
X816582Y510114D03*
X806692Y515814D03*
X813035Y515714D03*
X810039Y510114D03*
X791488Y518114D03*
X791464Y510100D03*
X799999Y515814D03*
X796653Y510114D03*
X803346D03*
X819378Y515764D03*
X843503Y515814D03*
X846850Y510114D03*
X823175Y517900D03*
X823199Y510098D03*
X828299Y518114D03*
X840157Y510114D03*
X833464D03*
X836810Y515814D03*
X816582Y537049D03*
Y547914D03*
X810039Y536999D03*
X806692Y530949D03*
X812999D03*
X803346Y537049D03*
X796653D03*
X799999Y530949D03*
X791501Y528936D03*
X791514Y536750D03*
X799999Y553614D03*
X810039Y547914D03*
X796653D03*
X803346D03*
X791464Y547900D03*
X806692Y553614D03*
X813035Y553514D03*
X791488Y555914D03*
X810039Y585714D03*
X806692Y568749D03*
X810039Y574799D03*
X812999Y568749D03*
X803346Y585714D03*
X796653D03*
X791514Y574550D03*
X791464Y585700D03*
X799999Y568749D03*
X796653Y574849D03*
X803346D03*
X791501Y566736D03*
X816582Y585714D03*
Y574849D03*
X819378Y553564D03*
Y531100D03*
X836810Y530949D03*
X833464Y537049D03*
X846850Y547914D03*
X833464D03*
X840157D03*
X828275Y547900D03*
X843503Y553614D03*
X836810D03*
X846850Y536999D03*
X843503Y530949D03*
X823199Y547898D03*
Y536999D03*
X823225Y529150D03*
X828325Y536750D03*
X840157Y537049D03*
X828312Y528936D03*
X819378Y568900D03*
X823175Y555700D03*
X828299Y555914D03*
X828275Y585700D03*
X823225Y566950D03*
X823199Y585698D03*
Y574799D03*
X828312Y566736D03*
X840157Y585714D03*
X833464D03*
X828325Y574550D03*
X840157Y574849D03*
X833464D03*
X836810Y568749D03*
X846850Y585714D03*
Y574799D03*
X843503Y568749D03*
X846850Y612599D03*
X840157Y612649D03*
X833464D03*
X823199Y612599D03*
X810039D03*
X803346Y612649D03*
X796653D03*
X816582D03*
X791514Y612350D03*
X806692Y606549D03*
X812999D03*
X799999D03*
X791501Y604536D03*
X806692Y591414D03*
X813035Y591314D03*
X799999Y591414D03*
X791488Y593714D03*
X819378Y606700D03*
Y591364D03*
X823225Y604750D03*
X823175Y593500D03*
X843503Y591414D03*
X828312Y604536D03*
X843503Y606549D03*
X836810D03*
X828325Y612350D03*
X836810Y591414D03*
X828299Y593714D03*
X870275Y9114D03*
X865086Y9100D03*
X860010Y9098D03*
X876968Y9114D03*
Y-1751D03*
X873621Y-7851D03*
X865123Y-9864D03*
X860036Y-9650D03*
X849810Y-7851D03*
X856189Y-7700D03*
X860010Y-1801D03*
X865136Y-2050D03*
X853543Y-1751D03*
X870275D03*
X853393Y9114D03*
X860036Y28150D03*
X859986Y16900D03*
X865110Y17114D03*
X856189Y14814D03*
X849846Y14714D03*
X873621Y14814D03*
Y29949D03*
X865123Y27936D03*
X849810Y29949D03*
X856189Y30100D03*
X896847Y-9650D03*
X910432Y-7851D03*
X883661Y-1801D03*
X880314Y-7851D03*
X886621D03*
X907086Y-1751D03*
X890354D03*
X896821Y-1801D03*
X901947Y-2050D03*
X901934Y-9864D03*
X893000Y-7700D03*
X883661Y9114D03*
X907086D03*
X896821Y9098D03*
X901897Y9100D03*
X890204Y9114D03*
X910432Y29949D03*
X896797Y16900D03*
X893000Y14814D03*
X901921Y17114D03*
X901934Y27936D03*
X893000Y30100D03*
X880314Y14814D03*
X886657Y14714D03*
X886621Y29949D03*
X880314D03*
X896847Y28150D03*
X910432Y14814D03*
X859986Y54700D03*
X870275Y36049D03*
X865136Y35750D03*
X865086Y46900D03*
X876968Y46914D03*
Y36049D03*
X873621Y67749D03*
Y52614D03*
X860010Y46898D03*
X860036Y65950D03*
X865123Y65736D03*
X849810Y67749D03*
X856189Y67900D03*
X853393Y46914D03*
X870275D03*
X865110Y54914D03*
X860010Y35999D03*
X856189Y52614D03*
X853543Y36049D03*
X849846Y52514D03*
X876968Y84714D03*
Y73849D03*
X873621Y90414D03*
X870275Y73849D03*
X853543D03*
X860010Y73799D03*
X849846Y90314D03*
X856189Y90414D03*
X865110Y92714D03*
X870275Y84714D03*
X865086Y84700D03*
X853393Y84714D03*
X860010Y84698D03*
X859986Y92500D03*
X865136Y73550D03*
X910432Y67749D03*
X893000Y67900D03*
X901934Y65736D03*
X896847Y65950D03*
X910432Y52614D03*
X890204Y46914D03*
X896821Y35999D03*
X901921Y54914D03*
X896797Y54700D03*
X883661Y35999D03*
X886621Y67749D03*
X880314D03*
X883661Y46914D03*
X880314Y52614D03*
X886657Y52514D03*
X901947Y35750D03*
X901897Y46900D03*
X896821Y46898D03*
X893000Y52614D03*
X890354Y36049D03*
X907086D03*
X883661Y73799D03*
X910432Y90414D03*
X907086Y84714D03*
X901897Y84700D03*
X907086Y46914D03*
X896821Y84698D03*
X893000Y90414D03*
X890204Y84714D03*
X896797Y92500D03*
X901921Y92714D03*
X890354Y73849D03*
X896821Y73799D03*
X901947Y73550D03*
X907086Y73849D03*
X883661Y84714D03*
X886657Y90314D03*
X880314Y90414D03*
X886657Y109884D03*
X907086Y104284D03*
X901934Y105051D03*
X896847Y105265D03*
X890204Y104284D03*
X893000Y109534D03*
X896821Y113114D03*
X901947Y112865D03*
X910432Y109984D03*
X883661Y104284D03*
X873621Y515814D03*
X876968Y510114D03*
X870275D03*
X859986Y517900D03*
X865086Y510100D03*
X860010Y510098D03*
X865110Y518114D03*
X853393Y510114D03*
X856189Y515814D03*
X849846Y515714D03*
X907000Y495800D03*
X882900Y495900D03*
X893000Y493094D03*
X886500Y493400D03*
X910432Y491044D03*
X901921Y490514D03*
X896785D03*
X901921Y498514D03*
X896785D03*
X889100Y498500D03*
X901897Y510100D03*
X893000Y515814D03*
X890204Y510114D03*
X896821Y510098D03*
X901921Y518114D03*
X896797Y517900D03*
X880314Y515814D03*
X886657Y515714D03*
X883661Y510114D03*
X910432Y515814D03*
X907086Y510114D03*
X860010Y536999D03*
X865123Y528936D03*
X873621Y530949D03*
Y553614D03*
X876968Y537049D03*
Y547914D03*
X860010Y547898D03*
X870275Y547914D03*
X853393D03*
X865086Y547900D03*
X856189Y553614D03*
X849846Y553514D03*
X870275Y537049D03*
X853543D03*
X856189Y531100D03*
X849810Y530949D03*
X865136Y536750D03*
X860036Y529150D03*
X849810Y568749D03*
X865086Y585700D03*
X860010Y585698D03*
X865136Y574550D03*
X859986Y555700D03*
X865110Y555914D03*
X860010Y574799D03*
X853393Y585714D03*
X870275D03*
X873621Y568749D03*
X876968Y574849D03*
Y585714D03*
X860036Y566950D03*
X865123Y566736D03*
X870275Y574849D03*
X853543D03*
X856189Y568900D03*
X890354Y537049D03*
X893000Y531100D03*
X896821Y536999D03*
X901934Y528936D03*
X901947Y536750D03*
X910432Y530949D03*
X907086Y537049D03*
X886621Y530949D03*
X883661Y536999D03*
X880314Y530949D03*
Y553614D03*
X886657Y553514D03*
X883661Y547914D03*
X893000Y553614D03*
X910432D03*
X890204Y547914D03*
X896821Y547898D03*
X901897Y547900D03*
X907086Y547914D03*
X880314Y568749D03*
X886621D03*
X883661Y574799D03*
Y585714D03*
X901921Y555914D03*
X896797Y555700D03*
X901934Y566736D03*
X896847Y566950D03*
X901897Y585700D03*
X890354Y574849D03*
X896821Y574799D03*
X893000Y568900D03*
X901947Y574550D03*
X896821Y585698D03*
X890204Y585714D03*
X910432Y568749D03*
X907086Y574849D03*
Y585714D03*
X890354Y612649D03*
X896821Y612599D03*
X883661D03*
X907086Y612649D03*
X870275D03*
X876968D03*
X860010Y612599D03*
X853543Y612649D03*
X859986Y593500D03*
X865110Y593714D03*
X856189Y591414D03*
X849846Y591314D03*
X860036Y604750D03*
X865123Y604536D03*
X856189Y606700D03*
X849810Y606549D03*
X865136Y612350D03*
X873621Y606549D03*
Y591414D03*
X886657Y591314D03*
X896847Y604750D03*
X901934Y604536D03*
X901947Y612350D03*
X896797Y593500D03*
X901921Y593714D03*
X893000Y591414D03*
X910432D03*
Y606549D03*
X893000Y606700D03*
X880314Y606549D03*
X886621D03*
X880314Y591414D03*
X923432Y-7851D03*
X929811Y-7700D03*
X933658Y-9650D03*
X917125Y-7851D03*
X913779Y-1751D03*
X933632Y-1801D03*
X927165Y-1751D03*
X920472Y-1801D03*
X927015Y9114D03*
X933632Y9098D03*
X913779Y9114D03*
X920472D03*
X923432Y29949D03*
X917125D03*
Y14814D03*
X929811D03*
X933608Y16900D03*
X923468Y14714D03*
X933658Y28150D03*
X929811Y30100D03*
X938745Y-9864D03*
X938758Y-2050D03*
X938708Y9100D03*
X947243Y-7851D03*
X950590Y-1751D03*
X953936Y-7851D03*
X943897Y-1751D03*
Y9114D03*
X950590D03*
X960629Y-9786D03*
X963976Y-1843D03*
X970669Y-1743D03*
X967322Y-9786D03*
X963976Y9114D03*
X970669D03*
X967322Y28014D03*
X960629Y17057D03*
Y28014D03*
X967322Y17057D03*
X938745Y27936D03*
X938732Y17114D03*
X953936Y14814D03*
Y29949D03*
X947243D03*
Y14814D03*
X933658Y65950D03*
X923432Y67749D03*
X929811Y67900D03*
X917125Y67749D03*
X920472Y35999D03*
X917125Y52614D03*
X913779Y46914D03*
Y36049D03*
X927015Y73849D03*
X913779D03*
X920472Y73799D03*
X933632D03*
X913779Y84714D03*
X920472D03*
X933608Y92500D03*
X920472Y46914D03*
X933632Y35999D03*
X927165Y36049D03*
X927015Y46914D03*
X933608Y54700D03*
X933632Y46898D03*
X929811Y52614D03*
X933632Y84698D03*
X927015Y84714D03*
X923468Y90314D03*
X929811Y90414D03*
X917125D03*
X953936Y52614D03*
X967322Y65814D03*
X960629D03*
X970669Y35957D03*
Y46914D03*
X967322Y54857D03*
X963976Y35957D03*
Y46914D03*
X960629Y54857D03*
X938758Y35750D03*
X938708Y46900D03*
X938732Y54914D03*
X938745Y65736D03*
X950590Y36049D03*
X953936Y67749D03*
X950590Y46914D03*
X947243Y67749D03*
X943897Y36049D03*
Y46914D03*
X947243Y52614D03*
X963976Y73757D03*
X960629Y89964D03*
X963976Y87392D03*
X967322Y89964D03*
X970669Y87392D03*
Y73757D03*
X938708Y84700D03*
X938732Y92714D03*
X938758Y73550D03*
X957600Y70400D03*
X943897Y84714D03*
X947243Y90414D03*
X943897Y73849D03*
X950590D03*
X953886Y90414D03*
X950590Y84714D03*
X957774Y87394D03*
X957200Y73800D03*
X933658Y105265D03*
X929811Y109534D03*
X933632Y113114D03*
X923468Y109884D03*
X917125Y109984D03*
X920472Y104284D03*
X913779D03*
X927015D03*
X938758Y112865D03*
X938745Y105051D03*
X947250Y107700D03*
X950600Y112300D03*
X953800Y105000D03*
X927607Y203260D03*
Y207159D03*
X934367D03*
Y199360D03*
X930987Y201309D03*
X934367Y214960D03*
X930987Y213009D03*
X920847Y211060D03*
X927607Y214960D03*
Y211060D03*
X937747Y216909D03*
X924227D03*
Y213009D03*
X968166Y218860D03*
X951256Y194841D03*
X958026Y201309D03*
X967036Y193507D03*
X947887Y203260D03*
Y207159D03*
X944507Y213009D03*
Y201309D03*
X947887Y199360D03*
X941127D03*
Y207159D03*
X947887Y211060D03*
Y218860D03*
X941127D03*
Y214960D03*
X962526Y205210D03*
X961406Y214960D03*
Y211060D03*
Y218860D03*
X951267Y209109D03*
X958026Y213009D03*
X954647Y211060D03*
Y218860D03*
X964786Y213009D03*
Y216909D03*
Y209109D03*
X934367Y226660D03*
X924227Y236409D03*
X920847Y238360D03*
X913787Y226660D03*
X913700Y222710D03*
X913787Y238360D03*
X924227Y232509D03*
X927607Y230559D03*
Y234460D03*
X930987Y232509D03*
X934367Y234460D03*
X924227Y228610D03*
X930987Y220809D03*
X924227Y224709D03*
X937747Y232509D03*
Y236409D03*
X924227Y240309D03*
X917467D03*
X930987D03*
X924227Y248109D03*
Y244209D03*
X917467D03*
X913787Y250060D03*
X934367Y246160D03*
X927607Y250060D03*
X924227Y220809D03*
X913787Y253960D03*
X927607D03*
X934367D03*
X937747Y252009D03*
X930987D03*
X924227D03*
X917467D03*
Y259809D03*
X924227D03*
X930987D03*
X920847Y265660D03*
X930987Y275409D03*
X937747D03*
Y271509D03*
Y255909D03*
X934367Y277360D03*
X930987Y271509D03*
X934367Y273460D03*
X927607Y269560D03*
X917467Y263709D03*
X913787Y265660D03*
X924227Y267609D03*
X934367Y265660D03*
X924227Y263709D03*
Y275409D03*
X927607Y277360D03*
X920847Y273460D03*
Y269560D03*
X924227Y255909D03*
X951267Y248109D03*
X958026Y244209D03*
X968166Y242260D03*
X944507Y228610D03*
Y224709D03*
Y244209D03*
Y248109D03*
X941127Y242260D03*
Y250060D03*
Y246160D03*
X947887D03*
X941127Y222760D03*
X947887Y226660D03*
Y234460D03*
X941127Y238360D03*
Y234460D03*
Y230559D03*
Y226660D03*
X971546Y248109D03*
X968166Y246160D03*
X951267Y240309D03*
X958026D03*
X964786D03*
X954647Y246160D03*
Y250060D03*
X958026Y228610D03*
Y236409D03*
X961406Y238360D03*
X951267Y228610D03*
X954647Y226660D03*
X958026Y224709D03*
Y232509D03*
X954647Y230559D03*
X961406Y222760D03*
X968166Y226660D03*
X971546Y236409D03*
X968166Y238360D03*
X971546Y220809D03*
X964786Y232509D03*
Y220809D03*
X947887Y253960D03*
X941127D03*
X958026Y252009D03*
X968166Y277360D03*
X951267Y275409D03*
X961406Y277360D03*
X958026Y263709D03*
X968166Y269560D03*
X961406Y261760D03*
X958026Y255909D03*
X951267Y259809D03*
X958026D03*
X954647Y277360D03*
Y265660D03*
X951267Y267609D03*
X954647Y273460D03*
X958026Y275409D03*
X954647Y269560D03*
X961406D03*
X971546Y275409D03*
Y263709D03*
X941127Y277360D03*
Y265660D03*
X944507Y275409D03*
Y263709D03*
X941127Y269560D03*
Y257860D03*
Y261760D03*
X947887Y277360D03*
Y265660D03*
X971546Y259809D03*
Y255909D03*
X964786Y279310D03*
X934367Y285160D03*
Y300760D03*
X927607D03*
Y308560D03*
X934367D03*
X927607Y285160D03*
Y292959D03*
X934367D03*
X937747Y318309D03*
Y341709D03*
Y326110D03*
X917467Y333909D03*
Y341709D03*
X913787Y339760D03*
X924227Y333909D03*
Y337809D03*
Y341709D03*
X913787Y328060D03*
X924227Y330009D03*
X920847Y328060D03*
X917467Y330009D03*
X930987Y326110D03*
X934367Y331960D03*
X927607Y328060D03*
X934367Y324160D03*
X924227Y322209D03*
X927607Y320260D03*
X930987Y318309D03*
X934367Y316360D03*
X927607D03*
X930987Y337809D03*
X924227Y326110D03*
X961406Y292959D03*
Y285160D03*
X954647Y292959D03*
Y285160D03*
X968166Y292959D03*
Y300760D03*
X971546Y310509D03*
X964786D03*
X954647Y308560D03*
X961406D03*
X954647Y300760D03*
X961406D03*
X964786Y283209D03*
X971546D03*
X947887Y308560D03*
X941127D03*
Y300760D03*
X947887D03*
X941127Y285160D03*
Y292959D03*
X947887D03*
Y285160D03*
X968166Y281260D03*
X958026Y333909D03*
Y337809D03*
Y341709D03*
Y318309D03*
X951267D03*
X954647Y316360D03*
X961406D03*
Y324160D03*
X971546Y337809D03*
X964786Y330009D03*
X971546D03*
X951267D03*
X958026D03*
X968166Y312460D03*
X964786Y314409D03*
X951267Y337809D03*
X954647Y331960D03*
Y328060D03*
X971546Y322209D03*
X968166Y320260D03*
X964786Y322209D03*
X958026Y326110D03*
X947887Y316360D03*
X941127D03*
X944507Y322209D03*
Y318309D03*
X947887Y331960D03*
Y328060D03*
X941127Y331960D03*
Y328060D03*
Y339760D03*
Y335860D03*
X944507Y333909D03*
X937747Y365109D03*
Y345609D03*
Y361209D03*
X924227Y365109D03*
X930987D03*
X927607Y367060D03*
X934367Y370959D03*
Y363160D03*
X927607D03*
X924227Y369010D03*
X913787Y343660D03*
X934367D03*
X927607D03*
Y347560D03*
X934367Y351460D03*
X930987Y357309D03*
Y345609D03*
X917467Y353409D03*
Y349509D03*
X913787Y355360D03*
X924227Y349509D03*
Y345609D03*
Y353409D03*
Y361209D03*
Y357309D03*
X920847Y355360D03*
X917167Y361209D03*
Y369010D03*
X934367Y382660D03*
X930987Y384609D03*
Y376809D03*
X934367Y390460D03*
X927607Y386560D03*
Y390460D03*
X930987Y396309D03*
X934367Y398260D03*
X927607Y394359D03*
X917467Y388509D03*
X924227Y392410D03*
X920847Y390460D03*
X924227Y372909D03*
X937747Y400209D03*
X917100Y380709D03*
X937747D03*
X924227D03*
X920847Y382660D03*
X924227Y376809D03*
X927607Y382660D03*
X968166Y370959D03*
X958026Y361209D03*
X954647Y347560D03*
X961406Y359260D03*
X958026Y357309D03*
X951267D03*
X941127Y355360D03*
Y347560D03*
Y351460D03*
X958026Y345609D03*
X951267Y349509D03*
X954647Y351460D03*
X958026Y353409D03*
X968166Y355360D03*
Y351460D03*
X964786Y357309D03*
X971546Y361209D03*
X968166Y359260D03*
X958026Y365109D03*
X964786D03*
X954647Y370959D03*
Y367060D03*
X958026Y369010D03*
X951267D03*
X971546Y349509D03*
X947887Y363160D03*
X941127D03*
X947887Y370959D03*
X941127D03*
Y367060D03*
X944507Y369010D03*
X947887Y343660D03*
X941127Y359260D03*
X944507Y349509D03*
Y353409D03*
X941127Y343660D03*
X947887Y351460D03*
X958026Y372909D03*
X941127Y374860D03*
X961406D03*
X944507Y372909D03*
X941127Y382660D03*
Y378760D03*
X947887D03*
X944507Y384609D03*
X947887Y390460D03*
Y386560D03*
X941127Y390460D03*
X947887Y398260D03*
X941127D03*
X944507Y396309D03*
X947887Y394359D03*
X964786Y376809D03*
X971546D03*
X968166Y378760D03*
Y386560D03*
X964786Y392410D03*
X968166Y390460D03*
Y394359D03*
X964786Y388509D03*
X961406Y378760D03*
X954647D03*
X958026Y384609D03*
X961406Y382660D03*
X951267Y388509D03*
X958026D03*
X954647Y394359D03*
X961406Y386560D03*
X952216Y402421D03*
X970416Y401941D03*
X971546Y380709D03*
X968166Y382660D03*
X920700Y495944D03*
X913800Y495800D03*
X927165Y495944D03*
X929811Y515814D03*
X933632Y510098D03*
X923600Y491144D03*
X917192Y491219D03*
X933632Y490644D03*
X929811D03*
X933632Y498644D03*
X933608Y517900D03*
X913779Y510114D03*
X917125Y515814D03*
X923468Y515714D03*
X920472Y510114D03*
X927015D03*
X938732Y490644D03*
X950700Y490700D03*
X943897Y490444D03*
X970669Y512792D03*
X967322Y515364D03*
X963976Y512792D03*
X960629Y515364D03*
X938708Y510100D03*
X938732Y518114D03*
Y498644D03*
X954000Y497300D03*
X953886Y515814D03*
X950590Y510114D03*
X943897D03*
X947243Y515814D03*
X947443Y497644D03*
X957774Y512794D03*
X961309Y499136D03*
X933632Y536999D03*
X929811Y531100D03*
X933658Y529150D03*
X913779Y537049D03*
X917125Y530949D03*
X927015Y537049D03*
X923432Y530949D03*
X920472Y536999D03*
X923468Y553514D03*
X917125Y553614D03*
X913779Y547914D03*
X927015D03*
X920472D03*
X933632Y547898D03*
X929811Y553614D03*
X933608Y555700D03*
X933632Y585698D03*
X933658Y566950D03*
X929811Y568900D03*
X933632Y574799D03*
X920472D03*
X927015Y585714D03*
X920472D03*
X913779Y574849D03*
X917125Y568749D03*
X913779Y585714D03*
X923432Y568749D03*
X927015Y574849D03*
X960629Y529014D03*
X963976Y536957D03*
X970669D03*
X967322Y529014D03*
X963976Y547914D03*
X970669D03*
X938745Y528936D03*
X938758Y536750D03*
X938708Y547900D03*
X957600Y533100D03*
X957701Y552000D03*
X950590Y537049D03*
X957283Y536957D03*
X953936Y530949D03*
X957283Y548200D03*
X953886Y553614D03*
X950590Y547914D03*
X947243Y530949D03*
X943897Y537049D03*
Y547914D03*
X947243Y553614D03*
X967322Y555857D03*
X960629D03*
X970669Y585714D03*
Y574757D03*
X960629Y566814D03*
X963976Y585714D03*
Y574757D03*
X967322Y566814D03*
X938732Y555914D03*
X938745Y566736D03*
X938758Y574550D03*
X938708Y585700D03*
X957600Y570900D03*
X950590Y574849D03*
Y585714D03*
X957283Y574757D03*
X957456Y588334D03*
X953936Y568749D03*
X943897Y574849D03*
X947243Y568749D03*
X943897Y585714D03*
X933632Y612599D03*
X923432Y606549D03*
X917125D03*
X933658Y604750D03*
X923468Y591314D03*
X917125Y591414D03*
X933608Y593500D03*
X929811Y591414D03*
X927015Y612449D03*
X920472Y612399D03*
X913779Y612449D03*
X929811Y606700D03*
X967322Y593657D03*
X963976Y612457D03*
X970669D03*
X960629Y604614D03*
X967322D03*
X960629Y593657D03*
X938758Y612350D03*
X938745Y604536D03*
X938732Y593714D03*
X957500Y591000D03*
X953936Y606549D03*
X957283Y611600D03*
X950590Y612249D03*
X953886Y591414D03*
X947243Y606549D03*
X943897Y612249D03*
X947243Y591414D03*
X980708Y-4536D03*
X987401Y-9901D03*
X997441Y-7108D03*
X990748Y-1743D03*
X977362Y-7108D03*
X980708Y9114D03*
X990748Y9122D03*
X977362Y28014D03*
X987401D03*
Y17057D03*
X977362D03*
X997441Y28022D03*
Y17057D03*
X1000787Y-4536D03*
Y9122D03*
X1017519Y-1858D03*
Y-9786D03*
X1007480Y-1858D03*
X1007280Y9114D03*
X1017519D03*
X1007480Y-9786D03*
Y17014D03*
Y28014D03*
X1017519D03*
Y17042D03*
X987401Y65814D03*
X977362D03*
X987401Y54857D03*
X977362D03*
X990748Y46922D03*
Y35957D03*
X980708D03*
Y46914D03*
X997441Y65822D03*
Y54857D03*
Y92757D03*
X990748Y73757D03*
Y87392D03*
X977362Y92757D03*
X987401Y89964D03*
X980708Y84714D03*
Y73757D03*
X1000787Y35957D03*
Y46922D03*
X1017519Y54842D03*
X1007480Y46914D03*
X1008226Y54842D03*
X1008217Y35942D03*
X1007480Y65736D03*
X1016600Y65950D03*
X1017519Y35942D03*
Y46914D03*
X1017919Y92500D03*
X1017519Y87500D03*
X1000787Y84599D03*
Y73757D03*
X1007480Y87500D03*
X1007573Y92500D03*
X1008099Y73479D03*
X1017350Y73450D03*
X976200Y105600D03*
X983936Y199108D03*
X973808Y201308D03*
X995206Y203260D03*
X988446Y218860D03*
X995206Y214960D03*
X981686Y218860D03*
X974926Y211060D03*
X985066Y216909D03*
X979426Y214958D03*
X1001965Y214960D03*
X1027875Y193507D03*
X1032385Y201309D03*
X1015485Y203260D03*
Y214960D03*
X1022245D03*
X1012105Y205210D03*
X1025625Y205211D03*
X1029005Y214960D03*
X1007595Y193507D03*
X1005345Y205210D03*
X1008725Y214960D03*
X988446Y234460D03*
X998586Y248109D03*
X985066D03*
X981686Y250060D03*
X974926D03*
X988446Y246160D03*
X981686Y242260D03*
X974926D03*
X988446D03*
X998586Y244209D03*
Y232509D03*
X991826Y244209D03*
Y232509D03*
X995206Y226660D03*
X988446Y238360D03*
X985066Y236409D03*
X981686Y234460D03*
X974926Y226660D03*
Y230559D03*
Y234460D03*
Y222760D03*
X985066Y224709D03*
X978306Y232509D03*
Y220809D03*
X974926Y253960D03*
X988446D03*
X978306Y252009D03*
X985066D03*
X974926Y265660D03*
X991826Y259809D03*
X985066D03*
X981686Y269560D03*
X995206D03*
X985066Y267609D03*
X991826Y263709D03*
X988446Y265660D03*
X998586Y263709D03*
X991826Y271509D03*
X995206Y273460D03*
X991826Y279310D03*
Y275409D03*
X974926Y269560D03*
X978306Y267609D03*
Y259809D03*
X991826Y255909D03*
X995206Y265660D03*
X991826Y267609D03*
X974926Y273460D03*
X1032385Y232509D03*
X1018865Y244209D03*
X1012105D03*
X1018865Y232509D03*
X1015485Y226660D03*
X1022245D03*
X1012105Y232509D03*
X1025625D03*
X1029005Y226660D03*
X1005345Y244209D03*
X1008725Y226660D03*
X1005345Y232509D03*
X1001965Y226660D03*
X1005345Y248109D03*
X1022245Y250060D03*
X1001965Y261760D03*
X1012105Y255909D03*
X1015485Y253960D03*
X1018865Y252009D03*
X1005345Y259809D03*
X1008725Y257860D03*
X981686Y281260D03*
Y292959D03*
Y300760D03*
X988446D03*
X978306Y310509D03*
X991826D03*
X985066D03*
X974926Y300760D03*
X988446Y292959D03*
X991826Y283209D03*
X988446Y281260D03*
X985066Y283209D03*
X978306D03*
X974926Y292959D03*
Y281260D03*
X991826Y333909D03*
X995206Y335860D03*
Y339760D03*
Y328060D03*
X991826Y326110D03*
X981686Y339760D03*
X978306Y333909D03*
Y330009D03*
Y326110D03*
X981686Y331960D03*
X985066Y330009D03*
X974926Y324160D03*
X988446Y339760D03*
X974926Y312460D03*
X981686D03*
X988446D03*
X991826Y314409D03*
Y330009D03*
X995206Y331960D03*
X988446D03*
X995206Y324160D03*
X988446Y316360D03*
X991826Y318309D03*
X995206Y320260D03*
X991826Y322209D03*
X998586Y333909D03*
X974926Y339760D03*
Y335860D03*
X1017957Y312421D03*
X1025438Y312381D03*
X1022915Y312372D03*
X1020404Y312408D03*
X1028039Y312414D03*
X1008725Y339760D03*
X1005345Y337809D03*
X1001965Y335860D03*
X1012105Y341709D03*
X995206Y343660D03*
X985066Y361209D03*
X974926Y355360D03*
Y347560D03*
X981686D03*
X978306Y345609D03*
X981686Y355360D03*
X985066Y349509D03*
X998586D03*
X978306Y365109D03*
X981686Y363160D03*
X974926D03*
Y367060D03*
Y370959D03*
X988446Y367060D03*
X998586Y365109D03*
Y353409D03*
X991826Y365109D03*
X995206Y370959D03*
X991826Y353409D03*
X974926Y343660D03*
X988446Y359260D03*
Y347560D03*
X991826Y345609D03*
X988446Y351460D03*
Y355360D03*
X998586Y392410D03*
X988446Y382660D03*
X995206D03*
X985066Y372909D03*
X974926Y374860D03*
X985066Y384609D03*
X974926Y386560D03*
X974066Y399911D03*
X978306Y376809D03*
X974926Y378760D03*
X981686D03*
X985066Y380709D03*
X1005345Y365109D03*
X1008725Y370959D03*
X1001965D03*
X1005345Y353409D03*
X1018865Y365109D03*
X1012105D03*
X1025625D03*
X1022245Y370959D03*
X1015485D03*
X1018865Y353409D03*
X1012105D03*
X1025625D03*
X1029005Y370959D03*
X1032385Y365109D03*
X1005345Y349509D03*
X1018865Y345609D03*
X1022245Y347560D03*
X1015485Y343660D03*
X1025625Y345609D03*
X1029005Y347560D03*
X1032385Y349509D03*
X1007595Y402800D03*
X1008725Y382660D03*
X1001965D03*
X1005345Y392410D03*
X1029005Y390460D03*
X1025625Y392410D03*
X1022245Y382660D03*
X1015485D03*
X1012105Y392410D03*
X1018865D03*
X1029005Y382660D03*
X1027875Y402800D03*
X987401Y515364D03*
X990748Y512792D03*
X997441Y518157D03*
X976421Y499768D03*
X980708Y510114D03*
X977362Y518157D03*
X1000490Y509999D03*
X1016473Y515152D03*
Y510114D03*
X1008650Y515200D03*
X1008526Y510114D03*
X990748Y536957D03*
X977362Y529014D03*
X980708Y536957D03*
X987401Y529014D03*
X990748Y547922D03*
X980708Y547914D03*
X997441Y529022D03*
X977362Y555857D03*
X987401D03*
X997441D03*
X977362Y566814D03*
X990748Y574757D03*
Y585722D03*
X980708Y585714D03*
Y574757D03*
X997441Y566822D03*
X987401Y566814D03*
X1000787Y536957D03*
Y547922D03*
X1017300Y536200D03*
X1017519Y529057D03*
X1017300Y547914D03*
X1007518Y536727D03*
X1007480Y528942D03*
X1007280Y547914D03*
X1016800Y566814D03*
X1019277Y585714D03*
X1016800Y574742D03*
X1000787Y585722D03*
Y574757D03*
X1016819Y555842D03*
X1007518D03*
Y566814D03*
X1007480Y574742D03*
X1006633Y585714D03*
X977362Y593657D03*
X987401D03*
X997441D03*
Y607292D03*
X977362D03*
X990748Y612457D03*
X980708Y609864D03*
X987401Y604499D03*
X1016778Y611759D03*
X1017519Y604614D03*
Y593642D03*
X1007480Y612242D03*
X1000787Y609864D03*
X1007480Y604614D03*
X1006634Y593642D03*
X1047637Y-4536D03*
X1057676Y-1743D03*
X1047637Y9107D03*
X1057677D03*
X1050983Y-7108D03*
X1050984Y17042D03*
X1061023Y-9786D03*
X1067716Y-4536D03*
Y-9901D03*
X1081102Y-4536D03*
X1074409D03*
X1084448Y-7108D03*
X1077755D03*
X1091141Y-1843D03*
X1067716Y9107D03*
X1091141D03*
X1074409D03*
X1081102D03*
X1061024Y17057D03*
X1067716Y28007D03*
Y17042D03*
X1091141D03*
X1084450Y17057D03*
X1077757D03*
X1091141Y28007D03*
X1050984Y54842D03*
X1047637Y35942D03*
Y46907D03*
X1057677Y35942D03*
Y46907D03*
X1057676Y87392D03*
X1050983Y92757D03*
X1047637Y84599D03*
X1035000Y81200D03*
X1057677Y73742D03*
X1047637D03*
X1061024Y54857D03*
X1067716Y54842D03*
Y35942D03*
Y46907D03*
Y65807D03*
X1091141Y54842D03*
Y35942D03*
X1084450Y54857D03*
X1081102Y35942D03*
X1074409D03*
X1077757Y54857D03*
X1081102Y46907D03*
X1074409D03*
X1091141D03*
Y65807D03*
X1067716Y89964D03*
Y84599D03*
X1081102D03*
X1091141Y87392D03*
Y92657D03*
X1077755Y92757D03*
X1074409Y84714D03*
X1084448Y92757D03*
X1061023Y89964D03*
X1067716Y73742D03*
X1074409D03*
X1081102D03*
X1091141D03*
X1050983Y105800D03*
X1057734Y105750D03*
X1077304Y105800D03*
X1071111D03*
X1064428D03*
X1035765Y214960D03*
X1042524D03*
X1042506Y195041D03*
X1045904Y197359D03*
X1054000Y199100D03*
X1035765Y207159D03*
X1042524Y203260D03*
X1049284Y214960D03*
Y203260D03*
X1072202Y216196D03*
X1065242Y208397D03*
X1068822Y214247D03*
X1065242Y212296D03*
Y204496D03*
X1071072Y199583D03*
X1095861Y218147D03*
X1089101Y214247D03*
Y210346D03*
X1092481Y216196D03*
X1095861Y206446D03*
X1091351Y199841D03*
X1075582Y206446D03*
Y218147D03*
X1082341D03*
X1078962Y216196D03*
X1078961Y212296D03*
X1082341Y214247D03*
X1085721Y212296D03*
Y216196D03*
X1084591Y198931D03*
X1042524Y226660D03*
X1039145Y232509D03*
X1035765Y226660D03*
X1057314Y240309D03*
X1049284Y226660D03*
X1045904Y232509D03*
X1057314D03*
X1050002Y264899D03*
X1047002D03*
X1043502D03*
X1040502D03*
X1095861Y229847D03*
X1068822Y233746D03*
X1065242Y235696D03*
Y223996D03*
X1068822Y237647D03*
Y249347D03*
X1065242Y247396D03*
X1068822Y241547D03*
X1072202Y243496D03*
Y251296D03*
X1092481Y223996D03*
Y231797D03*
X1089101Y233746D03*
Y237647D03*
X1095861D03*
Y245447D03*
X1078962Y251296D03*
X1082341Y245447D03*
Y249347D03*
X1078962Y247396D03*
X1092481Y243496D03*
X1075582Y245447D03*
X1085721Y251296D03*
X1075582Y249347D03*
X1085721Y243496D03*
X1089101Y241547D03*
X1085721Y223996D03*
X1075582Y229847D03*
X1082341D03*
X1078962Y227896D03*
Y220096D03*
Y223996D03*
X1085721Y231797D03*
X1082341Y237647D03*
X1075582D03*
X1072202Y231797D03*
Y223996D03*
X1089101Y253247D03*
X1092481Y255196D03*
X1095861Y257147D03*
X1049284Y370959D03*
X1035765D03*
X1042524D03*
X1045904Y365109D03*
X1039145D03*
X1052664D03*
X1042524Y359260D03*
X1049284Y351460D03*
X1045904Y353409D03*
X1035765Y351460D03*
Y359260D03*
X1039145Y353409D03*
X1042524Y351460D03*
X1054914Y347000D03*
X1052664Y392410D03*
X1040265Y394359D03*
X1049284Y382660D03*
X1035765D03*
X1042524D03*
Y390460D03*
X1056176Y402471D03*
X1041395Y402800D03*
X1060694Y351460D03*
X1086841Y358547D03*
X1094731Y346546D03*
X1086841Y354647D03*
X1090221Y352696D03*
X1091351Y348497D03*
X1073322Y354647D03*
X1076702Y356596D03*
X1080082Y354647D03*
X1083462Y368296D03*
X1076702Y372197D03*
Y368296D03*
X1073322Y362447D03*
X1086841D03*
X1090221Y372197D03*
Y364396D03*
X1093601Y366347D03*
X1090221Y368296D03*
X1076702Y360496D03*
X1083462D03*
Y352696D03*
X1076702D03*
X1093601Y358547D03*
X1090221Y379996D03*
X1073323Y401449D03*
X1078962Y399496D03*
X1093601Y401447D03*
X1073322Y374146D03*
X1086841D03*
X1073323Y397548D03*
X1073322Y385847D03*
X1080082Y393647D03*
X1083462Y391696D03*
X1080082Y385847D03*
X1083462Y376096D03*
X1080082Y378047D03*
X1083462Y379996D03*
X1076702Y376096D03*
X1090221Y395595D03*
X1086841Y389747D03*
X1093601Y393647D03*
X1090221Y391696D03*
X1093601Y385847D03*
X1086841D03*
X1093601Y397546D03*
Y378047D03*
X1086841Y381947D03*
X1093601Y405347D03*
X1077832Y407800D03*
X1047637Y509999D03*
X1057676Y512792D03*
X1035000Y521556D03*
X1050983Y518157D03*
X1067716Y509999D03*
X1074409Y510114D03*
X1061023Y515364D03*
X1091141Y518057D03*
X1077755Y518157D03*
X1081102Y509999D03*
X1084448Y518157D03*
X1082800Y497650D03*
X1091141Y512792D03*
X1067716Y515364D03*
X1057677Y547907D03*
Y536942D03*
X1047637Y547907D03*
Y536942D03*
X1057677Y574742D03*
Y585707D03*
X1047637Y574742D03*
Y585707D03*
X1050984Y555842D03*
X1074409Y547907D03*
X1081102D03*
X1091141D03*
Y529007D03*
Y536942D03*
X1074409D03*
X1081102D03*
X1067716D03*
Y529007D03*
X1061024Y555857D03*
X1077757D03*
X1084450D03*
X1091141Y555842D03*
X1067716D03*
X1081102Y574742D03*
Y585707D03*
X1074409D03*
X1091141Y574742D03*
Y585707D03*
X1067716Y574742D03*
Y585599D03*
Y566807D03*
X1091141D03*
X1074409Y574742D03*
X1091141Y612557D03*
X1057676Y612657D03*
X1050984Y593642D03*
X1047637Y609864D03*
X1061024Y593657D03*
X1061023Y604614D03*
X1077757Y593657D03*
X1084450D03*
X1067716Y593642D03*
Y609864D03*
Y604499D03*
X1081102Y609864D03*
X1091141Y593642D03*
Y607292D03*
X1084448D03*
X1077755D03*
X1050983D03*
X1074409Y609864D03*
X1098235Y68090D03*
X1110520Y67900D03*
X1104141Y67749D03*
X1114366Y65950D03*
X1119453Y65736D03*
X1098259Y70896D03*
X1101181Y84714D03*
X1098218Y85296D03*
X1114340Y73799D03*
X1107874Y73849D03*
X1101181Y73799D03*
X1098207Y73589D03*
X1110520Y90314D03*
X1114340Y84698D03*
X1114316Y92500D03*
X1107724Y84714D03*
X1119440Y92714D03*
X1119416Y84700D03*
X1119466Y73550D03*
X1098300Y89900D03*
X1104177Y90314D03*
X1127952Y67749D03*
X1134645D03*
X1140952D03*
X1156265Y65736D03*
X1151178Y65950D03*
X1147331Y67900D03*
X1131299Y73849D03*
X1124606D03*
X1127952Y90414D03*
X1131299Y84714D03*
X1124606D03*
X1147331Y90414D03*
X1137992Y73799D03*
X1144535Y84714D03*
X1140988Y90314D03*
X1137992Y84714D03*
X1134645Y90414D03*
X1144685Y73849D03*
X1156252Y92714D03*
X1151128Y92500D03*
X1151152Y84698D03*
X1156228Y84700D03*
X1156278Y73550D03*
X1151152Y73799D03*
X1138242Y104314D03*
X1144685D03*
X1156278Y112865D03*
X1151152Y113114D03*
X1141038Y109564D03*
X1147331D03*
X1156265Y105051D03*
X1151178Y105265D03*
X1116141Y206446D03*
X1136420Y210346D03*
X1099241Y216196D03*
Y212296D03*
X1109381Y214247D03*
X1116141Y218147D03*
X1106001Y212296D03*
X1102621Y218147D03*
Y214247D03*
X1119521Y216196D03*
X1119520Y212296D03*
X1104871Y198050D03*
X1106001Y216196D03*
X1112761D03*
X1129660Y206447D03*
X1126280Y216196D03*
Y212296D03*
X1125300Y199900D03*
X1122900Y214247D03*
Y218147D03*
X1129660Y214247D03*
X1147950Y209900D03*
X1136420Y218147D03*
Y214247D03*
X1151060Y212296D03*
X1157820D03*
X1099241Y227896D03*
Y220096D03*
X1102621Y229847D03*
X1099241Y223996D03*
X1109381Y233746D03*
X1112761Y231797D03*
Y223996D03*
X1116141Y237647D03*
X1109381D03*
X1106001Y223996D03*
X1102621Y237647D03*
Y245447D03*
X1112761Y251296D03*
X1116141Y245447D03*
X1106001Y243496D03*
X1112761D03*
X1109381Y241547D03*
X1106001Y251296D03*
X1099241D03*
Y247396D03*
X1119521Y223996D03*
Y220096D03*
Y227896D03*
Y247396D03*
Y251296D03*
X1106001Y231797D03*
X1116141Y229847D03*
X1107561Y269038D03*
X1116141Y264947D03*
X1111631Y271300D03*
X1106001Y262996D03*
Y259096D03*
X1099241Y255196D03*
Y259096D03*
X1119521Y270796D03*
X1118391Y274997D03*
X1119521Y255196D03*
X1102621Y261047D03*
Y257147D03*
X1109381Y261047D03*
X1116141Y257147D03*
X1112761Y259096D03*
X1110648Y276899D03*
X1100200Y273300D03*
X1129660Y237647D03*
X1126280Y223996D03*
Y231797D03*
X1122900Y229847D03*
Y237647D03*
X1129660Y233746D03*
Y241547D03*
X1126280Y251296D03*
Y243496D03*
X1122900Y245447D03*
X1144300Y243496D03*
X1151060Y247396D03*
X1154440Y245447D03*
X1144300Y247396D03*
Y251296D03*
X1136420Y245447D03*
X1154440Y241547D03*
X1136420D03*
X1157820Y239596D03*
X1147680Y222047D03*
X1144300Y235696D03*
X1136420Y229847D03*
Y233746D03*
Y222047D03*
Y225947D03*
Y237647D03*
X1133040Y223996D03*
Y235696D03*
Y243496D03*
Y251296D03*
X1147680Y225947D03*
X1151060Y223996D03*
X1147680Y233746D03*
X1154440Y229847D03*
X1157820Y220096D03*
Y223996D03*
Y231797D03*
X1154440Y253247D03*
X1130780Y278596D03*
X1129660Y261047D03*
X1130780Y274696D03*
X1126280Y259096D03*
X1122900Y257147D03*
X1157820Y278596D03*
Y270796D03*
X1151060Y266896D03*
Y274696D03*
X1137540D03*
X1151060Y259096D03*
X1144300Y255196D03*
X1133040Y259096D03*
X1134160Y268847D03*
X1136420Y257147D03*
X1144300Y278596D03*
Y270796D03*
X1137540Y278596D03*
X1119521Y286396D03*
Y305896D03*
X1108251Y338746D03*
X1117261Y340996D03*
X1104871Y340697D03*
X1119521Y321496D03*
X1130780Y290296D03*
X1127400Y288347D03*
X1130780Y309797D03*
Y301996D03*
X1127400Y303947D03*
Y307847D03*
X1157820Y290296D03*
X1151060Y298096D03*
Y290296D03*
Y282496D03*
X1144300Y286396D03*
Y294196D03*
X1157820D03*
X1140920Y300047D03*
X1134160Y292247D03*
Y300047D03*
X1140920Y292247D03*
X1137540Y282496D03*
X1144300Y309797D03*
X1137540D03*
X1147680Y303947D03*
X1154440Y307847D03*
X1130780Y313696D03*
X1157820D03*
X1124021Y340996D03*
Y337096D03*
X1127400Y327347D03*
X1157820Y337096D03*
Y333196D03*
X1134160Y323446D03*
X1151060Y340996D03*
Y333196D03*
X1154440Y319547D03*
X1157820Y317596D03*
X1137540D03*
X1157820Y329296D03*
X1147680Y327347D03*
X1154440Y335147D03*
X1144300Y340996D03*
Y337096D03*
X1140920Y339047D03*
Y331247D03*
X1154440Y323446D03*
Y315647D03*
X1147680Y319547D03*
X1157820Y325396D03*
X1154440Y339047D03*
Y331247D03*
X1127400Y319547D03*
Y315647D03*
X1100361Y350747D03*
X1113881D03*
Y358547D03*
X1117261Y348796D03*
X1100361Y358547D03*
X1103741Y348796D03*
Y352696D03*
X1110501D03*
X1107121Y346847D03*
Y354647D03*
Y358547D03*
Y362447D03*
X1103741Y372197D03*
X1110501Y364396D03*
X1103741D03*
X1113881Y366347D03*
X1117261Y372197D03*
Y368296D03*
X1110501Y372197D03*
X1096981Y368296D03*
Y372197D03*
X1100361Y366347D03*
X1113881Y401447D03*
X1110501Y391696D03*
Y395595D03*
X1107121Y389747D03*
X1100361Y385847D03*
X1107121D03*
X1100361Y393647D03*
X1103741Y391696D03*
X1100361Y397547D03*
X1113881Y385847D03*
Y397546D03*
Y393647D03*
X1103741Y379996D03*
X1113881Y378047D03*
X1117261Y376096D03*
X1110501Y379996D03*
X1107121Y381947D03*
X1096981Y376096D03*
X1100361Y378047D03*
X1151060Y368296D03*
X1147680Y366347D03*
X1120641Y350747D03*
Y358547D03*
Y366347D03*
X1127400Y362447D03*
X1124021Y348796D03*
Y352696D03*
X1127400Y354647D03*
Y358547D03*
X1130780Y360496D03*
X1127400Y342947D03*
X1134160Y346847D03*
Y362447D03*
Y366347D03*
Y370247D03*
X1147680Y342947D03*
X1151060Y356596D03*
Y360496D03*
X1144300D03*
X1137540D03*
X1144300Y356596D03*
X1140920Y358547D03*
X1147680Y346847D03*
Y350747D03*
X1151060Y352696D03*
Y348796D03*
X1147680Y358547D03*
X1157820Y360496D03*
X1154440Y358547D03*
Y342947D03*
Y354647D03*
X1157820Y352696D03*
X1147680Y354647D03*
X1144300Y348796D03*
X1140920Y346847D03*
Y350747D03*
X1144300Y344896D03*
X1151060D03*
X1154440Y346847D03*
X1140920Y362447D03*
X1154440Y366347D03*
X1144300Y372197D03*
X1137540D03*
Y368296D03*
X1140920Y366347D03*
Y370247D03*
X1151060Y364396D03*
X1144300D03*
X1137540D03*
X1147680Y362447D03*
X1130780Y352696D03*
Y344896D03*
X1124021Y372197D03*
X1130780D03*
X1124021Y364396D03*
X1137540Y403396D03*
Y399496D03*
X1124021Y391696D03*
X1130780Y395596D03*
X1127400Y385847D03*
Y389747D03*
X1130780Y391696D03*
X1124021Y379996D03*
X1127400Y381947D03*
X1130780Y379996D03*
X1137540Y395597D03*
X1140920Y397546D03*
X1137540Y376096D03*
X1157820Y387796D03*
X1140920Y378047D03*
Y381947D03*
X1147680Y393647D03*
X1120641Y385847D03*
Y393647D03*
Y378047D03*
Y401447D03*
X1140920Y374146D03*
X1151060Y395597D03*
Y391696D03*
X1147680Y385847D03*
Y397546D03*
X1151060Y379996D03*
X1154440Y378047D03*
Y381947D03*
X1140920Y389747D03*
X1134160Y393647D03*
Y385847D03*
Y378047D03*
X1140920Y385847D03*
X1144300Y391696D03*
X1117261Y407296D03*
X1113881Y405347D03*
X1096699Y407782D03*
X1134160Y405347D03*
X1119440Y518114D03*
X1114316Y517900D03*
X1114340Y510098D03*
X1110520Y515714D03*
X1097343Y512794D03*
X1104177Y515714D03*
X1101181Y510114D03*
X1098300Y515300D03*
X1107724Y510114D03*
X1137992Y495887D03*
X1144385D03*
X1140988Y493744D03*
X1156252Y490867D03*
X1147331Y493494D03*
X1151168Y490867D03*
X1127952Y515814D03*
X1124606Y510114D03*
X1131299D03*
X1156252Y518114D03*
X1147331Y515814D03*
X1151128Y517900D03*
X1156252Y498867D03*
X1151168D03*
X1151152Y510098D03*
X1134645Y515814D03*
X1137992Y510114D03*
X1140988Y515714D03*
X1144535Y510114D03*
X1156228Y510100D03*
X1104141Y530949D03*
X1098040Y536723D03*
X1098160Y533809D03*
X1119466Y536750D03*
X1119453Y528936D03*
X1098018Y531156D03*
X1114366Y529150D03*
X1114340Y536999D03*
X1110520Y531100D03*
X1107874Y537049D03*
X1101181Y536999D03*
X1131299Y537049D03*
X1124606D03*
X1127952Y530949D03*
X1151178Y529150D03*
X1151152Y536999D03*
X1147331Y531100D03*
X1156278Y536750D03*
X1156265Y528936D03*
X1134645Y530949D03*
X1140952D03*
X1137992Y536999D03*
X1144685Y537049D03*
X1137992Y612599D03*
X1144685Y612649D03*
X1151152Y612599D03*
X1124606Y612649D03*
X1131299D03*
X1114340Y612599D03*
X1107874Y612649D03*
X1101181Y612599D03*
X1119466Y612350D03*
X1156278D03*
X1177763Y67749D03*
X1171456D03*
X1164763D03*
X1177799Y90314D03*
X1174803Y84714D03*
X1168110D03*
Y73849D03*
X1161417D03*
X1174803Y73799D03*
X1161417Y84714D03*
X1164763Y90414D03*
X1171456D03*
X1187989Y65950D03*
X1193076Y65736D03*
X1184142Y67900D03*
X1201574Y67749D03*
X1211614Y73799D03*
X1218307Y73849D03*
X1208267Y90414D03*
X1218157Y84714D03*
X1211614D03*
X1214574Y67749D03*
X1208267D03*
X1181346Y84714D03*
X1181496Y73849D03*
X1184142Y90414D03*
X1193039Y84700D03*
X1193063Y92714D03*
X1187939Y92500D03*
X1187963Y84698D03*
Y73799D03*
X1193089Y73550D03*
X1198228Y73849D03*
X1204921D03*
X1198228Y84714D03*
X1204921D03*
X1201574Y90414D03*
X1177799Y109914D03*
X1161632Y104314D03*
X1170721Y109564D03*
X1164428D03*
X1168075Y104314D03*
X1174742D03*
X1208267Y110014D03*
X1181346Y104314D03*
X1187963Y113114D03*
X1193089Y112865D03*
X1184142Y109564D03*
X1193076Y105051D03*
X1187989Y105265D03*
X1201574Y110014D03*
X1198228Y104314D03*
X1204921D03*
X1161200Y206446D03*
X1167960Y206447D03*
Y218147D03*
X1171339Y208397D03*
X1174719Y218147D03*
Y206447D03*
X1178099Y208397D03*
Y216196D03*
X1161200Y210346D03*
Y218147D03*
X1181479Y206447D03*
X1188239Y210346D03*
Y206447D03*
X1201759Y218147D03*
X1205759Y206682D03*
X1197492Y201356D03*
X1198379Y212296D03*
X1194999Y210346D03*
X1184859Y204496D03*
X1188239Y214247D03*
X1164580Y235696D03*
X1167960Y229847D03*
X1164580Y223996D03*
Y227896D03*
Y239596D03*
X1178099Y247396D03*
X1161200Y241547D03*
X1164580Y247396D03*
X1161200Y249347D03*
X1171339Y247396D03*
X1178099Y243496D03*
X1171339Y235696D03*
Y220096D03*
Y231797D03*
X1178099Y227896D03*
Y235696D03*
Y220096D03*
X1174719Y237647D03*
X1167960Y253247D03*
X1174719D03*
X1164580Y270796D03*
X1171339Y274696D03*
X1174719Y280547D03*
X1171339Y266896D03*
X1164580Y278596D03*
X1159578Y265117D03*
X1171339Y259096D03*
X1178099Y274696D03*
X1181479Y222047D03*
X1188239D03*
X1191619Y239596D03*
X1188239Y225947D03*
X1184859Y235696D03*
X1188239Y237647D03*
X1184859Y247396D03*
X1188239Y249347D03*
X1201759Y229847D03*
Y225947D03*
Y233746D03*
X1198379Y235696D03*
Y243496D03*
X1201759Y241547D03*
Y249347D03*
X1198379Y239596D03*
X1194999Y225947D03*
Y222047D03*
Y233746D03*
X1184859Y239596D03*
Y251296D03*
X1212199D03*
Y243496D03*
X1208519Y233746D03*
X1215700Y223600D03*
X1194999Y264947D03*
Y268847D03*
Y272747D03*
Y280547D03*
X1188239Y257147D03*
X1208519Y272747D03*
X1208819Y280547D03*
X1181479Y261047D03*
Y268847D03*
Y276646D03*
X1212199Y274696D03*
X1217200Y270500D03*
X1213808Y264800D03*
X1208519Y264947D03*
X1184859Y259096D03*
X1191619Y274696D03*
X1205139D03*
X1198379Y278596D03*
X1201759Y261047D03*
X1198379Y255196D03*
X1201759Y257147D03*
X1174719Y300047D03*
Y284447D03*
X1164580Y294196D03*
Y290296D03*
Y286396D03*
X1161200Y284447D03*
X1178099Y294196D03*
Y298096D03*
Y286396D03*
X1164580Y301996D03*
X1171339D03*
X1161200Y307847D03*
Y335147D03*
Y339047D03*
X1164580Y329296D03*
Y333196D03*
Y337096D03*
X1167960Y339047D03*
Y327347D03*
X1161200Y331247D03*
Y327347D03*
X1178099Y337096D03*
Y317596D03*
X1164580Y321496D03*
Y317596D03*
X1161200Y323446D03*
Y319547D03*
Y315647D03*
X1167960Y323446D03*
Y315647D03*
Y319547D03*
X1174719Y315647D03*
X1171339Y317596D03*
X1164580Y325396D03*
X1171339D03*
X1174719Y335147D03*
X1205500Y309797D03*
X1198379D03*
X1194999Y288347D03*
Y292247D03*
Y296147D03*
Y300047D03*
Y307847D03*
Y303947D03*
X1191619Y298096D03*
X1181479Y300047D03*
Y288347D03*
Y292247D03*
Y311747D03*
Y307847D03*
Y303947D03*
X1188239Y288347D03*
Y284447D03*
Y292247D03*
X1184859Y294196D03*
Y290296D03*
X1191619Y294196D03*
X1184859Y309797D03*
X1188239Y311747D03*
X1184859Y301996D03*
X1201759Y284447D03*
Y288347D03*
X1205439Y298096D03*
X1198379Y286396D03*
X1205439Y305896D03*
X1194999Y335147D03*
Y331247D03*
X1212200Y333196D03*
X1208519Y339047D03*
X1208826Y319544D03*
X1181479Y327347D03*
Y319547D03*
Y335147D03*
X1198379Y313696D03*
X1188239Y319547D03*
X1184859Y321496D03*
X1188239Y339047D03*
Y335147D03*
X1184859Y329296D03*
X1191619Y321496D03*
X1198379Y325396D03*
Y340996D03*
X1201759Y323446D03*
X1205139Y333196D03*
X1194999Y319547D03*
Y315647D03*
X1167960Y370247D03*
X1164580Y372197D03*
X1171339Y356596D03*
Y360496D03*
X1164580Y356596D03*
X1167960Y342947D03*
X1171339Y348796D03*
X1174719Y354647D03*
Y342947D03*
X1161200Y370247D03*
X1171339Y372197D03*
X1167960Y362447D03*
X1178099Y364396D03*
X1171339Y399496D03*
X1164580Y403396D03*
X1178099D03*
X1167960Y389747D03*
X1161200Y397546D03*
X1167960Y397547D03*
X1174719Y393647D03*
X1161200Y378047D03*
X1164580Y379996D03*
X1174719Y381947D03*
X1194999Y346847D03*
Y354647D03*
X1209219Y370247D03*
X1212199Y356597D03*
Y344896D03*
Y352696D03*
X1181479Y346847D03*
X1188239Y366347D03*
X1194999D03*
X1191619Y348796D03*
X1184859Y356596D03*
X1191619Y360496D03*
X1201759Y350747D03*
X1205139Y360496D03*
X1181479Y374146D03*
Y389747D03*
X1209769Y374146D03*
X1184859Y383896D03*
X1188239Y393647D03*
X1201759Y389747D03*
X1197258Y397546D03*
X1194999Y385847D03*
X1188239Y378047D03*
X1201759D03*
X1208819Y393647D03*
Y381897D03*
X1195555Y405773D03*
X1192200Y409550D03*
X1185989Y407800D03*
X1180400Y495787D03*
X1167500Y495800D03*
X1174203Y495787D03*
X1161320Y495800D03*
X1170656Y491144D03*
X1164363Y491044D03*
X1177849Y490944D03*
X1168110Y510114D03*
X1164763Y515814D03*
X1161417Y510114D03*
X1177799Y515714D03*
X1171456Y515814D03*
X1174803Y510114D03*
X1208267Y493444D03*
X1200974Y490744D03*
X1193063Y490909D03*
X1187978Y490609D03*
X1184142Y490794D03*
X1181346Y510114D03*
X1204400Y495887D03*
X1198100Y495800D03*
X1208267Y515814D03*
X1211614Y510114D03*
X1218157D03*
X1187963Y510098D03*
X1204921Y510114D03*
X1198228D03*
X1201574Y515814D03*
X1184142D03*
X1187939Y517900D03*
X1193039Y510100D03*
X1193063Y518114D03*
X1187978Y498609D03*
X1193063Y498909D03*
X1177763Y530949D03*
X1168110Y537049D03*
X1164763Y530949D03*
X1161417Y537049D03*
X1171456Y530949D03*
X1174803Y536999D03*
X1181496Y537049D03*
X1211614Y536999D03*
X1214574Y530949D03*
X1184142Y531100D03*
X1193076Y528936D03*
X1201574Y530949D03*
X1204921Y537049D03*
X1198228D03*
X1193089Y536750D03*
X1187989Y529150D03*
X1187963Y536999D03*
X1218307Y537049D03*
X1208267Y530949D03*
X1181496Y612649D03*
X1218307D03*
X1211614Y612599D03*
X1187963D03*
X1204921Y612649D03*
X1198228D03*
X1168110D03*
X1161417D03*
X1174803Y612599D03*
X1193089Y612350D03*
X1238385Y67749D03*
X1251771Y65699D03*
X1248425D03*
X1245078Y67749D03*
X1267976Y73676D03*
X1241732Y84714D03*
Y73849D03*
X1238385Y90414D03*
X1251771Y92599D03*
X1245078Y90414D03*
X1248425Y84757D03*
Y73849D03*
X1268581Y92706D03*
X1224774Y84698D03*
X1224750Y92500D03*
X1224774Y73799D03*
X1235039Y84714D03*
Y73849D03*
X1229887Y65736D03*
X1224800Y65950D03*
X1220953Y67900D03*
X1229900Y73550D03*
X1229850Y84700D03*
X1229874Y92714D03*
X1220953Y90414D03*
X1240927Y154932D03*
X1266200Y122500D03*
X1254024Y128013D03*
X1246251Y130066D03*
X1257800Y110900D03*
X1260500Y117500D03*
X1247326Y122802D03*
X1254300Y105200D03*
X1277660Y109450D03*
X1277230Y117570D03*
X1237400Y103100D03*
X1241712Y187710D03*
X1220167Y194407D03*
X1220017Y220323D03*
X1220194Y243384D03*
X1223100Y258600D03*
X1223508Y262600D03*
X1259800Y463300D03*
X1255530Y474770D03*
X1269050Y486650D03*
X1269600Y480800D03*
X1272830Y471660D03*
X1257720Y493060D03*
X1255388Y483557D03*
X1256130Y467820D03*
X1241732Y510114D03*
X1238385Y515814D03*
X1269000Y514700D03*
X1245078Y515814D03*
X1251771Y517999D03*
X1248425Y510157D03*
X1235039Y510114D03*
X1220953Y515814D03*
X1229874Y518114D03*
X1229850Y510100D03*
X1224750Y517900D03*
X1224774Y510098D03*
X1241732Y537049D03*
X1238385Y530949D03*
X1269800Y532978D03*
X1251771Y528899D03*
X1248425Y537049D03*
Y528899D03*
X1245078Y530949D03*
X1220953Y531100D03*
X1229887Y528936D03*
X1229900Y536750D03*
X1224800Y529150D03*
X1224774Y536999D03*
X1235039Y537049D03*
X1241732Y612649D03*
X1248425D03*
X1224774Y612599D03*
X1235039Y612649D03*
X1229900Y612350D03*
X1301279Y10058D03*
X1304079D03*
X1306879D03*
X1301200Y12610D03*
X1306800D03*
X1301200Y15200D03*
X1301100Y2700D03*
X1316300Y-14800D03*
X1320800Y-16900D03*
X1307900Y-14700D03*
X1309500Y-16800D03*
X1323600Y-16900D03*
X1322000Y-14800D03*
X1324800D03*
X1326000Y-12700D03*
X1323600Y-12600D03*
X1327600Y-14800D03*
Y4700D03*
X1326400Y2600D03*
X1324800Y4700D03*
X1322000D03*
X1323600Y2600D03*
X1306700Y2700D03*
X1309500D03*
X1307900Y4800D03*
X1320800Y2600D03*
X1316300Y4700D03*
X1317900Y2600D03*
X1319200Y4700D03*
X1313500Y4800D03*
X1315004Y2567D03*
X1302300Y4800D03*
X1303900Y2700D03*
X1310700Y4800D03*
X1312300Y2700D03*
X1305100Y4800D03*
X1322532Y9822D03*
X1325332D03*
X1312300Y-16800D03*
X1310700Y-14700D03*
X1315004Y-16933D03*
X1313500Y-14700D03*
X1319200Y-14800D03*
X1317900Y-16900D03*
X1321452Y31803D03*
X1304000Y15200D03*
X1328085Y9865D03*
X1322483Y12834D03*
X1328045Y15831D03*
X1325308Y15734D03*
X1322508D03*
X1328123Y12730D03*
X1306800Y15200D03*
X1313942Y30714D03*
X1309760Y30691D03*
X1316300Y31911D03*
X1318700Y31943D03*
X1311809Y32096D03*
X1325383Y12634D03*
X1304000Y12610D03*
X1301000Y62000D03*
X1323500Y68000D03*
X1318341Y60000D03*
X1321841Y63000D03*
X1304000Y62000D03*
X1310600Y41500D03*
X1308100D03*
X1323400Y41439D03*
X1326000D03*
X1326058Y43956D03*
X1323400Y43839D03*
X1318341Y63000D03*
X1341400Y46100D03*
X1336900Y89896D03*
X1323500Y75000D03*
Y71500D03*
X1286000Y134500D03*
Y139500D03*
Y137000D03*
X1298400Y144500D03*
X1288500Y137000D03*
Y139500D03*
Y134500D03*
X1286000Y132000D03*
X1288500D03*
X1322628Y100134D03*
X1323800Y104250D03*
X1326800D03*
Y107250D03*
X1323800D03*
X1326600Y123450D03*
X1323600D03*
X1326600Y126450D03*
X1323600D03*
X1340100Y145000D03*
X1335100Y155000D03*
Y145000D03*
X1330100Y150000D03*
X1340100D03*
Y155000D03*
X1315100Y145000D03*
X1335100Y150000D03*
X1330100Y145000D03*
Y155000D03*
Y160000D03*
X1340100D03*
X1306363Y169928D03*
X1335100Y160000D03*
X1324938Y209251D03*
X1322500D03*
X1320390Y216824D03*
X1303838Y169922D03*
X1320400Y234959D03*
X1325900D03*
X1314900D03*
X1336900D03*
X1331400D03*
X1342400D03*
X1334113Y273115D03*
X1340866Y268795D03*
X1327625Y275971D03*
X1336480Y309755D03*
X1336793Y303784D03*
X1342500Y312100D03*
X1316300Y282000D03*
X1325300Y282600D03*
X1341920Y309755D03*
X1342480Y303852D03*
X1319906Y338025D03*
X1338500Y319600D03*
X1326626Y464400D03*
X1300100Y442500D03*
X1301000Y460900D03*
X1305100Y432500D03*
X1320100Y427500D03*
Y432500D03*
X1325100Y427500D03*
Y432500D03*
X1305181Y427834D03*
X1310100Y427500D03*
Y432500D03*
X1315100Y427500D03*
Y432500D03*
X1340100Y427500D03*
X1330100Y432500D03*
Y427500D03*
X1335100Y457500D03*
Y452500D03*
Y447500D03*
Y442500D03*
X1330100D03*
X1305100D03*
X1310100D03*
X1320100D03*
X1315100D03*
X1325100D03*
X1340100Y457500D03*
Y452500D03*
Y447500D03*
Y442500D03*
X1319738Y477497D03*
X1326877Y469279D03*
X1319699Y472327D03*
X1301000Y466500D03*
X1319300Y525450D03*
X1321800D03*
X1311772Y501000D03*
X1319075D03*
X1316675Y500983D03*
X1314272Y501000D03*
X1300000Y552400D03*
Y558400D03*
Y555400D03*
X1343100Y566300D03*
X1340700D03*
X1338000D03*
X1340526Y563337D03*
X1343026D03*
X1338026D03*
X1333026D03*
X1335526D03*
Y566237D03*
X1317500Y552400D03*
X1320500D03*
X1321800Y532750D03*
X1319300Y532650D03*
X1321800Y527850D03*
X1319300D03*
Y530250D03*
X1321800D03*
X1317500Y555400D03*
X1320500D03*
X1303000Y576000D03*
Y579000D03*
Y571400D03*
Y568900D03*
Y565900D03*
Y563400D03*
X1306000Y579000D03*
X1309000Y565900D03*
Y563400D03*
Y571400D03*
X1306000Y568900D03*
X1309000D03*
X1306000Y576000D03*
Y571400D03*
X1321000D03*
Y568900D03*
X1318000D03*
X1312000D03*
X1318000Y571400D03*
X1315000D03*
Y568900D03*
X1312000Y571400D03*
X1320500Y558400D03*
X1317500D03*
X1312000Y563400D03*
Y565900D03*
X1315000Y563400D03*
Y565900D03*
X1318000Y563400D03*
Y565900D03*
X1321000Y563400D03*
Y565900D03*
X1306000D03*
Y563400D03*
X1333026Y566237D03*
X1307600Y620100D03*
X1306600Y610000D03*
X1306556Y607558D03*
X1324200Y610100D03*
Y600100D03*
Y597600D03*
X1321100Y598500D03*
Y601000D03*
X1315100Y598500D03*
Y601000D03*
X1312100Y598500D03*
X1309100D03*
Y601000D03*
X1312100D03*
X1318100Y598500D03*
Y601000D03*
X1324200Y602700D03*
Y605100D03*
Y607500D03*
X1357400Y-19800D03*
X1360400Y10600D03*
X1350654Y-18411D03*
X1348154Y-15911D03*
Y-18411D03*
X1357600Y5140D03*
X1345518Y-18476D03*
X1353154Y-18411D03*
X1375676Y7630D03*
X1385608Y-17485D03*
X1388294Y-5675D03*
X1389523Y4966D03*
X1355950Y-16507D03*
X1359450Y-7D03*
X1355950D03*
X1357489Y-1924D03*
X1359450Y2493D03*
X1355950D03*
X1357489Y-14424D03*
Y-10524D03*
Y-6124D03*
X1355889Y-8524D03*
X1355847Y-12275D03*
X1355989Y-3924D03*
X1356261Y32017D03*
X1356300Y20100D03*
X1356376Y24167D03*
X1356200Y28200D03*
X1357900Y30200D03*
X1357800Y26100D03*
X1357803Y22200D03*
X1356261Y15517D03*
X1357700Y17800D03*
X1359761Y32317D03*
X1371650Y-907D03*
X1371589Y-3424D03*
Y-5924D03*
X1371900Y28600D03*
Y26100D03*
Y31100D03*
X1369408Y50479D03*
X1375500Y76000D03*
X1397500Y51000D03*
X1365855Y46972D03*
X1359800Y37300D03*
X1357300D03*
X1344000Y83000D03*
X1402700Y51100D03*
X1381817Y46484D03*
X1388627Y35032D03*
X1380500Y54500D03*
X1380900Y59820D03*
X1372400Y37785D03*
X1389138Y58499D03*
X1370100Y82500D03*
X1366100D03*
X1364700Y86550D03*
X1389068Y78556D03*
X1389100Y74600D03*
X1350830Y60730D03*
X1356261Y34517D03*
X1356950Y54370D03*
X1356760Y66660D03*
X1357000Y60500D03*
X1359761Y34817D03*
X1350800Y66600D03*
X1351190Y54710D03*
X1363170Y54280D03*
X1362900Y60500D03*
X1363040Y66660D03*
X1380500Y50500D03*
X1356230Y126500D03*
X1359230D03*
X1360730Y129000D03*
X1362230Y126500D03*
X1355100Y155000D03*
Y145000D03*
Y150000D03*
X1360100Y155000D03*
Y145000D03*
Y150000D03*
X1345100D03*
X1350100Y155000D03*
Y150000D03*
Y145000D03*
X1345100D03*
Y155000D03*
X1397994Y103350D03*
X1397952Y105998D03*
X1395326Y100913D03*
Y103413D03*
X1395347Y106040D03*
X1386700Y125450D03*
Y128450D03*
X1383700Y125450D03*
Y128450D03*
X1380700Y125450D03*
Y128450D03*
X1376100Y116100D03*
X1376669Y121763D03*
Y118763D03*
X1376100Y124950D03*
X1373850Y114450D03*
X1369730Y129000D03*
X1363730D03*
X1366730D03*
X1373850Y117450D03*
X1368230Y126500D03*
X1373850Y123450D03*
X1365230Y126500D03*
X1397193Y112602D03*
X1394253Y116989D03*
X1385100Y155000D03*
X1375100D03*
X1365100D03*
X1380100D03*
Y145000D03*
X1385100D03*
X1380100Y150000D03*
X1385100D03*
X1365100Y145000D03*
Y150000D03*
X1375100D03*
X1370100Y155000D03*
Y145000D03*
X1375100D03*
X1370100Y150000D03*
X1352200Y104950D03*
Y108400D03*
X1357700D03*
Y104950D03*
X1373850Y120450D03*
X1380100Y160000D03*
X1360100D03*
X1355100D03*
X1345100D03*
X1350100D03*
X1390100D03*
X1370100D03*
X1390100Y170000D03*
X1385100Y160000D03*
Y165000D03*
Y170000D03*
X1365100Y160000D03*
X1375100D03*
X1390100Y165000D03*
X1383753Y265548D03*
X1397400Y234959D03*
X1391900D03*
X1386400D03*
X1358900D03*
X1353400D03*
X1347900D03*
X1349500Y265500D03*
X1359100Y265600D03*
X1380900Y234959D03*
X1369900D03*
X1364400D03*
X1375400Y235100D03*
X1369100Y265500D03*
X1374864Y265629D03*
X1398062Y315743D03*
X1403100Y321350D03*
X1383639Y315274D03*
X1389600Y315200D03*
X1384024Y320225D03*
X1386048Y310310D03*
X1386265Y304310D03*
X1389600Y320100D03*
X1397640Y310631D03*
X1397880Y304640D03*
X1392380D03*
X1392340Y310625D03*
X1403260Y310623D03*
X1403300Y304640D03*
X1388208Y341489D03*
X1348080Y309825D03*
X1353142Y309761D03*
X1358792Y309760D03*
X1358800Y303700D03*
X1353359Y303767D03*
X1348190Y303810D03*
X1346550Y322350D03*
X1350650Y315050D03*
X1357452Y319395D03*
X1369540Y310125D03*
X1374900Y310130D03*
X1381100Y304360D03*
X1380910Y310300D03*
X1364044Y309691D03*
X1364213Y303694D03*
X1375040Y304135D03*
X1369540D03*
X1371000Y322400D03*
X1363059Y314514D03*
X1368947Y313993D03*
X1358500Y338400D03*
X1370200D03*
X1364300Y338300D03*
X1392144Y364617D03*
X1389450Y372250D03*
X1384700Y359700D03*
X1392500Y344600D03*
X1392805Y360466D03*
X1388500Y350864D03*
X1391200Y386300D03*
X1384531Y382957D03*
X1394760Y394720D03*
X1362510Y360717D03*
X1354024Y398985D03*
X1352338Y404153D03*
X1351379Y399227D03*
X1352239Y401593D03*
X1358512Y371792D03*
X1360450Y402100D03*
X1359360Y398810D03*
X1357880Y403760D03*
X1356560Y398910D03*
X1362250Y399160D03*
X1354681Y401444D03*
X1354982Y404154D03*
X1357542Y401381D03*
X1364856Y366666D03*
X1382017Y367584D03*
X1363250Y401700D03*
X1371200Y402100D03*
X1381500Y396200D03*
X1375201Y396303D03*
X1365731Y360698D03*
X1358500Y374500D03*
X1360200Y377400D03*
X1358655Y379352D03*
X1362068Y393385D03*
X1360300Y381100D03*
X1360200Y384700D03*
Y389000D03*
X1358700Y386700D03*
X1358568Y390885D03*
Y393385D03*
X1358600Y382800D03*
X1362068Y390885D03*
X1374268Y389985D03*
X1374207Y384968D03*
Y387468D03*
X1370300Y350200D03*
X1358300Y344200D03*
X1358400Y350100D03*
X1370200Y343900D03*
X1364100Y350200D03*
X1385416Y410502D03*
X1404558Y416575D03*
X1402725Y408136D03*
X1402520Y413246D03*
X1388085Y410479D03*
X1403998Y429775D03*
X1404558Y421575D03*
X1398275Y453561D03*
X1397975Y457561D03*
X1403998Y434775D03*
X1382849Y410471D03*
X1380449Y410479D03*
X1358990Y411040D03*
X1358910Y408480D03*
X1358980Y406060D03*
X1355100Y427500D03*
Y432500D03*
X1361558Y410527D03*
X1345100Y442500D03*
X1350100D03*
X1345100Y437500D03*
X1350100D03*
X1355100D03*
Y442500D03*
X1369034Y458075D03*
X1369907Y410513D03*
X1372535Y410512D03*
X1375239Y410590D03*
X1377928Y410451D03*
X1366984Y410481D03*
X1364403Y410496D03*
X1380100Y447500D03*
X1370100Y442500D03*
X1365100Y452500D03*
X1379857Y458108D03*
X1365100Y442500D03*
X1375100D03*
X1380100Y452500D03*
X1365100Y447500D03*
X1388900Y525230D03*
X1395581Y525357D03*
X1383600Y482504D03*
X1386041Y493723D03*
X1383519Y487445D03*
X1390330Y516690D03*
X1385033Y516848D03*
X1387568Y516892D03*
X1388865Y519788D03*
X1388850Y522266D03*
X1386033Y498811D03*
X1344073Y508263D03*
X1363800Y481600D03*
X1363662Y486636D03*
X1365741Y492723D03*
X1382578Y516805D03*
X1377492Y516892D03*
X1369757Y517465D03*
X1365719Y497545D03*
X1352490Y515470D03*
X1346870Y515450D03*
X1352590Y519170D03*
X1346970Y519150D03*
X1401777Y557632D03*
X1385033Y544267D03*
X1390623Y574986D03*
X1400830Y564090D03*
X1400288Y570099D03*
X1404420Y576330D03*
X1404519Y560280D03*
Y557380D03*
X1361600Y559400D03*
X1358529Y537492D03*
X1361163Y540052D03*
X1358518Y540073D03*
X1356018D03*
X1356029Y537492D03*
X1363674Y537471D03*
X1355548Y559959D03*
X1361926Y584037D03*
Y586537D03*
X1359100Y586200D03*
X1357400Y588400D03*
X1360100D03*
X1344613Y556376D03*
Y561376D03*
Y558876D03*
X1347700Y554100D03*
X1353520Y537480D03*
X1344613Y553876D03*
X1361174Y537471D03*
X1358439Y559959D03*
X1375479Y540117D03*
X1375500Y537717D03*
X1366265Y537437D03*
X1363663Y540052D03*
X1363568Y550589D03*
X1380521Y535276D03*
X1378021D03*
X1375621Y535254D03*
X1371265Y537437D03*
X1368765D03*
X1366459Y550589D03*
X1377979Y537717D03*
Y540117D03*
X1380479Y537717D03*
X1368596Y539889D03*
X1371096D03*
X1366096D03*
X1380479Y540117D03*
X1376800Y584328D03*
X1364426Y586637D03*
Y584137D03*
X1360500Y570900D03*
Y574700D03*
X1360261Y578873D03*
X1360247Y567390D03*
X1360261Y562373D03*
Y581373D03*
X1362000Y576700D03*
Y572800D03*
X1362100Y569100D03*
X1362000Y565600D03*
X1363761Y581373D03*
X1375961Y577973D03*
X1376000Y575456D03*
Y572956D03*
X1387050Y615350D03*
X1392500Y592000D03*
X1376556Y615756D03*
X1357726Y591037D03*
X1360226D03*
X1363761Y612573D03*
X1360261D03*
X1360200Y597800D03*
X1361600Y599900D03*
X1361500Y595700D03*
X1360100Y610100D03*
X1360200Y606300D03*
Y602000D03*
X1361900Y608200D03*
X1361500Y604200D03*
X1360261Y593573D03*
X1363761Y610073D03*
X1375961Y609173D03*
X1375900Y604156D03*
Y606656D03*
X1454715Y2784D03*
X1450508Y2756D03*
X1410571Y13170D03*
X1420019Y13466D03*
X1448367Y13533D03*
X1438918D03*
X1429469Y13466D03*
X1457814D03*
X1436131Y5248D03*
X1432661Y5220D03*
X1406674Y46120D03*
X1411254Y46018D03*
X1412250Y65359D03*
X1407150Y58859D03*
X1410150D03*
X1407150Y52859D03*
X1410150D03*
X1409250Y65359D03*
X1407150Y55859D03*
X1410150D03*
X1413721Y36749D03*
X1412250Y68359D03*
X1409250D03*
X1409150Y71259D03*
X1412150D03*
X1442067Y34830D03*
X1423170Y36635D03*
X1432619Y34830D03*
X1451516D03*
X1460965D03*
X1452648Y103788D03*
X1451273Y148905D03*
X1449847Y202322D03*
X1439000Y208500D03*
X1442251Y180818D03*
X1418300Y199900D03*
X1440150Y175550D03*
X1440124Y166180D03*
X1451427Y167818D03*
X1434800Y248900D03*
X1462700Y221700D03*
X1464200Y231400D03*
X1458800Y254882D03*
X1410800Y316100D03*
X1408580Y310632D03*
X1408760Y304637D03*
X1410550Y320800D03*
X1419343Y310652D03*
X1419283Y304570D03*
X1413983Y304645D03*
X1413943Y310628D03*
X1417656Y367547D03*
X1420101Y396236D03*
X1418138Y386361D03*
X1415000Y399000D03*
X1412220Y388360D03*
X1417217Y379129D03*
X1417349Y382137D03*
X1417773Y374107D03*
X1464124Y353776D03*
X1465500Y395400D03*
X1456750Y381850D03*
X1459033Y395334D03*
X1446700Y387900D03*
X1437897Y402315D03*
X1443100Y368950D03*
X1439934Y403730D03*
X1411900Y429775D03*
X1405375Y453561D03*
X1405608Y456761D03*
X1411900Y434775D03*
X1435479Y423107D03*
X1439350Y406900D03*
X1459200Y459800D03*
Y454100D03*
X1459000Y449997D03*
X1451400Y454100D03*
Y459800D03*
X1445000Y437000D03*
X1429000Y437059D03*
X1444800Y442500D03*
X1444500Y448000D03*
X1429100Y453400D03*
X1429000Y448000D03*
Y442600D03*
X1448800Y427800D03*
X1412447Y416368D03*
X1412545Y421974D03*
X1413300Y454400D03*
X1413075Y457561D03*
X1448800Y416500D03*
X1464300Y404900D03*
X1439000Y423000D03*
X1464600Y428000D03*
X1459300Y430000D03*
X1464525Y420014D03*
X1464731Y432942D03*
X1445100Y431500D03*
X1459200Y465500D03*
X1451400D03*
X1408753Y527518D03*
X1415541Y489523D03*
X1416100Y483500D03*
X1415800Y477500D03*
Y495200D03*
X1420200Y520500D03*
X1447749Y485395D03*
X1439314Y477723D03*
X1439400Y483600D03*
X1439341Y489323D03*
X1453700Y501600D03*
X1458357Y523271D03*
X1461100Y523600D03*
X1439400Y494700D03*
X1409693Y560343D03*
X1412093D03*
X1410850Y564210D03*
X1410340Y570370D03*
X1407019Y557380D03*
X1412019D03*
X1409519D03*
X1406993Y560343D03*
X1447852Y575687D03*
X1445800Y574300D03*
X1445750Y539000D03*
X1461500Y540000D03*
X1439861Y540497D03*
X1461653Y580762D03*
X1461707Y583162D03*
X1461878Y585556D03*
X1441805Y570887D03*
X1443797Y572482D03*
X1422500Y579800D03*
X1414800D03*
X1461930Y587956D03*
X1409500Y538000D03*
X1420500Y549800D03*
X1420400Y538000D03*
X1462039Y590354D03*
X1462155Y592761D03*
X1465334Y618564D03*
X1451314Y623298D03*
X1458000Y623400D03*
X1455000D03*
X1461000D03*
X1442200D03*
X1445200D03*
X1448200D03*
X1463419Y606912D03*
X1527700Y6963D03*
X1506900Y3500D03*
X1469807Y2967D03*
X1473674Y2953D03*
X1476712Y13466D03*
X1467264Y13533D03*
X1492900Y4000D03*
X1489600D03*
X1495611Y13466D03*
X1486162Y13500D03*
X1470414Y34830D03*
X1479863D03*
X1497711Y34427D03*
X1489311Y34830D03*
X1499613Y84046D03*
X1515294Y91306D03*
X1523563Y93565D03*
X1511700Y84600D03*
X1482300Y118400D03*
X1469747Y148276D03*
X1483093Y130796D03*
X1523950Y104050D03*
X1523889Y99033D03*
X1523557Y116165D03*
X1523813Y120546D03*
X1523756Y108762D03*
X1501603Y108500D03*
X1499618Y124520D03*
X1497699Y112140D03*
X1511634Y121195D03*
X1511635Y114535D03*
X1511650Y109400D03*
Y103400D03*
X1511651Y98675D03*
X1500775Y98101D03*
X1501700Y103300D03*
X1513023Y140630D03*
X1511664Y133603D03*
X1488350Y149450D03*
X1523719Y149488D03*
X1499800Y199300D03*
X1491196Y218527D03*
X1523400Y217900D03*
X1483523Y181100D03*
X1517328Y186208D03*
X1527500Y167726D03*
X1502192Y164871D03*
X1494783Y177907D03*
X1469150Y242931D03*
X1479500Y238500D03*
X1498685Y224715D03*
X1491700Y241661D03*
X1491407Y258353D03*
X1523470Y242580D03*
X1472500Y341074D03*
X1526722Y295400D03*
X1501583Y339389D03*
X1521817Y330937D03*
X1526000Y341000D03*
X1517600Y320940D03*
X1487426Y330100D03*
X1514722Y293257D03*
X1515482Y280800D03*
X1512300Y280847D03*
X1511900Y287500D03*
X1472550Y397500D03*
X1470800Y402250D03*
X1472680Y380630D03*
X1483172Y351806D03*
X1474500Y365500D03*
X1478500D03*
X1483500D03*
X1482000Y395098D03*
Y399035D03*
Y383287D03*
Y387224D03*
X1473255Y376254D03*
X1528146Y349842D03*
X1519626Y365817D03*
X1488394Y365466D03*
X1497275Y401174D03*
X1508975D03*
X1483950Y401650D03*
X1491425Y391034D03*
X1503125Y377514D03*
X1491425D03*
X1526525D03*
X1514825D03*
X1526525Y384274D03*
Y391034D03*
X1514825Y384274D03*
X1520675Y387654D03*
Y380894D03*
X1514825Y391034D03*
X1508975Y387654D03*
Y380894D03*
X1503125Y384274D03*
Y391034D03*
X1497275Y380894D03*
X1491425Y384274D03*
X1497275Y387654D03*
Y394414D03*
X1491425Y397794D03*
X1503125D03*
X1508975Y394414D03*
X1514825Y397794D03*
X1524575Y401174D03*
X1491425Y418074D03*
X1487525D03*
X1472449Y439421D03*
X1467000Y454100D03*
Y459800D03*
X1466800Y449997D03*
X1467401Y411557D03*
X1471900Y406900D03*
X1472530Y432731D03*
X1472400Y428063D03*
X1472800Y420689D03*
X1467000Y465500D03*
X1482000Y418720D03*
Y406909D03*
Y410846D03*
Y414783D03*
Y422658D03*
Y426595D03*
X1483400Y438100D03*
X1482603Y442418D03*
X1482000Y462028D03*
X1483115Y454379D03*
X1483200Y450455D03*
X1482500Y434600D03*
X1503125Y404554D03*
X1509200Y413600D03*
X1510925Y404554D03*
X1497275Y414694D03*
X1503125Y424834D03*
X1497275Y428214D03*
X1495325Y424834D03*
X1503125Y433406D03*
X1491425D03*
X1495325D03*
X1524950Y419900D03*
X1518650D03*
X1483818Y430597D03*
X1528100Y410550D03*
X1501219Y416596D03*
X1487525Y404554D03*
X1526525D03*
X1515500Y416750D03*
X1518700Y406500D03*
X1491425Y404554D03*
X1495325Y411314D03*
X1512350Y445100D03*
X1509200D03*
Y454550D03*
X1512400Y454500D03*
X1503125Y440166D03*
X1501175Y436786D03*
X1495325Y440166D03*
X1497275Y436786D03*
X1510925Y460446D03*
X1505442Y443900D03*
X1507025Y460446D03*
X1503125Y453786D03*
Y460446D03*
X1501175Y457066D03*
X1487525Y453686D03*
X1497275Y457066D03*
Y450306D03*
X1495325Y446926D03*
Y453686D03*
X1497275Y443546D03*
X1501175Y463826D03*
X1493375D03*
X1515500Y445100D03*
X1514825Y460446D03*
X1520675Y457066D03*
X1518725Y460446D03*
X1521800Y441950D03*
Y448250D03*
X1526525Y460446D03*
X1522625D03*
X1524950Y441950D03*
X1473140Y525407D03*
X1482000Y481713D03*
Y469902D03*
X1476800Y498900D03*
X1482300D03*
X1476800Y507300D03*
X1481700Y524200D03*
X1473800Y495800D03*
X1499225Y480726D03*
X1508975Y477346D03*
X1510925Y480726D03*
X1508975Y470586D03*
X1510925Y473966D03*
X1505075Y470586D03*
X1501175D03*
X1503125Y467206D03*
X1507025Y487486D03*
X1487525Y473966D03*
X1491425D03*
X1489475Y470586D03*
X1490100Y489700D03*
X1487525Y487486D03*
X1489475Y484106D03*
X1516775D03*
X1514825Y480726D03*
Y473966D03*
X1516775Y470586D03*
X1518725Y487486D03*
Y480726D03*
Y473966D03*
Y467206D03*
X1522625D03*
Y473966D03*
Y487486D03*
X1526525D03*
Y473966D03*
Y467206D03*
X1514825Y487486D03*
X1511752Y498780D03*
X1490929Y507104D03*
X1506060Y508180D03*
X1501490Y504988D03*
X1501934Y513047D03*
X1505743Y516117D03*
X1511215Y507781D03*
X1512400Y519020D03*
X1493930Y522800D03*
X1488410Y517810D03*
X1497267Y505323D03*
X1496174Y514221D03*
X1509000Y498750D03*
X1488500Y498900D03*
X1526500Y498671D03*
Y506400D03*
X1485300Y498962D03*
X1483804Y509928D03*
X1484200Y524200D03*
X1475316Y527194D03*
X1468101Y573963D03*
X1527698Y578870D03*
X1474776Y572315D03*
X1491776Y573571D03*
X1479893Y572315D03*
X1482293D03*
X1477493D03*
X1487093D03*
X1489493D03*
X1484693D03*
X1518000Y562330D03*
X1510740Y557860D03*
X1494422Y574000D03*
X1481400Y539700D03*
X1494200Y530600D03*
X1497106Y531368D03*
X1511388Y531045D03*
X1503200Y530500D03*
X1505600D03*
X1508772Y530416D03*
X1514118Y530411D03*
X1483900Y539700D03*
X1525500Y582674D03*
Y580184D03*
X1525837Y574700D03*
X1523416Y573949D03*
X1527822Y576130D03*
X1525500Y577684D03*
X1499900Y574000D03*
X1496900D03*
X1469701Y599554D03*
X1470353Y592128D03*
X1469767Y596353D03*
X1503008Y620018D03*
X1472412Y596032D03*
Y599532D03*
X1479029Y596132D03*
X1477129Y597656D03*
X1474912Y596032D03*
X1480760Y611602D03*
X1485429Y597571D03*
X1491412Y596032D03*
X1489229Y597571D03*
X1487329Y596032D03*
X1512500Y598639D03*
X1510450Y597300D03*
X1507950D03*
X1510450Y600800D03*
X1508031Y599922D03*
X1524800Y598778D03*
X1522900Y597300D03*
X1526950D03*
X1518800Y597200D03*
X1520813Y598508D03*
X1516800Y598639D03*
X1514500Y597300D03*
X1511350Y613000D03*
X1513867Y612939D03*
X1516367D03*
X1475812Y611732D03*
X1474912Y599532D03*
X1478329Y611671D03*
X1483104Y596072D03*
X1481229Y597571D03*
X1584447Y-6702D03*
X1579447D03*
X1570200Y12900D03*
X1579773Y13257D03*
X1589259Y10241D03*
X1541400Y12500D03*
X1528384Y28040D03*
X1551309Y12792D03*
X1560700Y13000D03*
X1589500Y-600D03*
X1589900Y84422D03*
X1583621Y87213D03*
X1588700Y94288D03*
X1573473Y37216D03*
X1582923D03*
X1532800Y78590D03*
X1542179Y39695D03*
X1554573Y37216D03*
X1564023D03*
X1578000Y113000D03*
X1585500Y101000D03*
X1555000Y139000D03*
X1548955Y101358D03*
X1558189Y107067D03*
X1554800Y129100D03*
Y98200D03*
X1558100D03*
X1558383Y121500D03*
X1554945Y133400D03*
X1583600Y207495D03*
X1535399Y190920D03*
X1533132Y158068D03*
X1531565Y176645D03*
X1537298Y162703D03*
X1557634Y175948D03*
X1562079Y163580D03*
X1530200Y257200D03*
X1528460Y244371D03*
X1563440Y250955D03*
X1559577Y236300D03*
X1547000Y263500D03*
Y269400D03*
X1541000Y263500D03*
Y269500D03*
X1544000Y266500D03*
X1578630Y293430D03*
X1580150Y329483D03*
X1528250Y311900D03*
X1530033Y340799D03*
X1539400Y320200D03*
X1544904Y334008D03*
X1557250Y315410D03*
X1554800Y290600D03*
X1586400Y392900D03*
X1567475Y380894D03*
Y387654D03*
X1582420Y377830D03*
X1582350Y374567D03*
X1582124Y381164D03*
X1573000Y391161D03*
X1571366Y401154D03*
X1582000Y396250D03*
X1567475Y394414D03*
X1570672Y362134D03*
X1567121Y365817D03*
X1576380Y362890D03*
X1582500Y369600D03*
X1573521Y365500D03*
X1532375Y380894D03*
Y387654D03*
Y394414D03*
X1538225Y377514D03*
Y384274D03*
X1544075Y380894D03*
Y387654D03*
X1538225Y391034D03*
Y397794D03*
X1544075Y394414D03*
X1558996Y365817D03*
X1555775Y394414D03*
X1549925Y397794D03*
X1561625D03*
X1555775Y401174D03*
X1549925Y377514D03*
X1561625D03*
Y391034D03*
Y384274D03*
X1549925Y391034D03*
Y384274D03*
X1555775Y387654D03*
Y380894D03*
X1571375Y421454D03*
X1569425Y418074D03*
X1571375Y414694D03*
X1559675Y463826D03*
X1563575Y421454D03*
X1557725Y424834D03*
X1567475Y450306D03*
X1565525Y440166D03*
X1571375Y457066D03*
X1567475D03*
X1569425Y460446D03*
X1582200Y456200D03*
X1565525Y431594D03*
X1569425D03*
Y404554D03*
X1583208Y412815D03*
X1569425Y411314D03*
X1571390Y464480D03*
X1567475Y421454D03*
X1531250Y419900D03*
Y451400D03*
Y441950D03*
X1530425Y460446D03*
X1551875Y407934D03*
Y414694D03*
X1563575Y407934D03*
X1559675Y414694D03*
X1546025Y404554D03*
X1561625Y424834D03*
X1551990Y421158D03*
X1551875Y428214D03*
X1561625Y431594D03*
X1563575Y428214D03*
X1555775Y443546D03*
Y436786D03*
X1563575Y457066D03*
X1549938Y453714D03*
X1547975Y457066D03*
X1549925Y446926D03*
X1557725D03*
X1561625Y460446D03*
X1555775Y457066D03*
X1551875D03*
X1557725Y453686D03*
X1559675Y443546D03*
Y436786D03*
X1547975Y463826D03*
X1551875D03*
X1555775D03*
X1534400Y419900D03*
X1540700D03*
X1543850Y429350D03*
Y426200D03*
X1537550Y419900D03*
X1534325Y404554D03*
X1538225D03*
X1542125D03*
X1540700Y410450D03*
X1534400Y451400D03*
Y441950D03*
X1537550D03*
X1534325Y460446D03*
X1537550Y451400D03*
X1544075Y457066D03*
X1540175D03*
X1540700Y451400D03*
Y441950D03*
X1540175Y463826D03*
X1543850Y435650D03*
X1537550D03*
X1582644Y495077D03*
X1568600Y494500D03*
X1565210Y509160D03*
X1567817Y499735D03*
X1569425Y473966D03*
X1571375Y470586D03*
X1565525Y480726D03*
X1570062Y487039D03*
X1587970Y472370D03*
X1587433Y490425D03*
X1567475Y470586D03*
X1532375D03*
X1530425Y473966D03*
X1528475Y470586D03*
Y477346D03*
X1534180Y498580D03*
X1534039Y502906D03*
X1531580Y510790D03*
X1534325Y487486D03*
X1536275Y484106D03*
X1544075Y470586D03*
X1542125Y473966D03*
X1540175Y477346D03*
X1536275Y470586D03*
X1544075Y477346D03*
X1538225Y473966D03*
X1542475Y504400D03*
X1542425Y512200D03*
X1546025Y467206D03*
X1553825Y487486D03*
Y480726D03*
X1557725D03*
X1549925Y473966D03*
X1547975Y470586D03*
X1553825Y473966D03*
Y467206D03*
X1555775Y470586D03*
X1557725Y473966D03*
X1555775Y477346D03*
Y484106D03*
X1549925Y487486D03*
X1546025Y480726D03*
X1548300Y499000D03*
X1564600Y500414D03*
X1555424Y504609D03*
X1555832Y512288D03*
X1548300Y506600D03*
X1580360Y565524D03*
X1580400Y568000D03*
X1580300Y563000D03*
Y560500D03*
X1566000Y575820D03*
X1565940Y573120D03*
X1565800Y570600D03*
X1565600Y568100D03*
Y565700D03*
X1529944Y574725D03*
X1529894Y577342D03*
X1532354Y577283D03*
X1532642Y579853D03*
X1529600Y582300D03*
X1532400D03*
X1529942Y579853D03*
X1563800Y564100D03*
X1561300Y564000D03*
X1558800Y563900D03*
X1563448Y566766D03*
X1563432Y569340D03*
X1589604Y585896D03*
X1581704D03*
X1587504Y605496D03*
Y607996D03*
X1563827Y621376D03*
X1554800Y620910D03*
X1537711Y613397D03*
X1538679Y615641D03*
X1534928Y610532D03*
X1538337Y601097D03*
X1534948Y613302D03*
X1545000Y591100D03*
X1581704Y590196D03*
X1589604D03*
X1558800Y599300D03*
X1560400Y611600D03*
X1564300Y599400D03*
X1564400Y605500D03*
X1561700Y602200D03*
X1552400Y607600D03*
X1554900Y607100D03*
X1556200Y602400D03*
X1554400Y599300D03*
X1564300Y611500D03*
X1602504Y-17346D03*
X1646200Y5300D03*
X1646400Y13400D03*
X1597700Y9000D03*
X1615000Y12000D03*
X1634200Y9700D03*
X1627500Y11700D03*
X1608123Y13302D03*
X1619100Y6500D03*
X1626400Y4600D03*
X1606700D03*
X1636500D03*
X1591270Y93940D03*
X1592200Y37700D03*
X1590464Y77962D03*
X1637700Y67400D03*
X1639623Y38100D03*
X1649073Y38200D03*
X1620050Y35550D03*
X1608500Y72688D03*
X1606730Y84230D03*
X1632000Y83000D03*
X1625451Y84288D03*
X1605184Y61044D03*
X1610450Y37300D03*
X1627380Y36652D03*
X1630121Y37609D03*
X1595943Y71522D03*
X1603138Y65890D03*
X1602840Y37382D03*
X1635900Y83000D03*
X1595335Y98135D03*
X1641600Y96500D03*
X1638500D03*
X1595522Y127278D03*
X1650300Y195251D03*
X1648400Y214100D03*
X1643887Y181841D03*
X1604401Y213500D03*
X1618500Y181680D03*
X1625524Y184531D03*
X1635100Y182800D03*
X1620036Y196186D03*
X1635112Y195181D03*
X1605250Y197250D03*
X1591174Y225017D03*
X1640871Y235210D03*
X1608489Y252095D03*
X1635503Y340146D03*
X1629503D03*
X1603307Y393224D03*
X1591912Y391052D03*
X1650624Y357884D03*
X1650480Y368215D03*
X1642126Y357894D03*
X1642114Y368142D03*
X1601060Y401010D03*
X1599100Y399100D03*
X1610828Y381387D03*
X1596151D03*
X1596168Y375135D03*
X1609761Y372584D03*
X1613474Y391105D03*
X1620447Y373926D03*
X1610642Y375135D03*
X1608020Y356500D03*
X1619889Y352841D03*
X1607443Y398649D03*
X1629503Y346146D03*
X1635503Y346046D03*
X1632503Y343146D03*
X1621010Y435870D03*
X1620500Y463727D03*
X1634500Y418500D03*
X1603650Y415469D03*
X1646540Y441240D03*
X1604200Y464387D03*
X1594880Y494880D03*
X1646700Y480300D03*
X1639394Y507798D03*
X1627032Y510226D03*
X1627068Y512626D03*
X1606200Y487100D03*
X1623814Y471400D03*
X1614000Y469500D03*
X1617700Y489700D03*
X1615200D03*
X1611506Y474768D03*
X1620500Y475000D03*
X1603500Y495300D03*
X1597178Y472226D03*
X1599900Y487100D03*
X1603802Y487205D03*
X1629530Y496374D03*
X1644800Y532800D03*
X1636848Y533794D03*
X1649900Y583500D03*
X1638674Y556178D03*
X1622040Y554827D03*
X1609829Y556599D03*
X1624293Y561747D03*
X1615030Y584260D03*
X1610080Y561367D03*
X1603060Y582920D03*
X1603120Y578020D03*
X1599170Y572780D03*
X1602000Y565700D03*
X1590004Y605496D03*
Y607996D03*
X1601504Y591526D03*
X1613721Y592325D03*
X1614700Y597000D03*
X1615862Y605507D03*
X1601489Y602812D03*
X1601270Y597200D03*
X1602150Y610720D03*
X1654800Y13518D03*
X1711863Y13276D03*
X1672427Y9700D03*
X1664200Y5400D03*
X1656600Y6300D03*
X1664823Y13287D03*
X1685500Y3000D03*
X1682985Y2901D03*
X1675800Y4100D03*
X1702421Y13231D03*
X1684902Y13472D03*
X1691541Y13226D03*
X1700710Y73292D03*
X1700300Y94703D03*
X1672000Y51500D03*
X1669350Y69962D03*
X1709600Y45800D03*
X1692573Y85833D03*
X1702513Y79885D03*
X1668009Y37000D03*
X1706500D03*
X1678000D03*
X1687500D03*
X1696795Y38260D03*
X1658559Y37890D03*
X1659038Y95111D03*
X1659000Y85500D03*
X1670250Y87873D03*
X1674455Y169991D03*
X1677605Y169986D03*
X1687950Y186150D03*
X1708250Y164950D03*
X1671556Y208379D03*
X1657498Y277300D03*
Y267100D03*
X1657949Y257240D03*
X1653091Y331618D03*
X1652991Y318741D03*
Y323941D03*
X1657500Y287800D03*
X1657600Y304500D03*
X1681192Y454286D03*
X1668000Y416200D03*
X1695658Y486945D03*
X1694410Y499830D03*
X1692120Y501410D03*
X1699900Y512300D03*
X1709400Y513000D03*
X1652500Y575600D03*
X1667277Y535221D03*
X1698600Y584800D03*
X1664113Y548380D03*
X1658466D03*
X1661880Y583900D03*
X1686036Y548251D03*
X1677300Y550200D03*
X1680007Y547917D03*
X1669121Y547923D03*
X1708140Y547538D03*
X1697839Y545759D03*
X1709183Y588700D03*
X1654100Y615790D03*
X1653970Y607340D03*
X1652700Y591300D03*
Y600850D03*
X1662580Y593200D03*
X1661200Y601300D03*
Y607300D03*
X1730550Y21160D03*
X1721559Y13500D03*
X1730768Y13313D03*
X1763100Y21500D03*
X1768807Y21512D03*
X1753903Y22116D03*
X1749941Y21163D03*
X1741000Y21200D03*
X1715259Y35602D03*
X1715100Y46100D03*
X1713550Y56000D03*
X1716900Y87900D03*
X1753059Y35300D03*
X1735150Y60650D03*
X1748500Y79500D03*
X1748854Y58533D03*
X1717600Y46100D03*
X1724758Y38600D03*
X1720600Y70200D03*
X1733910Y38233D03*
X1757054Y66059D03*
X1758100Y37000D03*
X1749364Y38971D03*
X1743500Y39300D03*
X1768450Y77376D03*
X1765900Y83700D03*
X1754703Y84053D03*
X1771459Y52695D03*
X1733900Y92200D03*
X1754600Y109200D03*
X1767250Y99500D03*
Y104500D03*
X1770850Y109500D03*
X1714189Y159550D03*
X1714528Y190189D03*
X1758650Y158650D03*
X1750189Y159550D03*
X1745689D03*
X1741189D03*
X1727689D03*
X1723189D03*
X1718689D03*
X1732189D03*
X1736689D03*
X1745777Y179574D03*
X1751975Y179374D03*
X1739377D03*
X1733178Y179574D03*
X1758375D03*
X1764673Y179374D03*
X1770973Y179574D03*
X1726700Y179400D03*
X1740900Y198800D03*
X1744000D03*
X1769100Y209700D03*
X1765950Y209600D03*
X1769016Y198872D03*
X1765866Y198772D03*
X1731260Y209600D03*
X1740709D03*
X1756000Y210000D03*
X1753400Y209900D03*
X1743900Y209700D03*
X1728616Y198872D03*
X1753311Y198700D03*
X1756600Y198800D03*
X1731216Y198872D03*
X1763554Y237712D03*
X1762795Y232106D03*
X1772244D03*
X1752554Y237712D03*
X1771451D03*
X1724944Y250324D03*
X1727444D03*
X1771243Y250100D03*
X1729944Y250324D03*
X1768516Y249983D03*
X1744603Y232489D03*
X1753347Y232106D03*
X1763300Y250100D03*
X1766100Y447900D03*
X1762992Y447938D03*
X1740963Y448476D03*
X1753543Y448100D03*
X1750393Y448037D03*
X1737795Y448100D03*
X1722000Y513000D03*
X1742900Y485000D03*
X1734000Y488100D03*
X1755000Y485000D03*
X1748600D03*
X1749396Y493969D03*
X1751868Y494045D03*
X1770325Y490255D03*
X1773500Y472100D03*
X1767300Y472700D03*
X1765325Y490255D03*
X1758500Y493800D03*
X1760900Y472800D03*
X1772459Y467005D03*
X1769309D03*
X1759860D03*
X1756710D03*
X1747262D03*
X1744112D03*
X1734663D03*
X1729200Y519000D03*
X1733830Y502650D03*
X1768900Y521124D03*
X1749090Y513790D03*
X1740400Y496300D03*
X1726600Y519000D03*
X1728700Y502600D03*
X1713600Y513000D03*
X1756417Y563840D03*
X1746000Y574000D03*
X1718000Y587723D03*
X1749000Y552863D03*
X1769000Y576378D03*
X1742381Y585530D03*
X1730814Y568814D03*
X1733000Y560000D03*
X1767455Y571695D03*
X1767000Y563500D03*
X1728245Y585244D03*
X1746052Y614796D03*
X1724092Y618700D03*
X1772158Y610960D03*
X1750739Y618718D03*
X1742509Y595869D03*
X1742381Y591530D03*
X1763500Y599100D03*
X1727843Y597142D03*
X1732443Y592342D03*
Y597142D03*
X1727743Y592342D03*
X1832449Y-8950D03*
X1785612Y10729D03*
X1782371Y26832D03*
X1804508Y11858D03*
X1798676Y11726D03*
X1830344Y13397D03*
X1828824Y3699D03*
X1816693Y13331D03*
X1819800Y35500D03*
X1790700Y34900D03*
X1799774Y34890D03*
X1808444Y37152D03*
X1800000Y80000D03*
X1827000Y87000D03*
X1834300Y41100D03*
X1788200Y93000D03*
Y89000D03*
Y85000D03*
X1818383Y133277D03*
X1788448Y98820D03*
X1788648Y101490D03*
X1807745Y104500D03*
X1803400Y114000D03*
X1796059Y104402D03*
X1801366Y151937D03*
X1811348Y143448D03*
X1800264Y143789D03*
X1800000Y132627D03*
X1820648Y155537D03*
X1816348D03*
X1777172Y179374D03*
X1778466Y198772D03*
X1783572Y179574D03*
X1802369Y179374D03*
X1808769Y179574D03*
X1815000Y179300D03*
X1789870Y179374D03*
X1796170Y179574D03*
X1795348Y172037D03*
X1797848D03*
X1792748Y171937D03*
X1821367Y179574D03*
X1827565Y179174D03*
X1833388Y179500D03*
X1791150Y209600D03*
X1794300Y209700D03*
X1794216Y198872D03*
X1791066Y198772D03*
X1819457Y198872D03*
X1828700Y198800D03*
X1820349Y209586D03*
X1828950Y209600D03*
X1832274Y209734D03*
X1816266Y198772D03*
X1804166Y198472D03*
X1807751Y209586D03*
X1803072Y209728D03*
X1806821Y198600D03*
X1815670Y209728D03*
X1781700Y209700D03*
X1778550Y209600D03*
X1781616Y198872D03*
X1816348Y163437D03*
X1818500Y159500D03*
X1820648Y163437D03*
X1782452Y237712D03*
X1820281Y250498D03*
X1809281D03*
X1801384D03*
X1790383D03*
X1791141Y232106D03*
X1828936Y249900D03*
X1819488Y232106D03*
X1810040D03*
X1800591D03*
X1781693D03*
X1775590Y448100D03*
X1778740D03*
X1828600Y450100D03*
X1825984Y448030D03*
X1816535Y448300D03*
X1813385Y447945D03*
X1804000Y447900D03*
X1800787Y447943D03*
X1791338Y448400D03*
X1788189Y448300D03*
X1779700Y472100D03*
X1784525Y491830D03*
X1781907Y467005D03*
X1785057D03*
X1779303Y497246D03*
X1832301Y467005D03*
X1835550Y466870D03*
X1789774Y476403D03*
X1801500Y471055D03*
X1795164Y476406D03*
X1789525Y491830D03*
X1801125D03*
X1796125D03*
X1817325Y481320D03*
X1806600Y471055D03*
X1812325Y481320D03*
X1806975Y491630D03*
X1830220Y479950D03*
X1824960Y473980D03*
X1824125Y491830D03*
X1822852Y467005D03*
X1819702D03*
X1819125Y491830D03*
X1807104Y467005D03*
X1810254D03*
X1811975Y491630D03*
X1797655Y467005D03*
X1794505D03*
X1810508Y515900D03*
X1804000Y498176D03*
X1834540Y519600D03*
X1796400Y498000D03*
X1781510Y546362D03*
X1786500Y562200D03*
X1783700Y579200D03*
X1828800Y546500D03*
X1828700Y540252D03*
X1828900Y552300D03*
X1834000Y534900D03*
X1811704Y554341D03*
X1807600Y552047D03*
X1806200Y549200D03*
X1786900Y552500D03*
X1801200Y529800D03*
X1806200Y582900D03*
X1810387Y571435D03*
X1794000Y568800D03*
X1793320Y557968D03*
X1828700Y569474D03*
X1836281Y589122D03*
X1828800Y575600D03*
X1828875Y563674D03*
X1828824Y557663D03*
X1810385Y568821D03*
X1807958Y565690D03*
X1812452Y538501D03*
Y533601D03*
X1807852D03*
X1807752Y538501D03*
X1779000Y598900D03*
X1787500Y597791D03*
X1825014Y593695D03*
X1811500Y603500D03*
X1808152Y591601D03*
X1812852Y596401D03*
X1808252D03*
X1812852Y591601D03*
X1893094Y-10142D03*
X1838100Y3900D03*
X1889218Y43530D03*
Y53530D03*
X1846800Y95400D03*
X1847000Y86500D03*
X1848000Y56500D03*
X1850500D03*
X1890803Y63189D03*
X1884500Y79300D03*
X1882000D03*
X1895330Y64390D03*
X1877270Y63473D03*
X1880230Y76820D03*
X1879500Y79300D03*
X1880986Y53299D03*
X1860995Y84509D03*
X1856873Y91200D03*
X1856778Y87397D03*
X1864208Y87724D03*
X1864195Y84509D03*
X1864153Y91241D03*
X1860815Y91184D03*
X1875100Y51300D03*
X1872340Y147236D03*
X1895800Y149200D03*
X1885400Y147000D03*
X1878550Y99470D03*
X1882550D03*
X1894834Y139286D03*
X1863908Y140992D03*
X1878950Y137400D03*
X1871855Y104188D03*
X1856700Y110167D03*
X1869000Y153900D03*
X1887830Y102227D03*
X1852600Y97500D03*
X1887300Y121500D03*
X1850700Y156000D03*
X1875700Y115700D03*
Y121500D03*
X1881500Y115700D03*
Y121500D03*
Y127300D03*
X1887300D03*
X1875700D03*
X1887300Y115700D03*
X1846663Y153748D03*
X1839500Y212700D03*
X1857044Y186292D03*
X1863750Y163750D03*
X1868375Y171900D03*
X1846163Y168448D03*
X1886800Y210600D03*
X1871708Y213442D03*
X1854663Y158248D03*
X1846663D03*
X1852300Y252000D03*
X1858400Y251200D03*
X1843700Y253400D03*
X1839400Y450440D03*
X1838768Y454120D03*
X1847185Y454368D03*
X1860158Y450322D03*
X1864300Y447900D03*
X1882677Y447930D03*
X1895275Y454422D03*
X1898425Y447930D03*
Y454422D03*
X1845330Y466870D03*
X1843000Y505000D03*
X1857480Y466800D03*
X1861300D03*
X1881285Y467049D03*
X1849795Y493379D03*
X1850290Y486610D03*
X1872908Y471338D03*
X1870138Y485732D03*
X1852340Y509140D03*
X1877518Y527560D03*
X1889800Y580200D03*
X1878000Y539000D03*
X1861080Y537090D03*
X1842500Y534500D03*
X1844100Y551000D03*
X1848900Y545500D03*
X1878450Y548650D03*
X1870250Y541950D03*
X1896500Y555300D03*
X1879800Y579000D03*
X1858000Y574000D03*
X1870892Y583245D03*
X1874825Y564125D03*
X1859167Y559350D03*
X1894299Y557790D03*
X1906438Y-15968D03*
X1909406Y76790D03*
X1907986Y82393D03*
X1907929Y84793D03*
X1907907Y87223D03*
X1918379Y84788D03*
X1905501Y79790D03*
X1902796Y79820D03*
X1900100Y145100D03*
X1921199Y140499D03*
X1929711Y155759D03*
X1904136Y140160D03*
X1937000Y150000D03*
X1906871Y106049D03*
X1911231Y137097D03*
X1908715Y104512D03*
X1912100Y142600D03*
X1915030Y147250D03*
X1911440Y128840D03*
X1952440Y98520D03*
X1942637Y100877D03*
X1914152Y115928D03*
X1950983Y147344D03*
X1928100Y136078D03*
X1953200Y195530D03*
X1937100Y206800D03*
X1908967Y201609D03*
X1909186Y211906D03*
X1944500Y183900D03*
X1903524Y208156D03*
X1905074Y198163D03*
X1943200Y214800D03*
X1928400Y212500D03*
X1926000Y212400D03*
X1933898Y216707D03*
X1945156Y160236D03*
X1950994Y173745D03*
X1939316Y173600D03*
X1900740Y178720D03*
X1900700Y172990D03*
Y167290D03*
X1906440Y178720D03*
X1906500Y173100D03*
X1906400Y167290D03*
X1912190Y178870D03*
X1912230Y167330D03*
Y173030D03*
X1946105Y230344D03*
X1902909Y223195D03*
X1943517Y223637D03*
X1943800Y241800D03*
X1943900Y238500D03*
X1934750Y242700D03*
Y240300D03*
X1925600Y242700D03*
X1929000Y445800D03*
X1910500Y435600D03*
X1927100Y436200D03*
X1930100D03*
X1904724Y454422D03*
X1901574Y447930D03*
X1907500Y435600D03*
X1911023Y448400D03*
X1907874Y454422D03*
Y448400D03*
X1933100Y436200D03*
X1957100Y502990D03*
X1955790Y499790D03*
X1947380Y482450D03*
X1915100Y480050D03*
X1905010Y479410D03*
X1939000Y479400D03*
X1952500Y508000D03*
X1959260Y506010D03*
X1938410Y490650D03*
X1929480Y472880D03*
X1905000Y533900D03*
X1906050Y569100D03*
X1923600Y554200D03*
X1955400Y530500D03*
X1923600Y572300D03*
X1908400Y556800D03*
X1915593Y576807D03*
X1953500Y551900D03*
X1943300Y535700D03*
X1921800Y586100D03*
X1936770Y607210D03*
X1906200Y607800D03*
X1916050Y604450D03*
X1924000Y611391D03*
X1968179Y77969D03*
X1965679D03*
Y75369D03*
X1968179D03*
X1965679Y82969D03*
Y80469D03*
X1968179D03*
X1966212Y72897D03*
X1970679Y75369D03*
Y80469D03*
Y77969D03*
X1962800Y143700D03*
X1971200Y152500D03*
X1965400Y149700D03*
X1961472Y165760D03*
X1967817Y201029D03*
X1965900Y184600D03*
X1965057Y176447D03*
X1966542Y179606D03*
X1965973Y166190D03*
X1970270Y474640D03*
X1968870Y481710D03*
X1970500Y502720D03*
X1963500Y521000D03*
X1961500Y561700D03*
Y582700D03*
X1972700Y552700D03*
G54D21*
X1952756Y-14960D03*
Y58268D03*
G54D12*
X-15748Y101221D03*
Y148465D03*
Y357362D03*
Y373110D03*
Y388858D03*
Y404606D03*
X12205Y156339D03*
X-4331D03*
X17323Y101221D03*
Y116969D03*
Y132717D03*
Y148465D03*
X787Y101221D03*
Y116969D03*
Y148465D03*
X33858Y101221D03*
Y116969D03*
Y132717D03*
Y148465D03*
X28740Y109095D03*
Y156339D03*
X12205Y109095D03*
Y140591D03*
X-4331Y109095D03*
Y124843D03*
Y140591D03*
X17323Y357362D03*
Y373110D03*
Y388858D03*
Y404606D03*
X787Y357362D03*
Y373110D03*
Y388858D03*
Y404606D03*
X33858Y357362D03*
Y373110D03*
Y388858D03*
Y404606D03*
X28740Y365236D03*
Y380984D03*
Y396732D03*
X12205Y365236D03*
Y380984D03*
Y396732D03*
X-4331Y365236D03*
Y380984D03*
Y396732D03*
X12205Y412480D03*
X-4331D03*
X28740D03*
G54D22*
G01X238282Y649870D02*
Y649670D01*
G01X1702205Y536791D02*
X1699953Y539043D01*
G01X1687205Y536791D02*
X1689457Y539043D01*
G01X1687205Y536791D02*
X1689457Y534539D01*
G01X1699953D02*
X1702205Y536791D01*
G01D02*
X1704457Y539043D01*
G01X1702205Y536791D02*
X1704457Y534539D01*
G01X1753465Y536791D02*
X1755576Y538902D01*
G01X1749528Y536791D02*
X1751354Y538617D01*
G01X1753465Y536791D02*
X1755576Y534680D01*
G01X1751354Y538617D02*
X1751639Y538902D01*
G01X1751354Y538617D02*
Y538902D01*
G01X1747417Y534680D02*
X1749528Y536791D01*
G01X1747417Y538902D02*
X1749528Y536791D01*
G01D02*
X1751639Y534680D01*
G01X1751354D02*
X1753465Y536791D01*
G01X1751354Y538902D02*
X1753465Y536791D01*
G01X1714953Y534539D02*
X1717205Y536791D01*
G01X1714953Y539043D02*
X1717205Y536791D01*
G54D13*
X30500Y-42250D03*
Y-52250D03*
X12290Y264640D03*
X18450Y267010D03*
X22970Y244400D03*
X28720Y244450D03*
X17120Y244220D03*
X24200Y267060D03*
X50500Y-42250D03*
X70500D03*
X90500D03*
X110500D03*
X50500Y-52250D03*
X70500D03*
X90500D03*
X110500D03*
X130500Y-42250D03*
Y-52250D03*
X457246Y-52301D03*
Y-42301D03*
X477246Y-52301D03*
Y-42301D03*
X497246Y-52301D03*
Y-42301D03*
X517246Y-52301D03*
Y-42301D03*
X537246Y-52301D03*
Y-42301D03*
X557246Y-52301D03*
Y-42301D03*
X788984Y-52057D03*
Y-42057D03*
X808984Y-52057D03*
Y-42057D03*
X828984Y-52057D03*
Y-42057D03*
X848984Y-52057D03*
Y-42057D03*
X868984Y-52057D03*
Y-42057D03*
X888984Y-52057D03*
Y-42057D03*
X1125583Y-52285D03*
Y-42285D03*
X1145583Y-52285D03*
Y-42285D03*
X1382258Y-52257D03*
Y-42257D03*
X1402258Y-52257D03*
Y-42257D03*
X1422258Y-52257D03*
Y-42257D03*
X1442258Y-52257D03*
Y-42257D03*
G54D23*
G01X548049Y-193422D02*
Y-210922D01*
G01X543027Y-193422D02*
X553071D01*
G01X565549Y-199256D02*
Y-210922D01*
G01Y-194589D02*
X565112Y-194297D01*
Y-193714D01*
X565549Y-193422D01*
X565986Y-193714D01*
Y-194297D01*
X565549Y-194589D01*
G01X583049Y-210922D02*
X581739Y-210630D01*
X580429Y-209464D01*
X579555Y-207422D01*
X579119Y-205089D01*
X579555Y-202755D01*
X580429Y-200714D01*
X581739Y-199547D01*
X583049Y-199256D01*
X584359Y-199547D01*
X585669Y-200714D01*
X586542Y-202755D01*
X586761Y-205089D01*
X586542Y-207422D01*
X585669Y-209464D01*
X584359Y-210630D01*
X583049Y-210922D01*
G01X597492Y-215297D02*
X599021Y-216464D01*
X600767Y-216755D01*
X602295Y-216464D01*
X603606Y-215006D01*
X604479Y-212964D01*
Y-199256D01*
G01Y-201589D02*
X603606Y-200422D01*
X602295Y-199547D01*
X600767Y-199256D01*
X599021Y-199839D01*
X597929Y-201005D01*
X597055Y-203047D01*
X596619Y-205089D01*
X596837Y-206839D01*
X597711Y-208881D01*
X599021Y-210339D01*
X600767Y-210922D01*
X602077Y-210630D01*
X603606Y-209464D01*
X604479Y-208298D01*
G01X621979Y-210922D02*
Y-199256D01*
G01Y-201297D02*
X621106Y-200131D01*
X619795Y-199547D01*
X618267Y-199256D01*
X616739Y-199839D01*
X615429Y-201005D01*
X614555Y-202755D01*
X614119Y-205089D01*
X614555Y-207422D01*
X615429Y-209172D01*
X616739Y-210339D01*
X618267Y-210922D01*
X619795Y-210630D01*
X621106Y-209756D01*
X621979Y-208589D01*
G01X648682Y-210922D02*
Y-193422D01*
X653922D01*
X655669Y-194297D01*
X656979Y-196339D01*
X657416Y-198672D01*
X656979Y-201005D01*
X655887Y-202755D01*
X653922Y-203631D01*
X648682D01*
G01X674479Y-210922D02*
Y-199256D01*
G01Y-201297D02*
X673606Y-200131D01*
X672295Y-199547D01*
X670767Y-199256D01*
X669239Y-199839D01*
X667929Y-201005D01*
X667055Y-202755D01*
X666619Y-205089D01*
X667055Y-207422D01*
X667929Y-209172D01*
X669239Y-210339D01*
X670767Y-210922D01*
X672295Y-210630D01*
X673606Y-209756D01*
X674479Y-208589D01*
G01X684774Y-208881D02*
X685866Y-210047D01*
X687394Y-210922D01*
X688704D01*
X690014Y-210339D01*
X690887Y-209464D01*
X691324Y-208298D01*
X691106Y-206547D01*
X690232Y-205672D01*
X686302Y-203922D01*
X685429Y-201880D01*
X685866Y-200422D01*
X686739Y-199547D01*
X688049Y-199256D01*
X689359Y-199547D01*
X690669Y-200422D01*
G01X702274Y-208881D02*
X703366Y-210047D01*
X704894Y-210922D01*
X706204D01*
X707514Y-210339D01*
X708387Y-209464D01*
X708824Y-208298D01*
X708606Y-206547D01*
X707732Y-205672D01*
X703802Y-203922D01*
X702929Y-201880D01*
X703366Y-200422D01*
X704239Y-199547D01*
X705549Y-199256D01*
X706859Y-199547D01*
X708169Y-200422D01*
G01X735746Y-210922D02*
Y-193422D01*
X740112D01*
X741859Y-194297D01*
X743169Y-195464D01*
X744261Y-197213D01*
X745134Y-199256D01*
X745352Y-202172D01*
X745134Y-205089D01*
X744261Y-207131D01*
X743169Y-208881D01*
X741859Y-210047D01*
X740112Y-210922D01*
X735746D01*
G01X752590Y-193422D02*
X758049Y-210922D01*
X763508Y-193422D01*
G01X775549D02*
Y-210922D01*
G01X770527Y-193422D02*
X780571D01*
G01X804872Y-210922D02*
Y-193422D01*
X810549Y-208005D01*
X816226Y-193422D01*
Y-210922D01*
G01X829795Y-201589D02*
X830669Y-200714D01*
X831324Y-199256D01*
X831761Y-197213D01*
X831324Y-195464D01*
X830451Y-194297D01*
X828922Y-193422D01*
X823027D01*
Y-210922D01*
X830232D01*
X831761Y-209756D01*
X832634Y-208005D01*
X833071Y-205964D01*
X832634Y-203922D01*
X831324Y-202172D01*
X829795Y-201589D01*
X823027D01*
G01X647372Y-165922D02*
Y-148422D01*
X653049Y-163005D01*
X658726Y-148422D01*
Y-165922D01*
G01X670549D02*
X669239Y-165630D01*
X667929Y-164464D01*
X667055Y-162422D01*
X666619Y-160089D01*
X667055Y-157755D01*
X667929Y-155714D01*
X669239Y-154547D01*
X670549Y-154256D01*
X671859Y-154547D01*
X673169Y-155714D01*
X674042Y-157755D01*
X674261Y-160089D01*
X674042Y-162422D01*
X673169Y-164464D01*
X671859Y-165630D01*
X670549Y-165922D01*
G01X691979Y-148422D02*
Y-165922D01*
G01Y-163298D02*
X691106Y-164756D01*
X689795Y-165630D01*
X688267Y-165922D01*
X686521Y-165339D01*
X685211Y-163881D01*
X684337Y-162131D01*
X684119Y-160089D01*
X684337Y-158047D01*
X685211Y-156297D01*
X686521Y-154839D01*
X688267Y-154256D01*
X689795Y-154547D01*
X690887Y-155131D01*
X691979Y-156297D01*
G01X702274Y-158047D02*
X709261D01*
X708606Y-156005D01*
X707514Y-154839D01*
X705986Y-154256D01*
X704457Y-154547D01*
X703147Y-155422D01*
X702274Y-157464D01*
X701837Y-159214D01*
Y-160964D01*
X702274Y-162714D01*
X703366Y-164464D01*
X704676Y-165630D01*
X706204Y-165922D01*
X707732Y-165339D01*
X709261Y-163589D01*
G01X723049Y-165922D02*
Y-148422D01*
G01X975549Y-210922D02*
Y-193422D01*
X972929Y-196922D01*
G01Y-210922D02*
X978169D01*
G01X988246Y-208298D02*
X989555Y-209756D01*
X991084Y-210630D01*
X993049Y-210922D01*
X995014Y-210339D01*
X996542Y-209172D01*
X997634Y-207131D01*
X997852Y-204797D01*
X997416Y-202464D01*
X996324Y-201005D01*
X994795Y-199839D01*
X993267Y-199547D01*
X991739Y-199839D01*
X989774Y-201005D01*
X990429Y-193422D01*
X996324D01*
G01X1010549Y-210922D02*
Y-193422D01*
X1007929Y-196922D01*
G01Y-210922D02*
X1013169D01*
G01X1023901Y-196339D02*
X1025211Y-194589D01*
X1026739Y-193714D01*
X1028486Y-193422D01*
X1030669Y-194005D01*
X1032197Y-195464D01*
X1032634Y-197213D01*
X1032416Y-198964D01*
X1031542Y-200422D01*
X1027176Y-203339D01*
X1025211Y-205380D01*
X1023901Y-208298D01*
X1023464Y-210922D01*
X1032634D01*
G01X1041401Y-203631D02*
X1042929Y-201589D01*
X1044239Y-200422D01*
X1045986Y-199839D01*
X1047514Y-200422D01*
X1048606Y-201589D01*
X1049479Y-203339D01*
X1049697Y-205380D01*
X1049479Y-207131D01*
X1048606Y-208881D01*
X1047295Y-210339D01*
X1045767Y-210922D01*
X1044021Y-210339D01*
X1042492Y-208589D01*
X1041619Y-205964D01*
X1041401Y-203047D01*
X1041837Y-199256D01*
X1042492Y-197213D01*
X1043584Y-195172D01*
X1045112Y-193714D01*
X1046641Y-193422D01*
X1048169Y-194005D01*
X1049261Y-195464D01*
G01X962432Y-165922D02*
Y-148422D01*
X967672D01*
X969419Y-149297D01*
X970729Y-151339D01*
X971166Y-153672D01*
X970729Y-156005D01*
X969637Y-157755D01*
X967672Y-158631D01*
X962432D01*
G01X989102Y-149881D02*
X987792Y-149005D01*
X986264Y-148422D01*
X984517D01*
X982552Y-149297D01*
X981024Y-150755D01*
X979932Y-152506D01*
X979059Y-155422D01*
X978840Y-158047D01*
X979277Y-160672D01*
X979932Y-162422D01*
X981242Y-164172D01*
X982771Y-165339D01*
X984299Y-165922D01*
X985827D01*
X987356Y-165339D01*
X988666Y-164464D01*
X989758Y-163298D01*
G01X1003545Y-156589D02*
X1004419Y-155714D01*
X1005074Y-154256D01*
X1005511Y-152213D01*
X1005074Y-150464D01*
X1004201Y-149297D01*
X1002672Y-148422D01*
X996777D01*
Y-165922D01*
X1003982D01*
X1005511Y-164756D01*
X1006384Y-163005D01*
X1006821Y-160964D01*
X1006384Y-158922D01*
X1005074Y-157172D01*
X1003545Y-156589D01*
X996777D01*
G01X1012749Y-171755D02*
X1025849D01*
G01X1031777Y-165922D02*
Y-148422D01*
X1041821Y-165922D01*
Y-148422D01*
G01X1054299Y-165922D02*
X1052552Y-165630D01*
X1051024Y-164464D01*
X1049714Y-162714D01*
X1048840Y-160672D01*
X1048404Y-158339D01*
Y-156005D01*
X1048840Y-153672D01*
X1049714Y-151630D01*
X1051024Y-149881D01*
X1052552Y-148714D01*
X1054299Y-148422D01*
X1056045Y-148714D01*
X1057574Y-149881D01*
X1058884Y-151630D01*
X1059758Y-153672D01*
X1060194Y-156005D01*
Y-158339D01*
X1059758Y-160672D01*
X1058884Y-162714D01*
X1057574Y-164464D01*
X1056045Y-165630D01*
X1054299Y-165922D01*
G01X1128099Y-210922D02*
Y-193422D01*
X1125479Y-196922D01*
G01Y-210922D02*
X1130719D01*
G01X1147345Y-201589D02*
X1148219Y-200714D01*
X1148874Y-199256D01*
X1149311Y-197213D01*
X1148874Y-195464D01*
X1148001Y-194297D01*
X1146472Y-193422D01*
X1140577D01*
Y-210922D01*
X1147782D01*
X1149311Y-209756D01*
X1150184Y-208005D01*
X1150621Y-205964D01*
X1150184Y-203922D01*
X1148874Y-202172D01*
X1147345Y-201589D01*
X1140577D01*
G01X1105140Y-148422D02*
X1110599Y-165922D01*
X1116058Y-148422D01*
G01X1132466Y-165922D02*
X1123732D01*
Y-148422D01*
X1132466D01*
G01X1128972Y-156880D02*
X1123732D01*
G01X1141232Y-165922D02*
Y-148422D01*
X1146691D01*
X1148437Y-149297D01*
X1149529Y-150464D01*
X1149966Y-152797D01*
X1149529Y-155131D01*
X1148219Y-156589D01*
X1146691Y-157464D01*
X1141232D01*
G01X1146691D02*
X1149966Y-165922D01*
G01X1163099Y-166505D02*
X1162662Y-166214D01*
Y-165630D01*
X1163099Y-165339D01*
X1163536Y-165630D01*
Y-166214D01*
X1163099Y-166505D01*
G01X1238682Y-193422D02*
Y-210922D01*
X1247416D01*
G01X1263169D02*
Y-193422D01*
X1255090Y-205964D01*
X1266008D01*
G01X1279359Y-202172D02*
X1283726D01*
Y-207422D01*
X1282416Y-209172D01*
X1280887Y-210339D01*
X1278704Y-210922D01*
X1276521Y-210339D01*
X1274992Y-209172D01*
X1273682Y-207422D01*
X1272809Y-205380D01*
X1272372Y-203047D01*
Y-201005D01*
X1272809Y-199256D01*
X1273682Y-197213D01*
X1274992Y-195464D01*
X1276302Y-194297D01*
X1278049Y-193422D01*
X1279577D01*
X1281324Y-194005D01*
X1282634Y-195172D01*
G01X1290527Y-210922D02*
Y-193422D01*
X1300571Y-210922D01*
Y-193422D01*
G01X1308246Y-210922D02*
Y-193422D01*
X1312612D01*
X1314359Y-194297D01*
X1315669Y-195464D01*
X1316761Y-197213D01*
X1317634Y-199256D01*
X1317852Y-202172D01*
X1317634Y-205089D01*
X1316761Y-207131D01*
X1315669Y-208881D01*
X1314359Y-210047D01*
X1312612Y-210922D01*
X1308246D01*
G01X1238682Y-148422D02*
Y-165922D01*
X1247416D01*
G01X1264479D02*
Y-154256D01*
G01Y-156297D02*
X1263606Y-155131D01*
X1262295Y-154547D01*
X1260767Y-154256D01*
X1259239Y-154839D01*
X1257929Y-156005D01*
X1257055Y-157755D01*
X1256619Y-160089D01*
X1257055Y-162422D01*
X1257929Y-164172D01*
X1259239Y-165339D01*
X1260767Y-165922D01*
X1262295Y-165630D01*
X1263606Y-164756D01*
X1264479Y-163589D01*
G01X1273464Y-171172D02*
X1274774Y-171755D01*
X1276521Y-171172D01*
X1277612Y-170006D01*
X1278486Y-168547D01*
X1279795Y-163881D01*
X1282634Y-154256D01*
G01X1275647D02*
X1279795Y-163881D01*
G01X1292274Y-158047D02*
X1299261D01*
X1298606Y-156005D01*
X1297514Y-154839D01*
X1295986Y-154256D01*
X1294457Y-154547D01*
X1293147Y-155422D01*
X1292274Y-157464D01*
X1291837Y-159214D01*
Y-160964D01*
X1292274Y-162714D01*
X1293366Y-164464D01*
X1294676Y-165630D01*
X1296204Y-165922D01*
X1297732Y-165339D01*
X1299261Y-163589D01*
G01X1309992Y-165922D02*
Y-154256D01*
G01Y-156589D02*
X1311084Y-155422D01*
X1312176Y-154547D01*
X1313704Y-154256D01*
X1314795Y-154547D01*
X1316106Y-155422D01*
G01X1380796Y-165922D02*
Y-148422D01*
X1385162D01*
X1386909Y-149297D01*
X1388219Y-150464D01*
X1389311Y-152213D01*
X1390184Y-154256D01*
X1390402Y-157172D01*
X1390184Y-160089D01*
X1389311Y-162131D01*
X1388219Y-163881D01*
X1386909Y-165047D01*
X1385162Y-165922D01*
X1380796D01*
G01X1399824Y-158047D02*
X1406811D01*
X1406156Y-156005D01*
X1405064Y-154839D01*
X1403536Y-154256D01*
X1402007Y-154547D01*
X1400697Y-155422D01*
X1399824Y-157464D01*
X1399387Y-159214D01*
Y-160964D01*
X1399824Y-162714D01*
X1400916Y-164464D01*
X1402226Y-165630D01*
X1403754Y-165922D01*
X1405282Y-165339D01*
X1406811Y-163589D01*
G01X1417324Y-163881D02*
X1418416Y-165047D01*
X1419944Y-165922D01*
X1421254D01*
X1422564Y-165339D01*
X1423437Y-164464D01*
X1423874Y-163298D01*
X1423656Y-161547D01*
X1422782Y-160672D01*
X1418852Y-158922D01*
X1417979Y-156880D01*
X1418416Y-155422D01*
X1419289Y-154547D01*
X1420599Y-154256D01*
X1421909Y-154547D01*
X1423219Y-155422D01*
G01X1438099Y-154256D02*
Y-165922D01*
G01Y-149589D02*
X1437662Y-149297D01*
Y-148714D01*
X1438099Y-148422D01*
X1438536Y-148714D01*
Y-149297D01*
X1438099Y-149589D01*
G01X1452542Y-170297D02*
X1454071Y-171464D01*
X1455817Y-171755D01*
X1457345Y-171464D01*
X1458656Y-170006D01*
X1459529Y-167964D01*
Y-154256D01*
G01Y-156589D02*
X1458656Y-155422D01*
X1457345Y-154547D01*
X1455817Y-154256D01*
X1454071Y-154839D01*
X1452979Y-156005D01*
X1452105Y-158047D01*
X1451669Y-160089D01*
X1451887Y-161839D01*
X1452761Y-163881D01*
X1454071Y-165339D01*
X1455817Y-165922D01*
X1457127Y-165630D01*
X1458656Y-164464D01*
X1459529Y-163298D01*
G01X1469387Y-165922D02*
Y-154256D01*
G01Y-157172D02*
X1470261Y-155714D01*
X1471571Y-154547D01*
X1473317Y-154256D01*
X1474845Y-154547D01*
X1476156Y-155714D01*
X1476811Y-157755D01*
Y-165922D01*
G01X1487324Y-158047D02*
X1494311D01*
X1493656Y-156005D01*
X1492564Y-154839D01*
X1491036Y-154256D01*
X1489507Y-154547D01*
X1488197Y-155422D01*
X1487324Y-157464D01*
X1486887Y-159214D01*
Y-160964D01*
X1487324Y-162714D01*
X1488416Y-164464D01*
X1489726Y-165630D01*
X1491254Y-165922D01*
X1492782Y-165339D01*
X1494311Y-163589D01*
G01X1505042Y-165922D02*
Y-154256D01*
G01Y-156589D02*
X1506134Y-155422D01*
X1507226Y-154547D01*
X1508754Y-154256D01*
X1509845Y-154547D01*
X1511156Y-155422D01*
G01X1426729Y-193422D02*
X1431969D01*
G01X1429349D02*
Y-210922D01*
G01X1426729D02*
X1431969D01*
G01X1441390Y-193422D02*
X1446849Y-210922D01*
X1452308Y-193422D01*
G01X1464349Y-210922D02*
Y-203047D01*
X1459982Y-193422D01*
G01X1468716D02*
X1464349Y-203047D01*
G01X1551799Y-193422D02*
X1550052Y-194005D01*
X1548742Y-195464D01*
X1547869Y-197213D01*
X1547214Y-199547D01*
X1546996Y-202172D01*
X1547214Y-204797D01*
X1547869Y-207131D01*
X1548742Y-208881D01*
X1550052Y-210339D01*
X1551799Y-210922D01*
X1553545Y-210339D01*
X1554856Y-208881D01*
X1555729Y-207131D01*
X1556384Y-204797D01*
X1556602Y-202172D01*
X1556384Y-199547D01*
X1555729Y-197213D01*
X1554856Y-195464D01*
X1553545Y-194005D01*
X1551799Y-193422D01*
G01X1565151Y-196339D02*
X1566461Y-194589D01*
X1567989Y-193714D01*
X1569736Y-193422D01*
X1571919Y-194005D01*
X1573447Y-195464D01*
X1573884Y-197213D01*
X1573666Y-198964D01*
X1572792Y-200422D01*
X1568426Y-203339D01*
X1566461Y-205380D01*
X1565151Y-208298D01*
X1564714Y-210922D01*
X1573884D01*
G01X1582869Y-211505D02*
X1590729Y-193422D01*
G01X1604299Y-210922D02*
Y-193422D01*
X1601679Y-196922D01*
G01Y-210922D02*
X1606919D01*
G01X1621799Y-193422D02*
X1620052Y-194005D01*
X1618742Y-195464D01*
X1617869Y-197213D01*
X1617214Y-199547D01*
X1616996Y-202172D01*
X1617214Y-204797D01*
X1617869Y-207131D01*
X1618742Y-208881D01*
X1620052Y-210339D01*
X1621799Y-210922D01*
X1623545Y-210339D01*
X1624856Y-208881D01*
X1625729Y-207131D01*
X1626384Y-204797D01*
X1626602Y-202172D01*
X1626384Y-199547D01*
X1625729Y-197213D01*
X1624856Y-195464D01*
X1623545Y-194005D01*
X1621799Y-193422D01*
G01X1635369Y-211505D02*
X1643229Y-193422D01*
G01X1652651Y-196339D02*
X1653961Y-194589D01*
X1655489Y-193714D01*
X1657236Y-193422D01*
X1659419Y-194005D01*
X1660947Y-195464D01*
X1661384Y-197213D01*
X1661166Y-198964D01*
X1660292Y-200422D01*
X1655926Y-203339D01*
X1653961Y-205380D01*
X1652651Y-208298D01*
X1652214Y-210922D01*
X1661384D01*
G01X1674299Y-193422D02*
X1672552Y-194005D01*
X1671242Y-195464D01*
X1670369Y-197213D01*
X1669714Y-199547D01*
X1669496Y-202172D01*
X1669714Y-204797D01*
X1670369Y-207131D01*
X1671242Y-208881D01*
X1672552Y-210339D01*
X1674299Y-210922D01*
X1676045Y-210339D01*
X1677356Y-208881D01*
X1678229Y-207131D01*
X1678884Y-204797D01*
X1679102Y-202172D01*
X1678884Y-199547D01*
X1678229Y-197213D01*
X1677356Y-195464D01*
X1676045Y-194005D01*
X1674299Y-193422D01*
G01X1691799Y-210922D02*
Y-193422D01*
X1689179Y-196922D01*
G01Y-210922D02*
X1694419D01*
G01X1708862D02*
X1709299Y-207131D01*
X1709954Y-203922D01*
X1710827Y-201005D01*
X1711919Y-197797D01*
X1713666Y-193422D01*
X1704932D01*
G01X1599496Y-165922D02*
Y-148422D01*
X1603862D01*
X1605609Y-149297D01*
X1606919Y-150464D01*
X1608011Y-152213D01*
X1608884Y-154256D01*
X1609102Y-157172D01*
X1608884Y-160089D01*
X1608011Y-162131D01*
X1606919Y-163881D01*
X1605609Y-165047D01*
X1603862Y-165922D01*
X1599496D01*
G01X1625729D02*
Y-154256D01*
G01Y-156297D02*
X1624856Y-155131D01*
X1623545Y-154547D01*
X1622017Y-154256D01*
X1620489Y-154839D01*
X1619179Y-156005D01*
X1618305Y-157755D01*
X1617869Y-160089D01*
X1618305Y-162422D01*
X1619179Y-164172D01*
X1620489Y-165339D01*
X1622017Y-165922D01*
X1623545Y-165630D01*
X1624856Y-164756D01*
X1625729Y-163589D01*
G01X1639299Y-148422D02*
Y-165922D01*
G01X1636242Y-154256D02*
X1642356D01*
G01X1653524Y-158047D02*
X1660511D01*
X1659856Y-156005D01*
X1658764Y-154839D01*
X1657236Y-154256D01*
X1655707Y-154547D01*
X1654397Y-155422D01*
X1653524Y-157464D01*
X1653087Y-159214D01*
Y-160964D01*
X1653524Y-162714D01*
X1654616Y-164464D01*
X1655926Y-165630D01*
X1657454Y-165922D01*
X1658982Y-165339D01*
X1660511Y-163589D01*
G01X1969500Y100000D02*
Y95000D01*
G54D14*
X3937Y204370D03*
X-3937D03*
X-11811D03*
X35433D03*
X27559D03*
X19685D03*
X3937Y227992D03*
X-3937D03*
X-11811D03*
X35433D03*
X27559D03*
X19685D03*
X3937Y313504D03*
X-3937D03*
X-11811D03*
X3937Y337126D03*
X-3937D03*
X-11811D03*
X35433D03*
X27559D03*
X19685D03*
X35433Y313504D03*
X27559D03*
X19685D03*
G54D15*
X42724Y644684D03*
Y644656D03*
Y654684D03*
Y654656D03*
X67724Y644684D03*
Y644656D03*
Y654684D03*
Y654656D03*
X221656Y644656D03*
X196656D03*
X231446Y644756D03*
Y644784D03*
X221656Y644684D03*
X196656D03*
X221656Y654656D03*
X196656D03*
X231446Y654756D03*
Y654784D03*
X221656Y654684D03*
X196656D03*
X256446Y644756D03*
Y644784D03*
Y654756D03*
Y654784D03*
X409240Y644564D03*
X384240D03*
X418914Y644486D03*
Y644514D03*
X409240Y644536D03*
X384240D03*
X409240Y654564D03*
X384240D03*
X418914Y654486D03*
Y654514D03*
X409240Y654536D03*
X384240D03*
X443914Y644486D03*
Y644514D03*
Y654486D03*
Y654514D03*
X596707Y644293D03*
X571707D03*
X596708Y644266D03*
X571708D03*
X596707Y654293D03*
X571707D03*
X596708Y654266D03*
X571708D03*
X606462Y644245D03*
X631462D03*
X606462Y644217D03*
X631462D03*
X606462Y654245D03*
X631462D03*
X606462Y654217D03*
X631462D03*
X912351Y644245D03*
X887351D03*
X912351Y644273D03*
X887351D03*
X912351Y654245D03*
X887351D03*
X912351Y654273D03*
X887351D03*
X922116Y644206D03*
X947116D03*
X922116Y644234D03*
X947116D03*
X922116Y654206D03*
X947116D03*
X922116Y654234D03*
X947116D03*
X1200877Y644262D03*
Y644234D03*
Y654262D03*
Y654234D03*
X1225877Y644262D03*
X1235614Y644236D03*
X1260614D03*
X1235614Y644264D03*
X1260614D03*
X1225877Y644234D03*
Y654262D03*
X1235614Y654236D03*
X1260614D03*
X1235614Y654264D03*
X1260614D03*
X1225877Y654234D03*
X1514375Y644292D03*
Y644264D03*
Y654292D03*
Y654264D03*
X1539375Y644292D03*
Y644264D03*
Y654292D03*
Y654264D03*
G54D16*
X72074Y243282D03*
X65180Y243368D03*
X61800Y243400D03*
X68498Y243368D03*
X49560Y649770D03*
Y644670D03*
X54360D03*
X49560Y649570D03*
Y644670D03*
X54360D03*
X49560Y654670D03*
X54360D03*
X49560D03*
X54360D03*
X214820Y649570D03*
Y644670D03*
X210020D03*
X214820Y649770D03*
Y644670D03*
X210020D03*
X214820Y654670D03*
X210020D03*
X214820D03*
X210020D03*
X238282Y649670D03*
Y644770D03*
X243082D03*
X238282Y649870D03*
Y644770D03*
X243082D03*
X238282Y654770D03*
X243082D03*
X238282D03*
X243082D03*
X402404Y649650D03*
Y644550D03*
X397604D03*
X402404Y649450D03*
Y644550D03*
X397604D03*
X402404Y654550D03*
X397604D03*
X402404D03*
X397604D03*
X425750Y649400D03*
Y644500D03*
X430550D03*
X425750Y649600D03*
Y644500D03*
X430550D03*
X425750Y654500D03*
X430550D03*
X425750D03*
X430550D03*
X589871Y649379D03*
Y644279D03*
X585071D03*
X589872Y649180D03*
Y644280D03*
X585072D03*
X589871Y654279D03*
X585071D03*
X589872Y654280D03*
X585072D03*
X613298Y649331D03*
Y644231D03*
X618098D03*
X613298Y649131D03*
Y644231D03*
X618098D03*
X613298Y654231D03*
X618098D03*
X613298D03*
X618098D03*
X905515Y649159D03*
Y644259D03*
X900715D03*
X905515Y649359D03*
Y644259D03*
X900715D03*
X905515Y654259D03*
X900715D03*
X905515D03*
X900715D03*
X928952Y649120D03*
Y644220D03*
X933752D03*
X928952Y649320D03*
Y644220D03*
X933752D03*
X928952Y654220D03*
X933752D03*
X928952D03*
X933752D03*
X1219041Y649348D03*
Y644248D03*
X1214241D03*
X1219041Y649148D03*
Y644248D03*
X1214241D03*
X1219041Y654248D03*
X1214241D03*
X1219041D03*
X1214241D03*
X1242450Y649150D03*
Y644250D03*
X1247250D03*
X1242450Y649350D03*
Y644250D03*
X1247250D03*
X1242450Y654250D03*
X1247250D03*
X1242450D03*
X1247250D03*
X1527739Y644278D03*
D03*
Y654278D03*
D03*
X1532539Y649378D03*
Y644278D03*
Y649178D03*
Y644278D03*
Y654278D03*
D03*
G54D17*
G01X957774Y87394D02*
X956394D01*
X320784Y203219D03*
X330948Y201258D03*
X401377Y28022D03*
X411416D03*
X401377Y65822D03*
X411416D03*
X401377Y529022D03*
X411416D03*
X401377Y566822D03*
X411416D03*
X428149Y28022D03*
X434842Y28268D03*
X421456Y35957D03*
X434842Y65822D03*
X428149D03*
X458640Y200596D03*
X428149Y529022D03*
X434842D03*
X428149Y566822D03*
X434842D03*
X970392Y203219D03*
X980556Y201258D03*
X1050985Y28022D03*
X1061024D03*
X1077757D03*
X1084450Y28098D03*
X1050985Y65822D03*
X1071064Y35957D03*
X1061024Y65822D03*
X1084450D03*
X1077757D03*
X1050985Y529022D03*
Y566822D03*
X1061024Y529022D03*
X1084450D03*
X1077757D03*
X1067716Y547907D03*
X1071064Y574757D03*
X1061024Y566822D03*
X1084450D03*
X1077757D03*
X1108248Y200596D03*
X1111631Y198327D03*
X1451753Y276753D03*
X1454902Y279902D03*
X1445454Y270454D03*
X1448603Y273603D03*
X1454902Y305098D03*
X1448603Y311397D03*
X1458051Y301949D03*
X1464351Y295649D03*
Y289351D03*
X1458051Y283051D03*
X1489546Y270454D03*
X1486397Y273603D03*
X1483247Y276753D03*
X1470649Y295649D03*
Y289351D03*
X1480098Y305098D03*
X1476949Y301949D03*
X1486397Y311397D03*
X1489546Y314546D03*
X1483247Y308247D03*
X1476949Y283051D03*
X1606470Y93759D03*
X1638938Y109192D03*
X1638250Y125750D03*
X1651536Y121790D03*
X1638938Y118641D03*
X1645378Y128378D03*
X1638902Y112305D03*
X1648430Y150163D03*
X1638937Y131239D03*
Y143837D03*
Y137538D03*
X1638938Y153286D03*
X1616900Y153200D03*
X1629489Y150136D03*
X1616891Y146987D03*
X1616893Y140782D03*
X1635788Y137538D03*
Y143837D03*
Y131239D03*
X1616891Y134389D03*
X1629489Y137538D03*
Y143837D03*
Y131239D03*
X1620040Y106042D03*
X1623189Y118640D03*
X1629489D03*
X1610793Y109190D03*
X1607441Y118640D03*
X1616891Y124939D03*
X1596220Y109470D03*
X1613741Y115491D03*
X1602717Y102240D03*
X1620040Y162735D03*
X1627998Y172854D03*
X1601142Y172185D03*
X1674685Y134217D03*
X1693625Y133220D03*
X1680402Y128652D03*
X1678127Y117293D03*
X1673883Y124308D03*
X1654685Y146987D03*
X1654678Y137530D03*
X1657835Y134389D03*
X1671000Y103000D03*
X1709000Y127200D03*
X1691207Y139891D03*
X1667284Y137537D03*
X1657835Y124940D03*
Y150136D03*
X1667284Y121790D03*
Y128089D03*
Y150136D03*
X1664134Y140688D03*
X1668213Y172608D03*
X1729444Y123782D03*
X1726294Y101785D03*
X1742212Y117451D03*
X1717014Y108000D03*
Y139500D03*
X1739064Y108000D03*
X1742214Y101700D03*
X1745364Y114300D03*
X1755089Y150750D03*
X1752189Y136750D03*
X1752389Y132250D03*
X1754189Y124250D03*
X1757689Y123850D03*
X1752889Y146250D03*
X1745364Y145800D03*
X1731903Y133712D03*
X1720164Y97550D03*
Y111150D03*
X1723314D03*
Y117450D03*
X1720164Y120600D03*
Y133200D03*
Y126800D03*
X1751800Y141700D03*
X1742214Y98550D03*
Y126900D03*
X1745364Y120600D03*
X1742214Y111150D03*
X1739064Y114300D03*
G54D18*
X1643803Y585591D03*
X1640850Y582835D03*
X1631992D03*
X1623134D03*
X1640850Y567874D03*
X1631992D03*
X1623134D03*
X1646756Y595039D03*
X1623134Y612756D03*
X1640850Y597795D03*
X1631992D03*
X1623134D03*
X1640850Y612756D03*
X1631992D03*
X1691047Y585591D03*
X1688094Y582835D03*
X1679236D03*
X1670378D03*
X1688094Y567874D03*
X1679236D03*
X1670378D03*
X1694000Y595039D03*
X1688094Y612756D03*
X1679236D03*
X1670378D03*
X1688094Y597795D03*
X1679236D03*
X1670378D03*
G54D19*
X1702205Y536791D03*
X1687205D03*
X1702205D03*
X1687205D03*
X1717205D03*
D03*
M02*
